G04 ================== begin FILE IDENTIFICATION RECORD ==================*
G04 Layout Name:  15126-1b.brd*
G04 Film Name:    L11GND*
G04 File Format:  Gerber RS274X*
G04 File Origin:  Cadence Allegro 16.6-2015-S079*
G04 Origin Date:  Fri Feb 10 17:23:00 2017*
G04 *
G04 Layer:  VIA CLASS/L11GND*
G04 Layer:  PIN/L11GND*
G04 Layer:  ETCH/L11GND*
G04 Layer:  DRAWING FORMAT/LAYER_PCB_STORY*
G04 Layer:  DRAWING FORMAT/LAYER_L11GND*
G04 *
G04 Offset:    (0.00 0.00)*
G04 Mirror:    No*
G04 Mode:      Positive*
G04 Rotation:  0*
G04 FullContactRelief:  No*
G04 UndefLineWidth:     6.00*
G04 ================== end FILE IDENTIFICATION RECORD ====================*
%FSLAX35Y35*MOIN*%
%IR0*IPPOS*OFA0.00000B0.00000*MIA0B0*SFA1.00000B1.00000*%
%ADD11C,.02*%
%ADD22C,.04*%
%ADD21C,.031*%
%ADD10C,.022*%
%ADD18C,.06*%
%ADD25C,.052*%
%ADD12C,.034*%
%ADD14C,.044*%
%ADD30C,.045*%
%ADD19C,.018*%
%ADD31C,.055*%
%ADD20C,.064*%
%ADD17C,.028*%
%ADD13C,.046*%
%ADD28C,.047*%
%ADD24C,.056*%
%ADD16C,.039*%
%ADD15C,.057*%
%ADD23O,.032X.036*%
%ADD26O,.07X.046*%
%ADD27O,.098X.046*%
%ADD29O,.099X.048*%
%ADD32C,.01*%
%ADD33C,.025*%
%ADD34C,.006*%
%ADD72R,.05948X.06858*%
%ADD76O,.07202X.12102*%
%ADD47C,.03004*%
%ADD65C,.04004*%
%ADD57C,.03204*%
%ADD74C,.06104*%
%ADD53C,.07004*%
%ADD68C,.08004*%
%ADD61C,.06204*%
%ADD48C,.04404*%
%ADD62C,.07204*%
%ADD71C,.05504*%
%ADD63C,.06404*%
%ADD45C,.02804*%
%ADD70C,.06504*%
%ADD64C,.04704*%
%ADD52C,.07404*%
%ADD36C,.05604*%
%ADD73C,.05506*%
%ADD67C,.05704*%
%ADD66C,.09304*%
%ADD59C,.07504*%
%ADD51C,.08404*%
%ADD44C,.04804*%
%ADD54C,.07604*%
%ADD69C,.06804*%
%ADD56C,.05904*%
%ADD46C,.08604*%
%ADD60C,.07804*%
%ADD75C,.0669*%
%ADD41C,.06943*%
%ADD43C,.11211*%
%ADD55C,.12104*%
%ADD49C,.11204*%
%ADD50C,.15004*%
%ADD38O,.15402X.21902*%
%ADD35C,.11404*%
%ADD42C,.11209*%
%ADD37O,.15404X.21904*%
%ADD39C,.15504*%
%ADD40C,.15506*%
%ADD58C,.17804*%
G75*
%LPD*%
G75*
G36*
G01X1973300Y-60000D02*
X-19810D01*
Y-34500D01*
X1973300D01*
Y-60000D01*
G37*
G36*
G01X1683410Y265440D02*
X1870747D01*
G02X1871097Y264846I0J-400D01*
G03X1873549I1226J-679D01*
G02X1873899Y265440I350J194D01*
G01X1882971D01*
G02X1885265Y264305I0J-2886D01*
G01X1884953Y264056D01*
G03X1882513Y264079I-1230J-1027D01*
G02X1881896Y264095I-302J262D01*
G03X1879572Y261909I-1263J-986D01*
G02Y261309I-265J-300D01*
G03X1881843Y259059I1061J-1200D01*
G02X1882460Y259043I302J-262D01*
G03X1884784Y261229I1263J986D01*
G02Y261829I265J300D01*
G03X1885178Y263700I-1061J1200D01*
G01X1885537Y263875D01*
G02X1885814Y263053I-2566J-1322D01*
G01Y248336D01*
X1889250Y244900D01*
X1912227D01*
G02X1912588Y244329I-1J-400D01*
G03X1915486I1449J-683D01*
G02X1915847Y244900I362J171D01*
G01X1946598D01*
Y236102D01*
X1954390D01*
G03X1959543Y236615I2500J1024D01*
G02X1960225Y236815I393J-76D01*
G03X1959666Y239000I1665J1590D01*
G02X1958972Y238849I-386J104D01*
G03X1957693Y239706I-2081J-1723D01*
G01X1957552Y239750D01*
Y244900D01*
X1965118D01*
G02X1965425Y244244I0J-400D01*
G03X1965840Y240235I2158J-1803D01*
G01Y239440D01*
X1974348D01*
G02X1974383Y239296I-7128J-1809D01*
G01Y210008D01*
X1965840D01*
Y209213D01*
G03Y204801I1743J-2206D01*
G01Y204006D01*
X1974383D01*
Y166389D01*
G02X1973676Y166133I-400J0D01*
G03Y164339I-1078J-897D01*
G02X1974383Y164083I307J-256D01*
G01Y148981D01*
G02X1973838Y148609I-400J1D01*
G03X1973989Y146067I-510J-1306D01*
G02X1974578Y145715I189J-353D01*
G01Y144487D01*
G02X1973917Y144184I-400J0D01*
G03Y142056I-913J-1064D01*
G02X1974578Y141753I261J-303D01*
G01Y68400D01*
X1974577D01*
Y66929D01*
G02X1974572Y66780I-2136J-3D01*
G01Y58992D01*
X1972510Y56930D01*
X1905330D01*
X1903120Y54720D01*
Y52760D01*
G02X1902523Y52412I-400J0D01*
G03X1897805Y48998I-1578J-2786D01*
G02X1897250Y48554I-392J-79D01*
G03Y42706I-1305J-2924D01*
G02X1897805Y42262I163J-365D01*
G03Y41006I3140J-628D01*
G02X1897250Y40562I-392J-79D01*
G03Y34714I-1305J-2924D01*
G02X1897805Y34270I163J-365D01*
G03Y33014I3140J-628D01*
G02X1897250Y32570I-392J-79D01*
G03Y26722I-1305J-2924D01*
G02X1897805Y26278I163J-365D01*
G03X1897829Y24913I3140J-628D01*
G02X1897269Y24459I-389J-92D01*
G03Y18849I-1324J-2805D01*
G02X1897829Y18395I171J-362D01*
G03X1897805Y17030I3116J-737D01*
G02X1897250Y16586I-392J-79D01*
G03Y10738I-1305J-2924D01*
G02X1897805Y10294I163J-365D01*
G03Y9038I3140J-628D01*
G02X1897250Y8594I-392J-79D01*
G03Y2746I-1305J-2924D01*
G02X1897805Y2302I163J-365D01*
G03Y1046I3140J-628D01*
G02X1897250Y602I-392J-79D01*
G03Y-5246I-1305J-2924D01*
G02X1897805Y-5690I163J-365D01*
G03X1902505Y-9114I3140J-628D01*
G02X1903100Y-9463I195J-349D01*
G01Y-11420D01*
X1905310Y-13630D01*
X1918359D01*
X1918364Y-13636D01*
X1972636D01*
X1974560Y-15560D01*
Y-19890D01*
X1972650Y-21800D01*
X1918500D01*
X1918490Y-21790D01*
X1894759D01*
G02X1894387Y-21245I1J400D01*
G03X1891775I-1306J510D01*
G02X1891403Y-21790I-373J-145D01*
G01X1885332D01*
X1885292Y-21750D01*
X1397650D01*
X1396750Y-20850D01*
X1394700D01*
Y-20872D01*
X1393750Y-21822D01*
X658436D01*
G02X658075Y-21251I0J400D01*
G03X655539I-1268J599D01*
G02X655178Y-21822I-361J-171D01*
G01X456022D01*
X455101Y-20901D01*
X455102Y-20817D01*
G03X452433Y-20200I-1402J17D01*
G01X451667D01*
G03X449025Y-21072I-1267J-601D01*
G01X449029Y-21092D01*
X449051Y-21199D01*
X448428Y-21822D01*
X68857D01*
X68664Y-21629D01*
X68749Y-21494D01*
G03X67065Y-19435I-1185J749D01*
G02X66532Y-19149I-143J374D01*
G03X64216Y-18423I-1368J-307D01*
G02X63622Y-18362I-270J295D01*
G03X63434Y-20217I-1136J-822D01*
G02X64028Y-20278I270J-295D01*
G03X65663Y-20766I1136J822D01*
G02X66196Y-21052I143J-374D01*
G03X66354Y-21453I1368J307D01*
G01X66381Y-21499D01*
Y-21822D01*
X52231D01*
G02X51866Y-21259I0J400D01*
G03X49306I-1280J572D01*
G02X48941Y-21822I-365J-163D01*
G01X39766D01*
G02X39425Y-21214I0J400D01*
G03X37029I-1198J729D01*
G02X36688Y-21822I-341J-208D01*
G01X-14469D01*
G02X-21822Y-14469I0J7353D01*
G01Y617225D01*
G02X-15835Y624450I7354J0D01*
G01X358500D01*
Y624578D01*
X383723Y624560D01*
X385279D01*
G02X385654Y624023I0J-400D01*
G03X388286I1316J-484D01*
G02X388661Y624561I375J138D01*
G01X443500Y624578D01*
X444078Y624000D01*
X444091D01*
G02X444491Y623586I0J-400D01*
G03X447276Y623767I1401J-46D01*
G01X447273Y623783D01*
Y624000D01*
X447719D01*
Y623783D01*
X447716Y623767D01*
G03X450501Y623586I1384J-227D01*
G02X450901Y624000I400J14D01*
G01X451000D01*
X451450Y624450D01*
X451603D01*
G02X451968Y623888I-1J-400D01*
G03X454532I1282J-568D01*
G02X454897Y624450I366J162D01*
G01X455263D01*
G02X455628Y623888I-1J-400D01*
G03X458192I1282J-568D01*
G02X458557Y624450I366J162D01*
G01X726284D01*
G02X726665Y623928I0J-400D01*
G03X729335I1335J-428D01*
G02X729716Y624450I381J122D01*
G01X734450D01*
X734500Y624500D01*
X1044801D01*
G02X1045178Y623967I0J-400D01*
G03X1047822I1322J-467D01*
G02X1048199Y624500I377J133D01*
G01X1476578D01*
X1476656Y624578D01*
X1550000D01*
X1550632Y623946D01*
X1550627Y623935D01*
X1550818Y623744D01*
X1550806Y623648D01*
G03X1552367Y622087I1392J-169D01*
G01X1552463Y622099D01*
X1552556Y622006D01*
G03X1552841Y622233I-724J1201D01*
G03X1553393Y622746I-643J1246D01*
G02X1553723Y622603I23J-399D01*
G03X1555889Y622617I1077J897D01*
G02X1556511I311J-252D01*
G03X1558611Y622529I1089J883D01*
G02X1559189I289J-277D01*
G03X1560660Y622177I1010J972D01*
G03X1561716Y622563I87J1399D01*
G01X1562457D01*
G03X1564645Y622691I1043J937D01*
G02X1565316Y622664I327J-231D01*
G03X1567673Y622584I1204J718D01*
G02X1568333Y622580I329J-228D01*
G03X1570746Y623998I1162J784D01*
G02X1571103Y624578I357J180D01*
G01X1967224D01*
G02X1974385Y618897I0J-7354D01*
G01Y598709D01*
G02X1973766Y598374I-400J0D01*
G03Y596026I-766J-1174D01*
G02X1974385Y595691I219J-335D01*
G01Y577663D01*
G02X1973700Y577383I-400J0D01*
G03Y575417I-1000J-983D01*
G02X1974385Y575137I285J-280D01*
G01Y566557D01*
G02X1973722Y566256I-400J0D01*
G03Y564144I-922J-1056D01*
G02X1974385Y563843I263J-301D01*
G01Y551213D01*
G02X1973700Y550933I-400J0D01*
G03Y548967I-1000J-983D01*
G02X1974385Y548687I285J-280D01*
G01Y538157D01*
G02X1973722Y537856I-400J0D01*
G03Y535744I-922J-1056D01*
G02X1974385Y535443I263J-301D01*
G01Y441408D01*
X1967473Y434496D01*
X1922046D01*
G02X1921947Y434959I266J299D01*
G03X1919536Y436382I-1247J642D01*
G03X1919533Y436377I1201J-724D01*
G02X1918867I-333J222D01*
G03X1916533I-1167J-777D01*
G02X1915867I-333J222D01*
G03X1915864Y436382I-1204J-719D01*
G03X1913453Y434959I-1164J-781D01*
G02X1913291Y434450I-365J-164D01*
G01X1683500D01*
X1680050Y431000D01*
Y306416D01*
G02X1679528Y306035I-400J0D01*
G03X1678129Y303689I-428J-1335D01*
G02Y303111I-277J-289D01*
G03Y301089I971J-1011D01*
G02Y300511I-277J-289D01*
G03X1678090Y298527I971J-1011D01*
G02Y297973I-288J-277D01*
G03Y296027I1010J-973D01*
G02Y295473I-288J-277D01*
G03Y293527I1010J-973D01*
G02Y292973I-288J-277D01*
G03Y291027I1010J-973D01*
G02Y290473I-288J-277D01*
G03X1678271Y288369I1010J-973D01*
G02Y287724I-236J-323D01*
G03X1678090Y285620I829J-1131D01*
G02Y285066I-288J-277D01*
G03Y283120I1010J-973D01*
G02Y282566I-288J-277D01*
G03X1678158Y280555I1010J-972D01*
G02Y279962I-269J-297D01*
G03X1678099Y277942I942J-1038D01*
G02Y277382I-285J-280D01*
G03X1678090Y275427I1001J-982D01*
G02Y274873I-288J-277D01*
G03X1678129Y272889I1010J-973D01*
G02Y272311I-277J-289D01*
G03X1679528Y269965I971J-1011D01*
G02X1680050Y269584I122J-381D01*
G01Y268800D01*
X1683410Y265440D01*
G37*
G36*
G01X-20621Y661811D02*
G02X-19685Y662747I936J0D01*
G01X1972600D01*
Y637600D01*
X-20412D01*
G02X-20621Y638189I726J589D01*
G01Y661811D01*
G37*
%LPC*%
G75*
G36*
G01X1606022Y557644D02*
Y561645D01*
G02X1607233Y563125I1511J-1D01*
G03X1607452Y563785I-79J393D01*
G02X1616289Y570393I3831J4090D01*
G02X1611415Y562272I-5004J-2520D01*
G02X1609474Y562570I-133J5602D01*
G03X1608983Y562072I-108J-385D01*
G02X1609044Y561654I-1450J-425D01*
G01Y557559D01*
X1609035Y557475D01*
G02X1606022Y557644I-1502J169D01*
G37*
G36*
G01X1514847Y92931D02*
X1514848D01*
Y92928D01*
X1514846D01*
Y92924D01*
X1514847D01*
G02X1514846Y92853I-1512J-14D01*
G01Y92836D01*
X1514844Y92817D01*
G02X1511844Y92664I-1509J102D01*
G01X1511820Y92780D01*
Y92784D01*
X1511819D01*
X1511496Y96414D01*
X1511497D01*
Y96415D01*
X1511501Y96542D01*
G02X1512516Y97974I1512J4D01*
G02X1513224Y98044I499J-1427D01*
G02X1514519Y96682I-211J-1498D01*
G01X1514529Y96683D01*
X1514541Y96554D01*
X1514534D01*
X1514535Y96548D01*
X1514541D01*
X1514852Y93055D01*
X1514849Y93053D01*
X1514848D01*
X1514843Y93048D01*
X1514844Y93026D01*
G02X1514847Y92931I-1509J-95D01*
G37*
G36*
G01X1756912Y37661D02*
Y37615D01*
X1756908Y37577D01*
G02X1754912Y36269I-1507J123D01*
G01X1754909Y36259D01*
X1751506Y37425D01*
Y37430D01*
X1751440Y37460D01*
G02X1751250Y37551I557J1406D01*
G03X1751065Y37198I-78J-184D01*
G02X1751762Y35935I-815J-1273D01*
G01Y35840D01*
X1751752Y35756D01*
G02X1750250Y34414I-1502J170D01*
G01X1746550D01*
G02X1745673Y37156I0J1511D01*
G03X1745687Y37796I-233J325D01*
G02X1747684Y38073I865J1104D01*
G03X1748006Y37436I323J-237D01*
G01X1750251D01*
G02X1750363Y37432I2J-1511D01*
G03X1750741Y38027I29J399D01*
G02X1752488Y40296I1260J837D01*
G01X1752491Y40306D01*
X1755896Y39140D01*
Y39138D01*
X1756013Y39082D01*
G02X1756350Y38877I-611J-1383D01*
G01Y38876D01*
G02X1756360Y38868I-939J-1184D01*
G01X1756362D01*
G02X1756912Y37710I-963J-1167D01*
G01Y37702D01*
G02Y37661I-1512J-20D01*
G37*
G36*
G01X58267Y271262D02*
Y271285D01*
X74529D01*
X79069Y266745D01*
Y222900D01*
X75369Y219200D01*
X51271D01*
X47694Y222777D01*
Y260689D01*
X58267Y271262D01*
G37*
G36*
G01X1928253Y535242D02*
X1930653D01*
G02Y529840I0J-2701D01*
G01X1928253D01*
G02Y535242I0J2701D01*
G37*
G36*
G01X1926853Y513904D02*
X1932053D01*
G02Y508500I0J-2702D01*
G01X1926853D01*
G02Y513904I0J2702D01*
G37*
G36*
G01X1951554Y127860D02*
X1958054D01*
G02Y112456I0J-7702D01*
G01X1951554D01*
G02Y127860I0J7702D01*
G37*
G36*
G01X1884727Y535242D02*
X1889927D01*
G02Y529840I0J-2701D01*
G01X1884727D01*
G02Y535242I0J2701D01*
G37*
G36*
G01X1886127Y513904D02*
X1888527D01*
G02Y508500I0J-2702D01*
G01X1886127D01*
G02Y513904I0J2702D01*
G37*
G36*
G01X1833443Y127860D02*
X1839943D01*
G02Y112456I0J-7702D01*
G01X1833443D01*
G02Y127860I0J7702D01*
G37*
G36*
G01X1857035Y602728D02*
X1854331D01*
G02Y618532I1J7902D01*
G01X1857044D01*
G03X1860510Y619640I-2J5982D01*
G02X1860511Y601620I7622J-9010D01*
G03X1857035Y602728I-3476J-4898D01*
G37*
G36*
G01Y-15776D02*
X1854331D01*
G02Y28I1J7902D01*
G01X1857044D01*
G03X1860510Y1136I-2J5982D01*
G02X1860511Y-16884I7622J-9010D01*
G03X1857035Y-15776I-3476J-4898D01*
G37*
G36*
G01X1684261Y616623D02*
X1687214Y611111D01*
G02X1683070Y608889I-2072J-1111D01*
G01X1680117Y614401D01*
G02X1684261Y616623I2072J1111D01*
G37*
G36*
G01Y601662D02*
X1687214Y596150D01*
G02X1683070Y593928I-2072J-1111D01*
G01X1680117Y599440D01*
G02X1684261Y601662I2072J1111D01*
G37*
G36*
G01X1675404Y616622D02*
X1678356Y611110D01*
G02X1674210Y608890I-2073J-1110D01*
G01X1671258Y614402D01*
G02X1675404Y616622I2073J1110D01*
G37*
G36*
G01Y601661D02*
X1678356Y596149D01*
G02X1674210Y593929I-2073J-1110D01*
G01X1671258Y599441D01*
G02X1675404Y601661I2073J1110D01*
G37*
G36*
G01X1408216Y602728D02*
X1405512D01*
G02Y618532I1J7902D01*
G01X1408225D01*
G03X1411691Y619640I-2J5982D01*
G02X1411692Y601620I7622J-9010D01*
G03X1408216Y602728I-3476J-4898D01*
G37*
G36*
G01Y-15776D02*
X1405512D01*
G02Y28I1J7902D01*
G01X1408225D01*
G03X1411691Y1136I-2J5982D01*
G02X1411692Y-16884I7622J-9010D01*
G03X1408216Y-15776I-3476J-4898D01*
G37*
G36*
G01X679869Y602728D02*
X677165D01*
G02Y618532I1J7902D01*
G01X679878D01*
G03X683344Y619640I-2J5982D01*
G02X683345Y601620I7622J-9010D01*
G03X679869Y602728I-3476J-4898D01*
G37*
G36*
G01Y-15776D02*
X677165D01*
G02Y28I1J7902D01*
G01X679878D01*
G03X683344Y1136I-2J5982D01*
G02X683345Y-16884I7622J-9010D01*
G03X679869Y-15776I-3476J-4898D01*
G37*
G36*
G01X2704Y602728D02*
X0D01*
G02Y618532I1J7902D01*
G01X2713D01*
G03X6179Y619640I-2J5982D01*
G02X6180Y601620I7622J-9010D01*
G03X2704Y602728I-3476J-4898D01*
G37*
G36*
G01X1313465Y618530D02*
G03X1312887I-289J-277D01*
G02Y620472I-1011J971D01*
G03X1313465I289J277D01*
G02Y618530I1011J-971D01*
G37*
G36*
G01X1591926Y619723D02*
G03X1592512Y619711I299J266D01*
G02X1592474Y617801I1007J-975D01*
G03X1591888Y617813I-299J-266D01*
G02X1591926Y619723I-1007J975D01*
G37*
G36*
G01X1602539Y617279D02*
G03X1601961I-289J-277D01*
G02Y619221I-1011J971D01*
G03X1602539I289J277D01*
G02Y617279I1011J-971D01*
G37*
G36*
G01X1962583Y618411D02*
G03Y617789I252J-311D01*
G02X1960817I-883J-1089D01*
G03Y618411I-252J311D01*
G02X1962583I883J1089D01*
G37*
G36*
G01X713345Y616607D02*
G03X712901Y616223I-44J-398D01*
G02X711655Y617667I-1401J51D01*
G03X712099Y618051I44J398D01*
G02X713345Y616607I1401J-51D01*
G37*
G36*
G01X1931383Y617811D02*
G03Y617189I252J-311D01*
G02X1929617I-883J-1089D01*
G03Y617811I-252J311D01*
G02X1931383I883J1089D01*
G37*
G36*
G01X1372904Y615115D02*
G03X1372297Y615025I-266J-298D01*
G02X1372034Y616802I-1197J731D01*
G03X1372641Y616892I266J298D01*
G02X1372904Y615115I1197J-731D01*
G37*
G36*
G01X629517Y611700D02*
G03X629012Y611466I-132J-378D01*
G02X628165Y613297I-1307J507D01*
G03X628670Y613531I132J378D01*
G02X629517Y611700I1307J-507D01*
G37*
G36*
G01X656071Y613089D02*
G03Y612511I277J-289D01*
G02X654129I-971J-1011D01*
G03Y613089I-277J289D01*
G02X656071I971J1011D01*
G37*
G36*
G01X1533154Y612419D02*
G03X1533178Y611832I283J-282D01*
G02X1531276Y611753I-908J-1068D01*
G03X1531252Y612340I-283J282D01*
G02X1531212Y612375I903J1072D01*
G03X1530665Y612370I-271J-294D01*
G02X1528864Y612257I-968J1014D01*
G03X1528294Y612159I-238J-322D01*
G02X1528149Y614024I-1244J841D01*
G03X1528470Y614063I146J136D01*
G02X1528563Y614209I1227J-679D01*
G03X1528485Y614509I-161J118D01*
G02X1530296Y615109I582J1275D01*
G03X1530435Y614576I350J-193D01*
G02X1530645Y614417I-738J-1192D01*
G03X1531192Y614422I271J294D01*
G02X1533154Y612419I969J-1014D01*
G37*
G36*
G01X1383607Y611122D02*
G03X1383603Y610567I286J-280D01*
G02X1381584Y610582I-1017J-965D01*
G03X1381588Y611137I-286J280D01*
G02X1383607Y611122I1017J965D01*
G37*
G36*
G01X1652380Y614210D02*
Y609115D01*
X1652371Y609031D01*
G02X1649358Y609200I-1502J169D01*
G01Y614201D01*
G02X1652380Y614210I1511J-1D01*
G37*
G36*
G01X1637045Y616571D02*
X1637046Y616569D01*
X1639942Y611164D01*
X1639943Y611162D01*
G02X1635798Y608941I-2045J-1162D01*
G01X1635797Y608943D01*
X1632901Y614348D01*
X1632900Y614350D01*
G02X1637045Y616571I2045J1162D01*
G37*
G36*
G01X1628179Y616586D02*
X1628180Y616585D01*
X1631092Y611148D01*
X1631093Y611146D01*
G02X1626947Y608926I-2054J-1146D01*
G01X1626946Y608927D01*
X1624034Y614364D01*
X1624033Y614366D01*
G02X1628179Y616586I2054J1146D01*
G37*
G36*
G01X1505671Y610089D02*
G03Y609511I277J-289D01*
G02X1503729I-971J-1011D01*
G03Y610089I-277J289D01*
G02X1505671I971J1011D01*
G37*
G36*
G01X1307614Y609031D02*
G03X1307604Y608489I289J-276D01*
G02X1305542Y608527I-1049J-931D01*
G03X1305552Y609069I-289J276D01*
G02X1307614Y609031I1049J931D01*
G37*
G36*
G01X1225862Y608964D02*
G03X1225868Y608407I290J-275D01*
G02X1223712Y608385I-1067J-1057D01*
G03X1223706Y608942I-290J275D01*
G02X1225862Y608964I1067J1057D01*
G37*
G36*
G01X1189051D02*
G03X1189057Y608407I290J-275D01*
G02X1186901Y608385I-1067J-1057D01*
G03X1186895Y608942I-290J275D01*
G02X1189051Y608964I1067J1057D01*
G37*
G36*
G01X1152240D02*
G03X1152246Y608407I290J-275D01*
G02X1150090Y608385I-1067J-1057D01*
G03X1150084Y608942I-290J275D01*
G02X1152240Y608964I1067J1057D01*
G37*
G36*
G01X1115428D02*
G03X1115434Y608407I290J-275D01*
G02X1113278Y608385I-1067J-1057D01*
G03X1113272Y608942I-290J275D01*
G02X1115428Y608964I1067J1057D01*
G37*
G36*
G01X934720D02*
G03X934726Y608407I290J-275D01*
G02X932570Y608385I-1067J-1057D01*
G03X932564Y608942I-290J275D01*
G02X934720Y608964I1067J1057D01*
G37*
G36*
G01X897909D02*
G03X897915Y608407I290J-275D01*
G02X895759Y608385I-1067J-1057D01*
G03X895753Y608942I-290J275D01*
G02X897909Y608964I1067J1057D01*
G37*
G36*
G01X861098D02*
G03X861104Y608407I290J-275D01*
G02X858948Y608385I-1067J-1057D01*
G03X858942Y608942I-290J275D01*
G02X861098Y608964I1067J1057D01*
G37*
G36*
G01X824287D02*
G03X824293Y608407I290J-275D01*
G02X822137Y608385I-1067J-1057D01*
G03X822131Y608942I-290J275D01*
G02X824287Y608964I1067J1057D01*
G37*
G36*
G01X787476D02*
G03X787482Y608407I290J-275D01*
G02X785326Y608385I-1067J-1057D01*
G03X785320Y608942I-290J275D01*
G02X787476Y608964I1067J1057D01*
G37*
G36*
G01X576254D02*
G03X576260Y608407I290J-275D01*
G02X574104Y608385I-1067J-1057D01*
G03X574098Y608942I-290J275D01*
G02X576254Y608964I1067J1057D01*
G37*
G36*
G01X539443D02*
G03X539449Y608407I290J-275D01*
G02X537293Y608385I-1067J-1057D01*
G03X537287Y608942I-290J275D01*
G02X539443Y608964I1067J1057D01*
G37*
G36*
G01X502632D02*
G03X502638Y608407I290J-275D01*
G02X500482Y608385I-1067J-1057D01*
G03X500476Y608942I-290J275D01*
G02X502632Y608964I1067J1057D01*
G37*
G36*
G01X465820D02*
G03X465826Y608407I290J-275D01*
G02X463670Y608385I-1067J-1057D01*
G03X463664Y608942I-290J275D01*
G02X465820Y608964I1067J1057D01*
G37*
G36*
G01X285112D02*
G03X285118Y608407I290J-275D01*
G02X282962Y608385I-1067J-1057D01*
G03X282956Y608942I-290J275D01*
G02X285112Y608964I1067J1057D01*
G37*
G36*
G01X248301D02*
G03X248307Y608407I290J-275D01*
G02X246151Y608385I-1067J-1057D01*
G03X246145Y608942I-290J275D01*
G02X248301Y608964I1067J1057D01*
G37*
G36*
G01X211490D02*
G03X211496Y608407I290J-275D01*
G02X209340Y608385I-1067J-1057D01*
G03X209334Y608942I-290J275D01*
G02X211490Y608964I1067J1057D01*
G37*
G36*
G01X174679D02*
G03X174685Y608407I290J-275D01*
G02X172529Y608385I-1067J-1057D01*
G03X172523Y608942I-290J275D01*
G02X174679Y608964I1067J1057D01*
G37*
G36*
G01X135718Y608385D02*
G03X135712Y608942I-290J275D01*
G02X137868Y608964I1067J1057D01*
G03X137874Y608407I290J-275D01*
G02X135718Y608385I-1067J-1057D01*
G37*
G36*
G01X1230967Y608719D02*
G03Y608170I291J-274D01*
G02X1228781I-1093J-1030D01*
G03Y608719I-291J274D01*
G02X1230967I1093J1030D01*
G37*
G36*
G01X1194156D02*
G03Y608170I291J-274D01*
G02X1191970I-1093J-1030D01*
G03Y608719I-291J274D01*
G02X1194156I1093J1030D01*
G37*
G36*
G01X1157345D02*
G03Y608170I291J-274D01*
G02X1155159I-1093J-1030D01*
G03Y608719I-291J274D01*
G02X1157345I1093J1030D01*
G37*
G36*
G01X1120533D02*
G03Y608170I291J-274D01*
G02X1118347I-1093J-1030D01*
G03Y608719I-291J274D01*
G02X1120533I1093J1030D01*
G37*
G36*
G01X939825D02*
G03Y608170I291J-274D01*
G02X937639I-1093J-1030D01*
G03Y608719I-291J274D01*
G02X939825I1093J1030D01*
G37*
G36*
G01X903014D02*
G03Y608170I291J-274D01*
G02X900828I-1093J-1030D01*
G03Y608719I-291J274D01*
G02X903014I1093J1030D01*
G37*
G36*
G01X866203D02*
G03Y608170I291J-274D01*
G02X864017I-1093J-1030D01*
G03Y608719I-291J274D01*
G02X866203I1093J1030D01*
G37*
G36*
G01X829392D02*
G03Y608170I291J-274D01*
G02X827206I-1093J-1030D01*
G03Y608719I-291J274D01*
G02X829392I1093J1030D01*
G37*
G36*
G01X792581D02*
G03Y608170I291J-274D01*
G02X790395I-1093J-1030D01*
G03Y608719I-291J274D01*
G02X792581I1093J1030D01*
G37*
G36*
G01X581359D02*
G03Y608170I291J-274D01*
G02X579173I-1093J-1030D01*
G03Y608719I-291J274D01*
G02X581359I1093J1030D01*
G37*
G36*
G01X544548D02*
G03Y608170I291J-274D01*
G02X542362I-1093J-1030D01*
G03Y608719I-291J274D01*
G02X544548I1093J1030D01*
G37*
G36*
G01X507737D02*
G03Y608170I291J-274D01*
G02X505551I-1093J-1030D01*
G03Y608719I-291J274D01*
G02X507737I1093J1030D01*
G37*
G36*
G01X470925D02*
G03X470926Y608171I292J-273D01*
G02X468740Y608170I-1093J-1031D01*
G03X468739Y608718I-292J273D01*
G02X470925Y608719I1093J1031D01*
G37*
G36*
G01X290217D02*
G03Y608170I291J-274D01*
G02X288031I-1093J-1030D01*
G03Y608719I-291J274D01*
G02X290217I1093J1030D01*
G37*
G36*
G01X253406D02*
G03Y608170I291J-274D01*
G02X251220I-1093J-1030D01*
G03Y608719I-291J274D01*
G02X253406I1093J1030D01*
G37*
G36*
G01X216595D02*
G03Y608170I291J-274D01*
G02X214409I-1093J-1030D01*
G03Y608719I-291J274D01*
G02X216595I1093J1030D01*
G37*
G36*
G01X179784D02*
G03Y608170I291J-274D01*
G02X177598I-1093J-1030D01*
G03Y608719I-291J274D01*
G02X179784I1093J1030D01*
G37*
G36*
G01X142973D02*
G03Y608170I291J-274D01*
G02X140787I-1093J-1030D01*
G03Y608719I-291J274D01*
G02X142973I1093J1030D01*
G37*
G36*
G01X1545090Y606559D02*
G03X1545469Y606114I397J-46D01*
G02X1544014Y604873I-62J-1401D01*
G03X1543635Y605318I-397J46D01*
G02X1542337Y606379I62J1401D01*
G03X1541774Y606642I-388J-97D01*
G02X1542522Y608243I-612J1261D01*
G03X1543085Y607980I388J97D01*
G02X1545090Y606559I612J-1261D01*
G37*
G36*
G01X1605380Y608460D02*
Y604365D01*
X1605371Y604281D01*
G02X1602358Y604450I-1502J169D01*
G01Y608451D01*
G02X1605380Y608460I1511J-1D01*
G37*
G36*
G01X1659880Y606260D02*
Y602165D01*
X1659871Y602081D01*
G02X1656858Y602250I-1502J169D01*
G01Y606251D01*
G02X1659880Y606260I1511J-1D01*
G37*
G36*
G01X1572237Y600367D02*
G03X1571718Y600360I-255J-308D01*
G02X1571683Y602796I-1058J1203D01*
G03X1572202Y602803I255J308D01*
G02X1572237Y600367I1058J-1203D01*
G37*
G36*
G01X1804772Y601902D02*
G03X1804178Y601662I-207J-342D01*
G02X1803850Y604145I-3193J841D01*
G03X1804486Y604068I347J199D01*
G02X1804772Y601902I1014J-968D01*
G37*
G36*
G01X1614860Y603260D02*
Y599165D01*
X1614851Y599081D01*
G02X1611838Y599250I-1502J169D01*
G01Y603251D01*
G02X1614860Y603260I1511J-1D01*
G37*
G36*
G01X1325210Y599127D02*
G03Y598573I288J-277D01*
G02X1323190I-1010J-973D01*
G03Y599127I-288J277D01*
G02X1323229Y601111I1010J973D01*
G03Y601689I-277J289D01*
G02X1323154Y603634I971J1011D01*
G03Y604166I-298J266D01*
G02Y606034I1046J934D01*
G03Y606566I-298J266D01*
G02X1323229Y608511I1046J934D01*
G03Y609089I-277J289D01*
G02X1325171I971J1011D01*
G03Y608511I277J-289D01*
G02X1325246Y606566I-971J-1011D01*
G03Y606034I298J-266D01*
G02Y604166I-1046J-934D01*
G03Y603634I298J-266D01*
G02X1325171Y601689I-1046J-934D01*
G03Y601111I277J-289D01*
G02X1325210Y599127I-971J-1011D01*
G37*
G36*
G01X713010Y598527D02*
G03Y597973I288J-277D01*
G02X710990I-1010J-973D01*
G03Y598527I-288J277D01*
G02X713010I1010J973D01*
G37*
G36*
G01X1589293Y595924D02*
G03X1588711Y595918I-288J-277D01*
G02X1586692Y595871I-1032J949D01*
G03X1586137Y595879I-282J-284D01*
G02X1586166Y597898I-958J1023D01*
G03X1586721Y597890I282J284D01*
G02X1588690Y597839I959J-1023D01*
G03X1589272Y597845I288J277D01*
G02X1589293Y595924I1032J-949D01*
G37*
G36*
G01X709771Y598289D02*
G03Y597711I277J-289D01*
G02X707829I-971J-1011D01*
G03Y598289I-277J289D01*
G02X709771I971J1011D01*
G37*
G36*
G01X1637045Y601610D02*
X1637046Y601608D01*
X1639942Y596203D01*
X1639943Y596201D01*
G02X1635798Y593980I-2045J-1162D01*
G01X1635797Y593982D01*
X1632901Y599387D01*
X1632900Y599389D01*
G02X1637045Y601610I2045J1162D01*
G37*
G36*
G01X1628179Y601625D02*
X1628180Y601624D01*
X1631092Y596187D01*
X1631093Y596185D01*
G02X1626947Y593965I-2054J-1146D01*
G01X1626946Y593966D01*
X1624034Y599403D01*
X1624033Y599405D01*
G02X1628179Y601625I2054J1146D01*
G37*
G36*
G01X1654010Y597960D02*
Y593865D01*
X1654001Y593781D01*
G02X1650988Y593950I-1502J169D01*
G01Y597951D01*
G02X1654010Y597960I1511J-1D01*
G37*
G36*
G01X754907Y592660D02*
G03X754330Y592649I-283J-282D01*
G02X754293Y594590I-1030J951D01*
G03X754870Y594601I283J282D01*
G02X754907Y592660I1030J-951D01*
G37*
G36*
G01X1801343Y595110D02*
G03X1801349Y594538I283J-283D01*
G02X1799387Y594518I-971J-1011D01*
G03X1799381Y595090I-283J283D01*
G02X1801343Y595110I971J1011D01*
G37*
G36*
G01X1710951Y594470D02*
G03X1710940Y593893I271J-294D01*
G02X1708999Y593930I-990J-993D01*
G03X1709010Y594507I-271J294D01*
G02X1710951Y594470I990J993D01*
G37*
G36*
G01X1605430Y596760D02*
Y592665D01*
X1605421Y592581D01*
G02X1602408Y592750I-1502J169D01*
G01Y596751D01*
G02X1605430Y596760I1511J-1D01*
G37*
G36*
G01X1718962Y593631D02*
G03X1718956Y593035I264J-301D01*
G02X1717083Y593055I-948J-1033D01*
G03X1717089Y593651I-264J301D01*
G02X1717027Y595657I948J1033D01*
G03Y596211I-288J277D01*
G02X1719047I1010J973D01*
G03Y595657I288J-277D01*
G02X1718962Y593631I-1010J-972D01*
G37*
G36*
G01X1554589Y590129D02*
G03X1554011I-289J-277D01*
G02Y592071I-1011J971D01*
G03X1554589I289J277D01*
G02Y590129I1011J-971D01*
G37*
G36*
G01X648104Y592592D02*
G03X648419Y592084I383J-114D01*
G02X646836Y591102I-239J-1382D01*
G03X646521Y591610I-383J114D01*
G02X645381Y592738I239J1382D01*
G03X644880Y593050I-393J-73D01*
G02X645879Y594654I-380J1350D01*
G03X646380Y594342I393J73D01*
G02X648104Y592592I380J-1350D01*
G37*
G36*
G01X2515Y591438D02*
G03X2495Y590851I262J-303D01*
G02X516Y590968I-1056J-1068D01*
G03X566Y591554I-245J316D01*
G02X506Y591623I1027J954D01*
G03X194I-156J-125D01*
G02X73Y593510I-1094J877D01*
G03X627I277J288D01*
G02X2515Y591438I973J-1010D01*
G37*
G36*
G01X1763216Y590944D02*
G03Y590666I144J-139D01*
G02X1760908I-1154J-1111D01*
G03Y590944I-144J139D01*
G02X1763216I1154J1111D01*
G37*
G36*
G01X1230970Y590087D02*
G03Y589541I292J-273D01*
G02X1228778I-1096J-1027D01*
G03Y590087I-292J273D01*
G02X1230970I1096J1027D01*
G37*
G36*
G01X1194159D02*
G03Y589541I292J-273D01*
G02X1191967I-1096J-1027D01*
G03Y590087I-292J273D01*
G02X1194159I1096J1027D01*
G37*
G36*
G01X1157348D02*
G03Y589541I292J-273D01*
G02X1155156I-1096J-1027D01*
G03Y590087I-292J273D01*
G02X1157348I1096J1027D01*
G37*
G36*
G01X1120536D02*
G03Y589541I292J-273D01*
G02X1118344I-1096J-1027D01*
G03Y590087I-292J273D01*
G02X1120536I1096J1027D01*
G37*
G36*
G01X939828D02*
G03Y589541I292J-273D01*
G02X937636I-1096J-1027D01*
G03Y590087I-292J273D01*
G02X939828I1096J1027D01*
G37*
G36*
G01X903017D02*
G03Y589541I292J-273D01*
G02X900825I-1096J-1027D01*
G03Y590087I-292J273D01*
G02X903017I1096J1027D01*
G37*
G36*
G01X866206D02*
G03Y589541I292J-273D01*
G02X864014I-1096J-1027D01*
G03Y590087I-292J273D01*
G02X866206I1096J1027D01*
G37*
G36*
G01X829395D02*
G03Y589541I292J-273D01*
G02X827203I-1096J-1027D01*
G03Y590087I-292J273D01*
G02X829395I1096J1027D01*
G37*
G36*
G01X792584D02*
G03Y589541I292J-273D01*
G02X790392I-1096J-1027D01*
G03Y590087I-292J273D01*
G02X792584I1096J1027D01*
G37*
G36*
G01X581362D02*
G03Y589541I292J-273D01*
G02X579170I-1096J-1027D01*
G03Y590087I-292J273D01*
G02X581362I1096J1027D01*
G37*
G36*
G01X544551D02*
G03Y589541I292J-273D01*
G02X542359I-1096J-1027D01*
G03Y590087I-292J273D01*
G02X544551I1096J1027D01*
G37*
G36*
G01X507740D02*
G03Y589541I292J-273D01*
G02X505548I-1096J-1027D01*
G03Y590087I-292J273D01*
G02X507740I1096J1027D01*
G37*
G36*
G01X470928D02*
G03Y589541I292J-273D01*
G02X468736I-1096J-1027D01*
G03Y590087I-292J273D01*
G02X470928I1096J1027D01*
G37*
G36*
G01X290220D02*
G03Y589541I292J-273D01*
G02X288028I-1096J-1027D01*
G03Y590087I-292J273D01*
G02X290220I1096J1027D01*
G37*
G36*
G01X253409D02*
G03Y589541I292J-273D01*
G02X251217I-1096J-1027D01*
G03Y590087I-292J273D01*
G02X253409I1096J1027D01*
G37*
G36*
G01X216598D02*
G03Y589541I292J-273D01*
G02X214406I-1096J-1027D01*
G03Y590087I-292J273D01*
G02X216598I1096J1027D01*
G37*
G36*
G01X179787D02*
G03Y589541I292J-273D01*
G02X177595I-1096J-1027D01*
G03Y590087I-292J273D01*
G02X179787I1096J1027D01*
G37*
G36*
G01X142976D02*
G03Y589541I292J-273D01*
G02X140784I-1096J-1027D01*
G03Y590087I-292J273D01*
G02X142976I1096J1027D01*
G37*
G36*
G01X1225870Y589873D02*
G03Y589327I292J-273D01*
G02X1223678I-1096J-1027D01*
G03Y589873I-292J273D01*
G02X1225870I1096J1027D01*
G37*
G36*
G01X1189059D02*
G03Y589327I292J-273D01*
G02X1186867I-1096J-1027D01*
G03Y589873I-292J273D01*
G02X1189059I1096J1027D01*
G37*
G36*
G01X1152248D02*
G03Y589327I292J-273D01*
G02X1150056I-1096J-1027D01*
G03Y589873I-292J273D01*
G02X1152248I1096J1027D01*
G37*
G36*
G01X1115436D02*
G03Y589327I292J-273D01*
G02X1113244I-1096J-1027D01*
G03Y589873I-292J273D01*
G02X1115436I1096J1027D01*
G37*
G36*
G01X934728D02*
G03Y589327I292J-273D01*
G02X932536I-1096J-1027D01*
G03Y589873I-292J273D01*
G02X934728I1096J1027D01*
G37*
G36*
G01X897917D02*
G03Y589327I292J-273D01*
G02X895725I-1096J-1027D01*
G03Y589873I-292J273D01*
G02X897917I1096J1027D01*
G37*
G36*
G01X861106D02*
G03Y589327I292J-273D01*
G02X858914I-1096J-1027D01*
G03Y589873I-292J273D01*
G02X861106I1096J1027D01*
G37*
G36*
G01X824295D02*
G03Y589327I292J-273D01*
G02X822103I-1096J-1027D01*
G03Y589873I-292J273D01*
G02X824295I1096J1027D01*
G37*
G36*
G01X787484D02*
G03Y589327I292J-273D01*
G02X785292I-1096J-1027D01*
G03Y589873I-292J273D01*
G02X787484I1096J1027D01*
G37*
G36*
G01X576262D02*
G03Y589327I292J-273D01*
G02X574070I-1096J-1027D01*
G03Y589873I-292J273D01*
G02X576262I1096J1027D01*
G37*
G36*
G01X539451D02*
G03Y589327I292J-273D01*
G02X537259I-1096J-1027D01*
G03Y589873I-292J273D01*
G02X539451I1096J1027D01*
G37*
G36*
G01X502640D02*
G03Y589327I292J-273D01*
G02X500448I-1096J-1027D01*
G03Y589873I-292J273D01*
G02X502640I1096J1027D01*
G37*
G36*
G01X465828D02*
G03Y589327I292J-273D01*
G02X463636I-1096J-1027D01*
G03Y589873I-292J273D01*
G02X465828I1096J1027D01*
G37*
G36*
G01X285120D02*
G03Y589327I292J-273D01*
G02X282928I-1096J-1027D01*
G03Y589873I-292J273D01*
G02X285120I1096J1027D01*
G37*
G36*
G01X248309D02*
G03Y589327I292J-273D01*
G02X246117I-1096J-1027D01*
G03Y589873I-292J273D01*
G02X248309I1096J1027D01*
G37*
G36*
G01X211498D02*
G03Y589327I292J-273D01*
G02X209306I-1096J-1027D01*
G03Y589873I-292J273D01*
G02X211498I1096J1027D01*
G37*
G36*
G01X174687D02*
G03Y589327I292J-273D01*
G02X172495I-1096J-1027D01*
G03Y589873I-292J273D01*
G02X174687I1096J1027D01*
G37*
G36*
G01X137876D02*
G03Y589327I292J-273D01*
G02X135684I-1096J-1027D01*
G03Y589873I-292J273D01*
G02X137876I1096J1027D01*
G37*
G36*
G01X1662192Y590760D02*
Y586665D01*
X1662182Y586581D01*
G02X1659168Y586750I-1502J169D01*
G01Y590751D01*
G02X1662192Y590760I1512J-1D01*
G37*
G36*
G01X1419447Y585240D02*
G03X1418893I-277J-288D01*
G02X1416824Y585375I-973J1010D01*
G03X1416215Y585394I-313J-249D01*
G02X1414200Y585322I-1042J938D01*
G03X1413646I-277J-288D01*
G02Y587342I-973J1010D01*
G03X1414200I277J288D01*
G02X1416269Y587207I973J-1010D01*
G03X1416878Y587188I313J249D01*
G02X1418893Y587260I1042J-938D01*
G03X1419447I277J288D01*
G02X1421393I973J-1010D01*
G03X1421947I277J288D01*
G02Y585240I973J-1010D01*
G03X1421393I-277J-288D01*
G02X1419447I-973J1010D01*
G37*
G36*
G01X1611008Y590005D02*
G02X1614030Y590014I1511J-1D01*
G01Y586004D01*
X1614031D01*
Y585919D01*
X1614021Y585835D01*
G02X1611008Y586004I-1502J169D01*
G01Y590005D01*
G37*
G36*
G01X1544189Y584753D02*
G03X1543611I-289J-277D01*
G02Y586695I-1011J971D01*
G03X1544189I289J277D01*
G02Y584753I1011J-971D01*
G37*
G36*
G01X1372689Y583685D02*
G03X1372111I-289J-277D01*
G02Y585627I-1011J971D01*
G03X1372689I289J277D01*
G02Y583685I1011J-971D01*
G37*
G36*
G01X1815255Y582948D02*
G03X1814679Y582814I-227J-329D01*
G02X1814253Y584653I-1223J686D01*
G03X1814829Y584787I227J329D01*
G02X1815255Y582948I1223J-686D01*
G37*
G36*
G01X1731818Y580896D02*
G03X1732393Y580876I297J267D01*
G02X1732324Y578932I975J-1008D01*
G03X1731749Y578952I-297J-267D01*
G02X1731818Y580896I-975J1008D01*
G37*
G36*
G01X1294692Y581162D02*
G03X1295092Y580762I400J0D01*
G02X1293688Y579358I-2J-1402D01*
G03X1293288Y579758I-400J0D01*
G02X1294692Y581162I2J1402D01*
G37*
G36*
G01X1684289Y586650D02*
X1684290Y586648D01*
X1687186Y581243D01*
X1687187Y581241D01*
G02X1683042Y579020I-2045J-1162D01*
G01X1683041Y579022D01*
X1680145Y584427D01*
X1680144Y584429D01*
G02X1684289Y586650I2045J1162D01*
G37*
G36*
G01X1675423Y586665D02*
X1675424Y586664D01*
X1678336Y581227D01*
X1678337Y581225D01*
G02X1674191Y579005I-2054J-1146D01*
G01X1674190Y579006D01*
X1671278Y584443D01*
X1671277Y584445D01*
G02X1675423Y586665I2054J1146D01*
G37*
G36*
G01X1637045Y586650D02*
X1637046Y586648D01*
X1639942Y581243D01*
X1639943Y581241D01*
G02X1635798Y579020I-2045J-1162D01*
G01X1635797Y579022D01*
X1632901Y584427D01*
X1632900Y584429D01*
G02X1637045Y586650I2045J1162D01*
G37*
G36*
G01X1628179Y586665D02*
X1628180Y586664D01*
X1631092Y581227D01*
X1631093Y581225D01*
G02X1626947Y579005I-2054J-1146D01*
G01X1626946Y579006D01*
X1624034Y584443D01*
X1624033Y584445D01*
G02X1628179Y586665I2054J1146D01*
G37*
G36*
G01X1607506Y582510D02*
Y578415D01*
X1607496Y578331D01*
G02X1604482Y578500I-1502J169D01*
G01Y582501D01*
G02X1607506Y582510I1512J-1D01*
G37*
G36*
G01X1654180Y582360D02*
Y578265D01*
X1654171Y578181D01*
G02X1651158Y578350I-1502J169D01*
G01Y582351D01*
G02X1654180Y582360I1511J-1D01*
G37*
G36*
G01X651238Y573438D02*
G03X650696Y573413I-257J-306D01*
G02X648729Y575411I-996J987D01*
G03Y575989I-277J289D01*
G02X650645Y578036I971J1011D01*
G03X651186Y578039I269J296D01*
G02X653150Y576038I954J-1028D01*
G03Y575484I288J-277D01*
G02X651238Y573438I-1009J-973D01*
G37*
G36*
G01X664689Y573229D02*
G03X664111I-289J-277D01*
G02Y575171I-1011J971D01*
G03X664689I289J277D01*
G02Y573229I1011J-971D01*
G37*
G36*
G01X1772522Y574592D02*
G03X1772110Y574142I-15J-400D01*
G02X1770775Y575365I-1391J-178D01*
G03X1771187Y575815I15J400D01*
G02X1772522Y574592I1391J178D01*
G37*
G36*
G01X660489Y568829D02*
G03X659911I-289J-277D01*
G02Y570771I-1011J971D01*
G03X660489I289J277D01*
G02Y568829I1011J-971D01*
G37*
G36*
G01X1225862Y571164D02*
G03X1225868Y570607I290J-275D01*
G02X1223712Y570585I-1067J-1057D01*
G03X1223706Y571142I-290J275D01*
G02X1225862Y571164I1067J1057D01*
G37*
G36*
G01X1189051D02*
G03X1189057Y570607I290J-275D01*
G02X1186901Y570585I-1067J-1057D01*
G03X1186895Y571142I-290J275D01*
G02X1189051Y571164I1067J1057D01*
G37*
G36*
G01X1152240D02*
G03X1152246Y570607I290J-275D01*
G02X1150090Y570585I-1067J-1057D01*
G03X1150084Y571142I-290J275D01*
G02X1152240Y571164I1067J1057D01*
G37*
G36*
G01X1115428D02*
G03X1115434Y570607I290J-275D01*
G02X1113278Y570585I-1067J-1057D01*
G03X1113272Y571142I-290J275D01*
G02X1115428Y571164I1067J1057D01*
G37*
G36*
G01X934720D02*
G03X934726Y570607I290J-275D01*
G02X932570Y570585I-1067J-1057D01*
G03X932564Y571142I-290J275D01*
G02X934720Y571164I1067J1057D01*
G37*
G36*
G01X897909D02*
G03X897915Y570607I290J-275D01*
G02X895759Y570585I-1067J-1057D01*
G03X895753Y571142I-290J275D01*
G02X897909Y571164I1067J1057D01*
G37*
G36*
G01X861098D02*
G03X861104Y570607I290J-275D01*
G02X858948Y570585I-1067J-1057D01*
G03X858942Y571142I-290J275D01*
G02X861098Y571164I1067J1057D01*
G37*
G36*
G01X824287D02*
G03X824293Y570607I290J-275D01*
G02X822137Y570585I-1067J-1057D01*
G03X822131Y571142I-290J275D01*
G02X824287Y571164I1067J1057D01*
G37*
G36*
G01X787476D02*
G03X787482Y570607I290J-275D01*
G02X785326Y570585I-1067J-1057D01*
G03X785320Y571142I-290J275D01*
G02X787476Y571164I1067J1057D01*
G37*
G36*
G01X576254D02*
G03X576260Y570607I290J-275D01*
G02X574104Y570585I-1067J-1057D01*
G03X574098Y571142I-290J275D01*
G02X576254Y571164I1067J1057D01*
G37*
G36*
G01X539443D02*
G03X539449Y570607I290J-275D01*
G02X537293Y570585I-1067J-1057D01*
G03X537287Y571142I-290J275D01*
G02X539443Y571164I1067J1057D01*
G37*
G36*
G01X502632D02*
G03X502638Y570607I290J-275D01*
G02X500482Y570585I-1067J-1057D01*
G03X500476Y571142I-290J275D01*
G02X502632Y571164I1067J1057D01*
G37*
G36*
G01X463670Y570585D02*
G03X463664Y571142I-290J275D01*
G02X465820Y571164I1067J1057D01*
G03X465826Y570607I290J-275D01*
G02X463670Y570585I-1067J-1057D01*
G37*
G36*
G01X285112Y571164D02*
G03X285118Y570607I290J-275D01*
G02X282962Y570585I-1067J-1057D01*
G03X282956Y571142I-290J275D01*
G02X285112Y571164I1067J1057D01*
G37*
G36*
G01X248301D02*
G03X248307Y570607I290J-275D01*
G02X246151Y570585I-1067J-1057D01*
G03X246145Y571142I-290J275D01*
G02X248301Y571164I1067J1057D01*
G37*
G36*
G01X211490D02*
G03X211496Y570607I290J-275D01*
G02X209340Y570585I-1067J-1057D01*
G03X209334Y571142I-290J275D01*
G02X211490Y571164I1067J1057D01*
G37*
G36*
G01X174679D02*
G03X174685Y570607I290J-275D01*
G02X172529Y570585I-1067J-1057D01*
G03X172523Y571142I-290J275D01*
G02X174679Y571164I1067J1057D01*
G37*
G36*
G01X135718Y570585D02*
G03X135712Y571142I-290J275D01*
G02X137868Y571164I1067J1057D01*
G03X137874Y570607I290J-275D01*
G02X135718Y570585I-1067J-1057D01*
G37*
G36*
G01X1230967Y570919D02*
G03Y570370I291J-274D01*
G02X1228781I-1093J-1030D01*
G03Y570919I-291J274D01*
G02X1230967I1093J1030D01*
G37*
G36*
G01X1194156D02*
G03Y570370I291J-274D01*
G02X1191970I-1093J-1030D01*
G03Y570919I-291J274D01*
G02X1194156I1093J1030D01*
G37*
G36*
G01X1157345D02*
G03Y570370I291J-274D01*
G02X1155159I-1093J-1030D01*
G03Y570919I-291J274D01*
G02X1157345I1093J1030D01*
G37*
G36*
G01X1120533D02*
G03Y570370I291J-274D01*
G02X1118347I-1093J-1030D01*
G03Y570919I-291J274D01*
G02X1120533I1093J1030D01*
G37*
G36*
G01X939825D02*
G03Y570370I291J-274D01*
G02X937639I-1093J-1030D01*
G03Y570919I-291J274D01*
G02X939825I1093J1030D01*
G37*
G36*
G01X903014D02*
G03Y570370I291J-274D01*
G02X900828I-1093J-1030D01*
G03Y570919I-291J274D01*
G02X903014I1093J1030D01*
G37*
G36*
G01X866203D02*
G03Y570370I291J-274D01*
G02X864017I-1093J-1030D01*
G03Y570919I-291J274D01*
G02X866203I1093J1030D01*
G37*
G36*
G01X829392D02*
G03Y570370I291J-274D01*
G02X827206I-1093J-1030D01*
G03Y570919I-291J274D01*
G02X829392I1093J1030D01*
G37*
G36*
G01X792581D02*
G03Y570370I291J-274D01*
G02X790395I-1093J-1030D01*
G03Y570919I-291J274D01*
G02X792581I1093J1030D01*
G37*
G36*
G01X581359D02*
G03Y570370I291J-274D01*
G02X579173I-1093J-1030D01*
G03Y570919I-291J274D01*
G02X581359I1093J1030D01*
G37*
G36*
G01X544548D02*
G03Y570370I291J-274D01*
G02X542362I-1093J-1030D01*
G03Y570919I-291J274D01*
G02X544548I1093J1030D01*
G37*
G36*
G01X507737D02*
G03Y570370I291J-274D01*
G02X505551I-1093J-1030D01*
G03Y570919I-291J274D01*
G02X507737I1093J1030D01*
G37*
G36*
G01X470925D02*
G03Y570370I291J-274D01*
G02X468739I-1093J-1030D01*
G03Y570919I-291J274D01*
G02X470925I1093J1030D01*
G37*
G36*
G01X290217D02*
G03Y570370I291J-274D01*
G02X288031I-1093J-1030D01*
G03Y570919I-291J274D01*
G02X290217I1093J1030D01*
G37*
G36*
G01X253406D02*
G03Y570370I291J-274D01*
G02X251220I-1093J-1030D01*
G03Y570919I-291J274D01*
G02X253406I1093J1030D01*
G37*
G36*
G01X216595D02*
G03Y570370I291J-274D01*
G02X214409I-1093J-1030D01*
G03Y570919I-291J274D01*
G02X216595I1093J1030D01*
G37*
G36*
G01X179784D02*
G03Y570370I291J-274D01*
G02X177598I-1093J-1030D01*
G03Y570919I-291J274D01*
G02X179784I1093J1030D01*
G37*
G36*
G01X142973D02*
G03Y570370I291J-274D01*
G02X140787I-1093J-1030D01*
G03Y570919I-291J274D01*
G02X142973I1093J1030D01*
G37*
G36*
G01X703008Y570426D02*
G03X703030Y569849I288J-278D01*
G02X701092Y569774I-930J-1049D01*
G03X701070Y570351I-288J278D01*
G02X703008Y570426I930J1049D01*
G37*
G36*
G01X649000Y567694D02*
G03X648400I-300J-265D01*
G02Y569552I-1050J929D01*
G03X649000I300J265D01*
G02Y567694I1050J-929D01*
G37*
G36*
G01X1603336Y572335D02*
Y568240D01*
X1603327Y568156D01*
G02X1600314Y568325I-1502J169D01*
G01Y572326D01*
G02X1603336Y572335I1511J-1D01*
G37*
G36*
G01X4611Y568271D02*
G03X5189I289J277D01*
G02Y566329I1011J-971D01*
G03X4611I-289J-277D01*
G02Y568271I-1011J971D01*
G37*
G36*
G01X1684289Y571689D02*
X1684290Y571687D01*
X1687186Y566282D01*
X1687187Y566280D01*
G02X1683042Y564059I-2045J-1162D01*
G01X1683041Y564061D01*
X1680145Y569466D01*
X1680144Y569468D01*
G02X1684289Y571689I2045J1162D01*
G37*
G36*
G01X1675423Y571704D02*
X1675424Y571703D01*
X1678336Y566266D01*
X1678337Y566264D01*
G02X1674191Y564044I-2054J-1146D01*
G01X1674190Y564045D01*
X1671278Y569482D01*
X1671277Y569484D01*
G02X1675423Y571704I2054J1146D01*
G37*
G36*
G01X1637045Y571689D02*
X1637046Y571687D01*
X1639942Y566282D01*
X1639943Y566280D01*
G02X1635798Y564059I-2045J-1162D01*
G01X1635797Y564061D01*
X1632901Y569466D01*
X1632900Y569468D01*
G02X1637045Y571689I2045J1162D01*
G37*
G36*
G01X1628179Y571704D02*
X1628180Y571703D01*
X1631092Y566266D01*
X1631093Y566264D01*
G02X1626947Y564044I-2054J-1146D01*
G01X1626946Y564045D01*
X1624034Y569482D01*
X1624033Y569484D01*
G02X1628179Y571704I2054J1146D01*
G37*
G36*
G01X1448220Y562717D02*
G03X1447680I-270J-295D01*
G02Y565083I-1080J1183D01*
G03X1448220I270J295D01*
G02X1450340Y565118I1080J-1183D01*
G03X1450860I260J304D01*
G02X1452980Y565083I1040J-1218D01*
G03X1453520I270J295D01*
G02X1455680I1080J-1183D01*
G03X1456220I270J295D01*
G02Y562717I1080J-1183D01*
G03X1455680I-270J-295D01*
G02X1453520I-1080J1183D01*
G03X1452980I-270J-295D01*
G02X1450860Y562682I-1080J1183D01*
G03X1450340I-260J-304D01*
G02X1448220Y562717I-1040J1218D01*
G37*
G36*
G01X1655911Y562918D02*
G03X1655333Y562646I-187J-354D01*
G02X1653568Y564276I-1373J284D01*
G03X1653794Y564874I-112J384D01*
G02X1655911Y562918I4734J3000D01*
G37*
G36*
G01X1598097Y561256D02*
G03X1597543I-277J-288D01*
G02X1595579Y563258I-973J1010D01*
G03X1595590Y563812I-283J283D01*
G02X1595597Y565723I1030J952D01*
G03X1595593Y566275I-292J274D01*
G02X1597623Y566291I1007J975D01*
G03X1597627Y565739I292J-274D01*
G02X1597714Y565641I-1004J-979D01*
G03X1598026I156J125D01*
G02X1600111Y563772I1093J-878D01*
G03X1600100Y563218I283J-283D01*
G02X1598097Y561256I-1030J-952D01*
G37*
G36*
G01X1469286Y560694D02*
G03X1468767Y560689I-257J-307D01*
G02X1468742Y563125I-1053J1207D01*
G03X1469261Y563130I257J307D01*
G02X1471361Y563136I1053J-1207D01*
G03X1471901Y563152I261J302D01*
G02X1471971Y560790I1117J-1149D01*
G03X1471431Y560774I-261J-302D01*
G02X1469286Y560694I-1117J1149D01*
G37*
G36*
G01X1491077Y560687D02*
G03X1490504Y560667I-277J-289D01*
G02X1490426Y562897I-1188J1075D01*
G03X1490999Y562917I277J289D01*
G02X1493387Y562903I1188J-1075D01*
G03X1493987I300J265D01*
G02X1496267Y563025I1200J-1061D01*
G03X1496812Y563031I269J296D01*
G02X1498963Y563086I1106J-1159D01*
G03X1499485I261J303D01*
G02Y560658I1045J-1214D01*
G03X1498963I-261J-303D01*
G02X1496838Y560689I-1045J1214D01*
G03X1496293Y560683I-269J-296D01*
G02X1493987Y560781I-1106J1159D01*
G03X1493387I-300J-265D01*
G02X1491077Y560687I-1200J1061D01*
G37*
G36*
G01X1383118Y561641D02*
G03X1383081Y561073I262J-302D01*
G02X1381114Y561202I-1049J-930D01*
G03X1381151Y561770I-262J302D01*
G02X1383118Y561641I1049J930D01*
G37*
G36*
G01X1739133Y559735D02*
G03X1739297Y559155I335J-218D01*
G02X1737522Y558653I-600J-1267D01*
G03X1737358Y559233I-335J218D01*
G02X1739133Y559735I600J1267D01*
G37*
G36*
G01X1626606Y559210D02*
Y555115D01*
X1626596Y555031D01*
G02X1623582Y555200I-1502J169D01*
G01Y559200D01*
G02X1626606Y559210I1512J0D01*
G37*
G36*
G01X2393Y555510D02*
G03X2416Y554924I283J-282D01*
G02X430Y554895I-977J-1141D01*
G03X436Y555482I-269J296D01*
G02X389Y555529I968J1015D01*
G03X-189I-289J-277D01*
G02Y557471I-1011J971D01*
G03X389I289J277D01*
G02X2393Y555510I1012J-971D01*
G37*
G36*
G01X652611Y551617D02*
G03X651989I-311J-252D01*
G02Y553383I-1089J883D01*
G03X652611I311J252D01*
G02Y551617I1089J-883D01*
G37*
G36*
G01X1663754Y549588D02*
X1658753D01*
G02X1658754Y552412I1J1412D01*
G01X1663754D01*
G02X1665166Y551010I0J-1412D01*
G01Y550916D01*
X1665155Y550832D01*
G02X1663754Y549588I-1401J167D01*
G37*
G36*
G01X1230970Y552287D02*
G03Y551741I292J-273D01*
G02X1228778I-1096J-1027D01*
G03Y552287I-292J273D01*
G02X1230970I1096J1027D01*
G37*
G36*
G01X1194159D02*
G03Y551741I292J-273D01*
G02X1191967I-1096J-1027D01*
G03Y552287I-292J273D01*
G02X1194159I1096J1027D01*
G37*
G36*
G01X1157348D02*
G03Y551741I292J-273D01*
G02X1155156I-1096J-1027D01*
G03Y552287I-292J273D01*
G02X1157348I1096J1027D01*
G37*
G36*
G01X1120536D02*
G03Y551741I292J-273D01*
G02X1118344I-1096J-1027D01*
G03Y552287I-292J273D01*
G02X1120536I1096J1027D01*
G37*
G36*
G01X939828D02*
G03Y551741I292J-273D01*
G02X937636I-1096J-1027D01*
G03Y552287I-292J273D01*
G02X939828I1096J1027D01*
G37*
G36*
G01X903017D02*
G03Y551741I292J-273D01*
G02X900825I-1096J-1027D01*
G03Y552287I-292J273D01*
G02X903017I1096J1027D01*
G37*
G36*
G01X866206D02*
G03Y551741I292J-273D01*
G02X864014I-1096J-1027D01*
G03Y552287I-292J273D01*
G02X866206I1096J1027D01*
G37*
G36*
G01X829395D02*
G03Y551741I292J-273D01*
G02X827203I-1096J-1027D01*
G03Y552287I-292J273D01*
G02X829395I1096J1027D01*
G37*
G36*
G01X792584D02*
G03Y551741I292J-273D01*
G02X790392I-1096J-1027D01*
G03Y552287I-292J273D01*
G02X792584I1096J1027D01*
G37*
G36*
G01X581362D02*
G03Y551741I292J-273D01*
G02X579170I-1096J-1027D01*
G03Y552287I-292J273D01*
G02X581362I1096J1027D01*
G37*
G36*
G01X544551D02*
G03Y551741I292J-273D01*
G02X542359I-1096J-1027D01*
G03Y552287I-292J273D01*
G02X544551I1096J1027D01*
G37*
G36*
G01X507740D02*
G03Y551741I292J-273D01*
G02X505548I-1096J-1027D01*
G03Y552287I-292J273D01*
G02X507740I1096J1027D01*
G37*
G36*
G01X470928D02*
G03Y551741I292J-273D01*
G02X468736I-1096J-1027D01*
G03Y552287I-292J273D01*
G02X470928I1096J1027D01*
G37*
G36*
G01X290220D02*
G03Y551741I292J-273D01*
G02X288028I-1096J-1027D01*
G03Y552287I-292J273D01*
G02X290220I1096J1027D01*
G37*
G36*
G01X253409D02*
G03Y551741I292J-273D01*
G02X251217I-1096J-1027D01*
G03Y552287I-292J273D01*
G02X253409I1096J1027D01*
G37*
G36*
G01X216598D02*
G03Y551741I292J-273D01*
G02X214406I-1096J-1027D01*
G03Y552287I-292J273D01*
G02X216598I1096J1027D01*
G37*
G36*
G01X179787D02*
G03Y551741I292J-273D01*
G02X177595I-1096J-1027D01*
G03Y552287I-292J273D01*
G02X179787I1096J1027D01*
G37*
G36*
G01X142976D02*
G03Y551741I292J-273D01*
G02X140784I-1096J-1027D01*
G03Y552287I-292J273D01*
G02X142976I1096J1027D01*
G37*
G36*
G01X1685000Y549032D02*
X1679999D01*
G02X1680000Y552056I1J1512D01*
G01X1685000D01*
G02X1686512Y550554I0J-1512D01*
G01Y550459D01*
X1686502Y550375D01*
G02X1685000Y549032I-1502J168D01*
G37*
G36*
G01X1225870Y552073D02*
G03Y551527I292J-273D01*
G02X1223678I-1096J-1027D01*
G03Y552073I-292J273D01*
G02X1225870I1096J1027D01*
G37*
G36*
G01X1189059D02*
G03Y551527I292J-273D01*
G02X1186867I-1096J-1027D01*
G03Y552073I-292J273D01*
G02X1189059I1096J1027D01*
G37*
G36*
G01X1152248D02*
G03Y551527I292J-273D01*
G02X1150056I-1096J-1027D01*
G03Y552073I-292J273D01*
G02X1152248I1096J1027D01*
G37*
G36*
G01X1115436D02*
G03Y551527I292J-273D01*
G02X1113244I-1096J-1027D01*
G03Y552073I-292J273D01*
G02X1115436I1096J1027D01*
G37*
G36*
G01X934728D02*
G03Y551527I292J-273D01*
G02X932536I-1096J-1027D01*
G03Y552073I-292J273D01*
G02X934728I1096J1027D01*
G37*
G36*
G01X897917D02*
G03Y551527I292J-273D01*
G02X895725I-1096J-1027D01*
G03Y552073I-292J273D01*
G02X897917I1096J1027D01*
G37*
G36*
G01X861106D02*
G03Y551527I292J-273D01*
G02X858914I-1096J-1027D01*
G03Y552073I-292J273D01*
G02X861106I1096J1027D01*
G37*
G36*
G01X824295D02*
G03Y551527I292J-273D01*
G02X822103I-1096J-1027D01*
G03Y552073I-292J273D01*
G02X824295I1096J1027D01*
G37*
G36*
G01X787484D02*
G03Y551527I292J-273D01*
G02X785292I-1096J-1027D01*
G03Y552073I-292J273D01*
G02X787484I1096J1027D01*
G37*
G36*
G01X576262D02*
G03Y551527I292J-273D01*
G02X574070I-1096J-1027D01*
G03Y552073I-292J273D01*
G02X576262I1096J1027D01*
G37*
G36*
G01X539451D02*
G03Y551527I292J-273D01*
G02X537259I-1096J-1027D01*
G03Y552073I-292J273D01*
G02X539451I1096J1027D01*
G37*
G36*
G01X502640D02*
G03Y551527I292J-273D01*
G02X500448I-1096J-1027D01*
G03Y552073I-292J273D01*
G02X502640I1096J1027D01*
G37*
G36*
G01X465828D02*
G03Y551527I292J-273D01*
G02X463636I-1096J-1027D01*
G03Y552073I-292J273D01*
G02X465828I1096J1027D01*
G37*
G36*
G01X285120D02*
G03Y551527I292J-273D01*
G02X282928I-1096J-1027D01*
G03Y552073I-292J273D01*
G02X285120I1096J1027D01*
G37*
G36*
G01X248309D02*
G03Y551527I292J-273D01*
G02X246117I-1096J-1027D01*
G03Y552073I-292J273D01*
G02X248309I1096J1027D01*
G37*
G36*
G01X211498D02*
G03Y551527I292J-273D01*
G02X209306I-1096J-1027D01*
G03Y552073I-292J273D01*
G02X211498I1096J1027D01*
G37*
G36*
G01X174687D02*
G03Y551527I292J-273D01*
G02X172495I-1096J-1027D01*
G03Y552073I-292J273D01*
G02X174687I1096J1027D01*
G37*
G36*
G01X137876D02*
G03Y551527I292J-273D01*
G02X135684I-1096J-1027D01*
G03Y552073I-292J273D01*
G02X137876I1096J1027D01*
G37*
G36*
G01X1794888Y551715D02*
G03X1794866Y551116I254J-309D01*
G02X1793012Y551185I-966J-1016D01*
G03X1793034Y551784I-254J309D01*
G02X1794888Y551715I966J1016D01*
G37*
G36*
G01X1936731Y551240D02*
G03X1937264Y550995I380J125D01*
G02X1936469Y549260I536J-1295D01*
G03X1935936Y549505I-380J-125D01*
G02X1936731Y551240I-536J1295D01*
G37*
G36*
G01X1739037Y549968D02*
G03X1739065Y549355I270J-295D01*
G02X1737267Y549271I-849J-1116D01*
G03X1737239Y549884I-270J295D01*
G02X1739037Y549968I849J1116D01*
G37*
G36*
G01X1364055Y546944D02*
G03X1363501I-277J-288D01*
G02Y548964I-973J1010D01*
G03X1364055I277J288D01*
G02Y546944I973J-1010D01*
G37*
G36*
G01X1705348Y545122D02*
X1700348D01*
G02Y548144I0J1511D01*
G01X1705348D01*
G02X1706860Y546643I0J-1512D01*
G01Y546548D01*
X1706850Y546464D01*
G02X1705348Y545122I-1502J169D01*
G37*
G36*
G01X1496273Y547033D02*
G03X1496820Y547010I286J280D01*
G02X1496723Y544674I1046J-1213D01*
G03X1496176Y544697I-286J-280D01*
G02X1493930Y544849I-1046J1213D01*
G03X1493330I-300J-265D01*
G02X1490874Y544916I-1200J1061D01*
G03X1490298Y544970I-314J-248D01*
G02X1490387Y547006I-918J1060D01*
G03X1490965Y547010I287J278D01*
G02X1493330Y546971I1165J-1100D01*
G03X1493930I300J265D01*
G02X1496273Y547033I1200J-1061D01*
G37*
G36*
G01X1439987Y544190D02*
G03X1439915Y543633I247J-315D01*
G02X1437935Y543889I-1116J-848D01*
G03X1438007Y544446I-247J315D01*
G02X1439987Y544190I1116J848D01*
G37*
G36*
G01X1676020Y550027D02*
G03X1676280Y549508I376J-136D01*
G02X1671633Y548350I-1359J-4449D01*
G03X1671350Y549032I-283J282D01*
G01X1669599D01*
G02X1669600Y552056I1J1512D01*
G01X1674600D01*
G02X1676112Y550554I0J-1512D01*
G01Y550459D01*
X1676102Y550375D01*
G02X1676020Y550027I-1502J170D01*
G37*
G36*
G01X1391434Y540655D02*
G03X1391428Y540051I259J-305D01*
G02X1389543Y540025I-928J-1051D01*
G03X1389521Y540629I-273J292D01*
G02X1391434Y540655I941J1171D01*
G37*
G36*
G01X1743894Y534951D02*
G03X1743351I-271J-294D01*
G02Y538631I-1697J1840D01*
G03X1743894I272J294D01*
G02X1747288I1697J-1840D01*
G03X1747831I272J294D01*
G02X1751225I1697J-1840D01*
G03X1751768I271J294D01*
G02X1755162I1697J-1840D01*
G03X1755705I271J294D01*
G02X1759099I1697J-1840D01*
G03X1759642I272J294D01*
G02Y534951I1697J-1840D01*
G03X1759099I-271J-294D01*
G02X1755705I-1697J1840D01*
G03X1755162I-272J-294D01*
G02X1751768I-1697J1840D01*
G03X1751225I-272J-294D01*
G02X1747831I-1697J1840D01*
G03X1747288I-271J-294D01*
G02X1743894I-1697J1840D01*
G37*
G36*
G01X735027Y534190D02*
G03X734473I-277J-288D01*
G02X732490Y536173I-973J1010D01*
G03Y536727I-288J277D01*
G02X734473Y538710I1010J973D01*
G03X735027I277J288D01*
G02X737010Y536727I973J-1010D01*
G03Y536173I288J-277D01*
G02X735027Y534190I-1010J-973D01*
G37*
G36*
G01X1712206Y533780D02*
X1707204D01*
G02X1704820Y534952I0J3011D01*
G03X1704207Y534977I-317J-244D01*
G02X1700203Y534976I-2002J1814D01*
G03X1699590Y534952I-296J-268D01*
G02X1697206Y533780I-2384J1839D01*
G01X1692204D01*
G02X1689820Y534952I0J3011D01*
G03X1689207Y534977I-317J-244D01*
G02Y538605I-2002J1814D01*
G03X1689820Y538630I296J269D01*
G02X1692204Y539802I2384J-1839D01*
G01X1697206D01*
G02X1699590Y538630I0J-3011D01*
G03X1700203Y538606I317J244D01*
G02X1704207Y538605I2002J-1815D01*
G03X1704820Y538630I296J269D01*
G02X1707204Y539802I2384J-1839D01*
G01X1712206D01*
G02X1714590Y538630I0J-3011D01*
G03X1715203Y538606I317J244D01*
G02Y534976I2002J-1815D01*
G03X1714590Y534952I-296J-268D01*
G02X1712206Y533780I-2384J1839D01*
G37*
G36*
G01X1225862Y533364D02*
G03X1225868Y532807I290J-275D01*
G02X1223712Y532785I-1067J-1057D01*
G03X1223706Y533342I-290J275D01*
G02X1225862Y533364I1067J1057D01*
G37*
G36*
G01X1189051D02*
G03X1189057Y532807I290J-275D01*
G02X1186901Y532785I-1067J-1057D01*
G03X1186895Y533342I-290J275D01*
G02X1189051Y533364I1067J1057D01*
G37*
G36*
G01X1152240D02*
G03X1152246Y532807I290J-275D01*
G02X1150090Y532785I-1067J-1057D01*
G03X1150084Y533342I-290J275D01*
G02X1152240Y533364I1067J1057D01*
G37*
G36*
G01X1115428D02*
G03X1115434Y532807I290J-275D01*
G02X1113278Y532785I-1067J-1057D01*
G03X1113272Y533342I-290J275D01*
G02X1115428Y533364I1067J1057D01*
G37*
G36*
G01X934720D02*
G03X934726Y532807I290J-275D01*
G02X932570Y532785I-1067J-1057D01*
G03X932564Y533342I-290J275D01*
G02X934720Y533364I1067J1057D01*
G37*
G36*
G01X897909D02*
G03X897915Y532807I290J-275D01*
G02X895759Y532785I-1067J-1057D01*
G03X895753Y533342I-290J275D01*
G02X897909Y533364I1067J1057D01*
G37*
G36*
G01X861098D02*
G03X861104Y532807I290J-275D01*
G02X858948Y532785I-1067J-1057D01*
G03X858942Y533342I-290J275D01*
G02X861098Y533364I1067J1057D01*
G37*
G36*
G01X824287D02*
G03X824293Y532807I290J-275D01*
G02X822137Y532785I-1067J-1057D01*
G03X822131Y533342I-290J275D01*
G02X824287Y533364I1067J1057D01*
G37*
G36*
G01X787476D02*
G03X787482Y532807I290J-275D01*
G02X785326Y532785I-1067J-1057D01*
G03X785320Y533342I-290J275D01*
G02X787476Y533364I1067J1057D01*
G37*
G36*
G01X576254D02*
G03X576260Y532807I290J-275D01*
G02X574104Y532785I-1067J-1057D01*
G03X574098Y533342I-290J275D01*
G02X576254Y533364I1067J1057D01*
G37*
G36*
G01X539443D02*
G03X539449Y532807I290J-275D01*
G02X537293Y532785I-1067J-1057D01*
G03X537287Y533342I-290J275D01*
G02X539443Y533364I1067J1057D01*
G37*
G36*
G01X502632D02*
G03X502638Y532807I290J-275D01*
G02X500482Y532785I-1067J-1057D01*
G03X500476Y533342I-290J275D01*
G02X502632Y533364I1067J1057D01*
G37*
G36*
G01X465820D02*
G03X465826Y532807I290J-275D01*
G02X463670Y532785I-1067J-1057D01*
G03X463664Y533342I-290J275D01*
G02X465820Y533364I1067J1057D01*
G37*
G36*
G01X285112D02*
G03X285118Y532807I290J-275D01*
G02X282962Y532785I-1067J-1057D01*
G03X282956Y533342I-290J275D01*
G02X285112Y533364I1067J1057D01*
G37*
G36*
G01X248301D02*
G03X248307Y532807I290J-275D01*
G02X246151Y532785I-1067J-1057D01*
G03X246145Y533342I-290J275D01*
G02X248301Y533364I1067J1057D01*
G37*
G36*
G01X211490D02*
G03X211496Y532807I290J-275D01*
G02X209340Y532785I-1067J-1057D01*
G03X209334Y533342I-290J275D01*
G02X211490Y533364I1067J1057D01*
G37*
G36*
G01X174679D02*
G03X174685Y532807I290J-275D01*
G02X172529Y532785I-1067J-1057D01*
G03X172523Y533342I-290J275D01*
G02X174679Y533364I1067J1057D01*
G37*
G36*
G01X135718Y532785D02*
G03X135712Y533342I-290J275D01*
G02X137868Y533364I1067J1057D01*
G03X137874Y532807I290J-275D01*
G02X135718Y532785I-1067J-1057D01*
G37*
G36*
G01X1230967Y533119D02*
G03Y532570I291J-274D01*
G02X1228781I-1093J-1030D01*
G03Y533119I-291J274D01*
G02X1230967I1093J1030D01*
G37*
G36*
G01X1194156D02*
G03Y532570I291J-274D01*
G02X1191970I-1093J-1030D01*
G03Y533119I-291J274D01*
G02X1194156I1093J1030D01*
G37*
G36*
G01X1157345D02*
G03Y532570I291J-274D01*
G02X1155159I-1093J-1030D01*
G03Y533119I-291J274D01*
G02X1157345I1093J1030D01*
G37*
G36*
G01X1120533D02*
G03Y532570I291J-274D01*
G02X1118347I-1093J-1030D01*
G03Y533119I-291J274D01*
G02X1120533I1093J1030D01*
G37*
G36*
G01X939825D02*
G03Y532570I291J-274D01*
G02X937639I-1093J-1030D01*
G03Y533119I-291J274D01*
G02X939825I1093J1030D01*
G37*
G36*
G01X903014D02*
G03Y532570I291J-274D01*
G02X900828I-1093J-1030D01*
G03Y533119I-291J274D01*
G02X903014I1093J1030D01*
G37*
G36*
G01X866203D02*
G03Y532570I291J-274D01*
G02X864017I-1093J-1030D01*
G03Y533119I-291J274D01*
G02X866203I1093J1030D01*
G37*
G36*
G01X829392D02*
G03Y532570I291J-274D01*
G02X827206I-1093J-1030D01*
G03Y533119I-291J274D01*
G02X829392I1093J1030D01*
G37*
G36*
G01X792581D02*
G03Y532570I291J-274D01*
G02X790395I-1093J-1030D01*
G03Y533119I-291J274D01*
G02X792581I1093J1030D01*
G37*
G36*
G01X581359D02*
G03Y532570I291J-274D01*
G02X579173I-1093J-1030D01*
G03Y533119I-291J274D01*
G02X581359I1093J1030D01*
G37*
G36*
G01X544548D02*
G03Y532570I291J-274D01*
G02X542362I-1093J-1030D01*
G03Y533119I-291J274D01*
G02X544548I1093J1030D01*
G37*
G36*
G01X507737D02*
G03Y532570I291J-274D01*
G02X505551I-1093J-1030D01*
G03Y533119I-291J274D01*
G02X507737I1093J1030D01*
G37*
G36*
G01X470925D02*
G03Y532570I291J-274D01*
G02X468739I-1093J-1030D01*
G03Y533119I-291J274D01*
G02X470925I1093J1030D01*
G37*
G36*
G01X290217D02*
G03Y532570I291J-274D01*
G02X288031I-1093J-1030D01*
G03Y533119I-291J274D01*
G02X290217I1093J1030D01*
G37*
G36*
G01X253406D02*
G03Y532570I291J-274D01*
G02X251220I-1093J-1030D01*
G03Y533119I-291J274D01*
G02X253406I1093J1030D01*
G37*
G36*
G01X216595D02*
G03Y532570I291J-274D01*
G02X214409I-1093J-1030D01*
G03Y533119I-291J274D01*
G02X216595I1093J1030D01*
G37*
G36*
G01X179784D02*
G03Y532570I291J-274D01*
G02X177598I-1093J-1030D01*
G03Y533119I-291J274D01*
G02X179784I1093J1030D01*
G37*
G36*
G01X142973D02*
G03Y532570I291J-274D01*
G02X140787I-1093J-1030D01*
G03Y533119I-291J274D01*
G02X142973I1093J1030D01*
G37*
G36*
G01X4611Y532271D02*
G03X5189I289J277D01*
G02Y530329I1011J-971D01*
G03X4611I-289J-277D01*
G02Y532271I-1011J971D01*
G37*
G36*
G01X1482727Y530190D02*
G03X1482173I-277J-288D01*
G02Y532210I-973J1010D01*
G03X1482727I277J288D01*
G02Y530190I973J-1010D01*
G37*
G36*
G01X115539Y527414D02*
G03X115435Y526832I214J-338D01*
G02X113575Y527166I-1113J-852D01*
G03X113679Y527748I-214J338D01*
G02X115539Y527414I1113J852D01*
G37*
G36*
G01X1818548Y526492D02*
G03X1818168Y526005I11J-400D01*
G02X1816761Y527101I-1368J-305D01*
G03X1817141Y527588I-11J400D01*
G02X1818548Y526492I1368J305D01*
G37*
G36*
G01X1638728Y528723D02*
G03X1638940Y528154I350J-194D01*
G02X1636593Y527726I-810J-2208D01*
G03X1636591Y528333I-261J303D01*
G02X1638728Y528723I909J1067D01*
G37*
G36*
G01X1785026Y521592D02*
G03X1784449Y521570I-278J-288D01*
G02X1782379Y521539I-1049J930D01*
G03X1781811Y521552I-290J-275D01*
G02X1781859Y523523I-973J1010D01*
G03X1782427Y523510I290J275D01*
G02X1784374Y523508I972J-1010D01*
G03X1784951Y523530I278J288D01*
G02X1785026Y521592I1049J-930D01*
G37*
G36*
G01X702144Y523214D02*
G03X702156Y522612I270J-296D01*
G02X700311Y522574I-901J-1074D01*
G03X700299Y523176I-270J296D01*
G02X702144Y523214I901J1074D01*
G37*
G36*
G01X1629183Y519602D02*
G03X1628572Y519538I-279J-287D01*
G02X1628383Y521324I-1165J780D01*
G03X1628994Y521388I279J287D01*
G02X1629183Y519602I1165J-780D01*
G37*
G36*
G01X1698850Y519221D02*
G03X1698272I-289J-277D01*
G02Y521163I-1011J971D01*
G03X1698850I289J277D01*
G02Y519221I1011J-971D01*
G37*
G36*
G01X1790804Y521062D02*
G03X1790594Y520541I159J-367D01*
G02X1788746Y521288I-1294J-541D01*
G03X1788956Y521809I-159J367D01*
G02X1790804Y521062I1294J541D01*
G37*
G36*
G01X1377636Y518921D02*
G03X1377082I-277J-288D01*
G02X1375031Y519035I-973J1010D01*
G03X1374417Y519037I-308J-256D01*
G02X1374423Y520836I-1072J903D01*
G03X1375037Y520834I308J256D01*
G02X1377082Y520941I1073J-903D01*
G03X1377636I277J288D01*
G02X1379572Y520950I973J-1010D01*
G03X1380124Y520952I275J290D01*
G02X1382173Y520836I970J-1012D01*
G03X1382787Y520834I308J256D01*
G02X1384832Y520941I1073J-903D01*
G03X1385386I277J288D01*
G02Y518921I973J-1010D01*
G03X1384832I-277J-288D01*
G02X1382781Y519035I-973J1010D01*
G03X1382167Y519037I-308J-256D01*
G02X1380132Y518921I-1072J903D01*
G03X1379580Y518919I-275J-290D01*
G02X1377636Y518921I-971J1012D01*
G37*
G36*
G01X1490100Y521502D02*
X1492664D01*
G02Y518498I36J-1502D01*
G01X1490099D01*
G02X1490100Y521502I1J1502D01*
G37*
G36*
G01X753910Y520148D02*
G03Y519594I288J-277D01*
G02X751890I-1010J-973D01*
G03Y520148I-288J277D01*
G02X753910I1010J973D01*
G37*
G36*
G01X1510005Y516654D02*
X1507444D01*
X1507441Y516653D01*
G02Y519657I-36J1502D01*
G01X1507444Y519656D01*
X1510005D01*
G02X1511506Y518165I0J-1501D01*
G01Y518070D01*
X1511497Y517986D01*
G02X1510005Y516654I-1492J169D01*
G37*
G36*
G01X53987Y525432D02*
G03X54513I263J302D01*
G02X56487I987J-1132D01*
G03X57013I263J302D01*
G02X59132Y523313I987J-1132D01*
G03Y522787I302J-263D01*
G02X59075Y520751I-1132J-987D01*
G03X59061Y520207I286J-280D01*
G02X56933Y518094I-1125J-995D01*
G03X56420Y518113I-268J-297D01*
G02X54397Y518281I-920J1187D01*
G03X54103I-147J-136D01*
G02X54037Y518214I-1102J1020D01*
G03X54036Y517925I138J-145D01*
G02X51848Y517819I-1044J-1079D01*
G03X51849Y518335I-305J259D01*
G02X51868Y520287I1151J965D01*
G03Y520813I-302J263D01*
G02Y522787I1132J987D01*
G03Y523313I-302J263D01*
G02X53987Y525432I1132J987D01*
G37*
G36*
G01X1500655Y514620D02*
X1498091D01*
G02Y517624I-36J1502D01*
G01X1500655D01*
G02X1502156Y516132I-1J-1502D01*
G01Y516037D01*
X1502147Y515953D01*
G02X1500655Y514620I-1492J169D01*
G37*
G36*
G01X1483227Y514690D02*
G03X1482673I-277J-288D01*
G02Y516710I-973J1010D01*
G03X1483227I277J288D01*
G02Y514690I973J-1010D01*
G37*
G36*
G01X63468Y516587D02*
G03Y517113I-302J263D01*
G02X63617Y519235I1132J987D01*
G03X63596Y519857I-262J303D01*
G02X63343Y522008I907J1197D01*
G03X63317Y522545I-309J254D01*
G02X63282Y524631I1063J1061D01*
G03Y525177I-292J273D01*
G02X65087Y527527I1098J1025D01*
G03X65604Y527653I188J353D01*
G02X67972Y525813I1237J-852D01*
G03Y525287I302J-263D01*
G02X67864Y523201I-1132J-987D01*
G03X67853Y522919I136J-147D01*
G02X67882Y520913I-1103J-1019D01*
G03Y520387I302J-263D01*
G02Y518413I-1132J-987D01*
G03Y517887I302J-263D01*
G02X66485Y515422I-1132J-987D01*
G03X66032Y515148I-71J-394D01*
G02X63468Y516587I-1432J452D01*
G37*
G36*
G01X1314671Y516789D02*
G03Y516211I277J-289D01*
G02X1312729I-971J-1011D01*
G03Y516789I-277J289D01*
G02X1314671I971J1011D01*
G37*
G36*
G01X1230970Y514487D02*
G03Y513941I292J-273D01*
G02X1228778I-1096J-1027D01*
G03Y514487I-292J273D01*
G02X1230970I1096J1027D01*
G37*
G36*
G01X1194159D02*
G03Y513941I292J-273D01*
G02X1191967I-1096J-1027D01*
G03Y514487I-292J273D01*
G02X1194159I1096J1027D01*
G37*
G36*
G01X1157348D02*
G03Y513941I292J-273D01*
G02X1155156I-1096J-1027D01*
G03Y514487I-292J273D01*
G02X1157348I1096J1027D01*
G37*
G36*
G01X1120536D02*
G03Y513941I292J-273D01*
G02X1118344I-1096J-1027D01*
G03Y514487I-292J273D01*
G02X1120536I1096J1027D01*
G37*
G36*
G01X939828D02*
G03Y513941I292J-273D01*
G02X937636I-1096J-1027D01*
G03Y514487I-292J273D01*
G02X939828I1096J1027D01*
G37*
G36*
G01X903017D02*
G03Y513941I292J-273D01*
G02X900825I-1096J-1027D01*
G03Y514487I-292J273D01*
G02X903017I1096J1027D01*
G37*
G36*
G01X866206D02*
G03Y513941I292J-273D01*
G02X864014I-1096J-1027D01*
G03Y514487I-292J273D01*
G02X866206I1096J1027D01*
G37*
G36*
G01X829395D02*
G03Y513941I292J-273D01*
G02X827203I-1096J-1027D01*
G03Y514487I-292J273D01*
G02X829395I1096J1027D01*
G37*
G36*
G01X792584D02*
G03Y513941I292J-273D01*
G02X790392I-1096J-1027D01*
G03Y514487I-292J273D01*
G02X792584I1096J1027D01*
G37*
G36*
G01X581362D02*
G03Y513941I292J-273D01*
G02X579170I-1096J-1027D01*
G03Y514487I-292J273D01*
G02X581362I1096J1027D01*
G37*
G36*
G01X544551D02*
G03Y513941I292J-273D01*
G02X542359I-1096J-1027D01*
G03Y514487I-292J273D01*
G02X544551I1096J1027D01*
G37*
G36*
G01X507740D02*
G03Y513941I292J-273D01*
G02X505548I-1096J-1027D01*
G03Y514487I-292J273D01*
G02X507740I1096J1027D01*
G37*
G36*
G01X470928D02*
G03Y513941I292J-273D01*
G02X468736I-1096J-1027D01*
G03Y514487I-292J273D01*
G02X470928I1096J1027D01*
G37*
G36*
G01X290220D02*
G03Y513941I292J-273D01*
G02X288028I-1096J-1027D01*
G03Y514487I-292J273D01*
G02X290220I1096J1027D01*
G37*
G36*
G01X253409D02*
G03Y513941I292J-273D01*
G02X251217I-1096J-1027D01*
G03Y514487I-292J273D01*
G02X253409I1096J1027D01*
G37*
G36*
G01X216598D02*
G03Y513941I292J-273D01*
G02X214406I-1096J-1027D01*
G03Y514487I-292J273D01*
G02X216598I1096J1027D01*
G37*
G36*
G01X179787D02*
G03Y513941I292J-273D01*
G02X177595I-1096J-1027D01*
G03Y514487I-292J273D01*
G02X179787I1096J1027D01*
G37*
G36*
G01X142976D02*
G03Y513941I292J-273D01*
G02X140784I-1096J-1027D01*
G03Y514487I-292J273D01*
G02X142976I1096J1027D01*
G37*
G36*
G01X1775235Y513745D02*
G03X1775789Y513710I295J270D01*
G02X1775660Y511695I906J-1070D01*
G03X1775106Y511730I-295J-270D01*
G02X1775235Y513745I-906J1070D01*
G37*
G36*
G01X1225870Y514273D02*
G03Y513727I292J-273D01*
G02X1223678I-1096J-1027D01*
G03Y514273I-292J273D01*
G02X1225870I1096J1027D01*
G37*
G36*
G01X1189059D02*
G03Y513727I292J-273D01*
G02X1186867I-1096J-1027D01*
G03Y514273I-292J273D01*
G02X1189059I1096J1027D01*
G37*
G36*
G01X1152248D02*
G03Y513727I292J-273D01*
G02X1150056I-1096J-1027D01*
G03Y514273I-292J273D01*
G02X1152248I1096J1027D01*
G37*
G36*
G01X1115436D02*
G03Y513727I292J-273D01*
G02X1113244I-1096J-1027D01*
G03Y514273I-292J273D01*
G02X1115436I1096J1027D01*
G37*
G36*
G01X934728D02*
G03Y513727I292J-273D01*
G02X932536I-1096J-1027D01*
G03Y514273I-292J273D01*
G02X934728I1096J1027D01*
G37*
G36*
G01X897917D02*
G03Y513727I292J-273D01*
G02X895725I-1096J-1027D01*
G03Y514273I-292J273D01*
G02X897917I1096J1027D01*
G37*
G36*
G01X861106D02*
G03Y513727I292J-273D01*
G02X858914I-1096J-1027D01*
G03Y514273I-292J273D01*
G02X861106I1096J1027D01*
G37*
G36*
G01X824295D02*
G03Y513727I292J-273D01*
G02X822103I-1096J-1027D01*
G03Y514273I-292J273D01*
G02X824295I1096J1027D01*
G37*
G36*
G01X787484D02*
G03Y513727I292J-273D01*
G02X785292I-1096J-1027D01*
G03Y514273I-292J273D01*
G02X787484I1096J1027D01*
G37*
G36*
G01X576262D02*
G03Y513727I292J-273D01*
G02X574070I-1096J-1027D01*
G03Y514273I-292J273D01*
G02X576262I1096J1027D01*
G37*
G36*
G01X539451D02*
G03Y513727I292J-273D01*
G02X537259I-1096J-1027D01*
G03Y514273I-292J273D01*
G02X539451I1096J1027D01*
G37*
G36*
G01X502640D02*
G03Y513727I292J-273D01*
G02X500448I-1096J-1027D01*
G03Y514273I-292J273D01*
G02X502640I1096J1027D01*
G37*
G36*
G01X465828D02*
G03Y513727I292J-273D01*
G02X463636I-1096J-1027D01*
G03Y514273I-292J273D01*
G02X465828I1096J1027D01*
G37*
G36*
G01X285120D02*
G03Y513727I292J-273D01*
G02X282928I-1096J-1027D01*
G03Y514273I-292J273D01*
G02X285120I1096J1027D01*
G37*
G36*
G01X248309D02*
G03Y513727I292J-273D01*
G02X246117I-1096J-1027D01*
G03Y514273I-292J273D01*
G02X248309I1096J1027D01*
G37*
G36*
G01X211498D02*
G03Y513727I292J-273D01*
G02X209306I-1096J-1027D01*
G03Y514273I-292J273D01*
G02X211498I1096J1027D01*
G37*
G36*
G01X174687D02*
G03Y513727I292J-273D01*
G02X172495I-1096J-1027D01*
G03Y514273I-292J273D01*
G02X174687I1096J1027D01*
G37*
G36*
G01X137876D02*
G03Y513727I292J-273D01*
G02X135684I-1096J-1027D01*
G03Y514273I-292J273D01*
G02X137876I1096J1027D01*
G37*
G36*
G01X1460011Y514043D02*
G03X1459949Y513438I227J-329D01*
G02X1458137Y513623I-1014J-968D01*
G03X1458199Y514228I-227J329D01*
G02X1460186Y516206I1014J968D01*
G03X1460740I277J288D01*
G02Y514186I973J-1010D01*
G03X1460186I-277J-288D01*
G02X1460011Y514043I-972J1011D01*
G37*
G36*
G01X730626Y510592D02*
G03X730049Y510570I-278J-288D01*
G02X729974Y512508I-1049J930D01*
G03X730551Y512530I278J288D01*
G02X730626Y510592I1049J-930D01*
G37*
G36*
G01X1506985Y512146D02*
X1509546D01*
X1509549Y512147D01*
G02Y509143I36J-1502D01*
G01X1509546Y509144D01*
X1506984D01*
G02X1506985Y512146I1J1501D01*
G37*
G36*
G01X1614027Y509290D02*
G03X1613473I-277J-288D01*
G02Y511310I-973J1010D01*
G03X1614027I277J288D01*
G02Y509290I973J-1010D01*
G37*
G36*
G01X1549341Y510717D02*
G03X1549325Y510156I277J-289D01*
G02X1547275I-1025J-956D01*
G03X1547259Y510717I-293J272D01*
G02X1549341I1041J1083D01*
G37*
G36*
G01X721845Y510766D02*
G03X722033Y510244I365J-163D01*
G02X720134Y509558I-619J-1258D01*
G03X719946Y510080I-365J163D01*
G02X721845Y510766I619J1258D01*
G37*
G36*
G01X1498277Y509740D02*
X1500838D01*
X1500841Y509741D01*
G02Y506737I36J-1502D01*
G01X1500838Y506738D01*
X1498276D01*
G02X1498277Y509740I1J1501D01*
G37*
G36*
G01X1485692Y509502D02*
X1488293D01*
G02X1489794Y508010I0J-1501D01*
G01Y507915D01*
X1489785Y507831D01*
G02X1488293Y506498I-1492J168D01*
G01X1485692D01*
G02Y509502I0J1502D01*
G37*
G36*
G01X1481975Y506474D02*
X1479374D01*
G02X1479375Y509476I1J1501D01*
G01X1481975D01*
G02X1483476Y507985I0J-1501D01*
G01Y507890D01*
X1483467Y507806D01*
G02X1481975Y506474I-1492J169D01*
G37*
G36*
G01X115452Y509327D02*
G03Y508773I288J-277D01*
G02X113432I-1010J-973D01*
G03Y509327I-288J277D01*
G02X115452I1010J973D01*
G37*
G36*
G01X1844304Y507840D02*
G03X1843851Y507461I-54J-396D01*
G02X1842636Y508910I-1401J59D01*
G03X1843089Y509289I54J396D01*
G02X1844304Y507840I1401J-59D01*
G37*
G36*
G01X34223Y509289D02*
G03X34058Y509518I-197J32D01*
G02X33490Y509735I241J1482D01*
G03X32964Y509651I-216J-337D01*
G02X32610Y511865I-1164J949D01*
G03X33136Y511949I216J337D01*
G02X35288Y512131I1164J-949D01*
G03X35856Y512173I263J301D01*
G02X38495Y511340I1144J-973D01*
G03X38958Y510982I399J37D01*
G02X39428Y508015I241J-1483D01*
G03X39092Y507574I61J-395D01*
G02X36111Y507205I-1492J-174D01*
G03X35713Y507553I-397J-52D01*
G02X34223Y509289I-6J1502D01*
G37*
G36*
G01X1556448Y508744D02*
G03Y508190I288J-277D01*
G02X1554428I-1010J-973D01*
G03Y508744I-288J277D01*
G02X1556448I1010J973D01*
G37*
G36*
G01X1543516Y508517D02*
G03X1543500Y507956I277J-289D01*
G02X1541450I-1025J-956D01*
G03X1541434Y508517I-293J272D01*
G02X1543516I1041J1083D01*
G37*
G36*
G01X764960Y507567D02*
G03Y507013I288J-277D01*
G02X762940I-1010J-973D01*
G03Y507567I-288J277D01*
G02Y509513I1010J973D01*
G03Y510067I-288J277D01*
G02X764960I1010J973D01*
G03Y509513I288J-277D01*
G02Y507567I-1010J-973D01*
G37*
G36*
G01X703409Y505754D02*
G03X702898Y505399I-112J-384D01*
G02X701891Y506846I-1398J101D01*
G03X702402Y507201I112J384D01*
G02X703409Y505754I1398J-101D01*
G37*
G36*
G01X712207Y504510D02*
G03X711639I-284J-282D01*
G02X709492Y504695I-997J986D01*
G03X708872Y504741I-329J-228D01*
G02X709001Y506501I-1022J960D01*
G03X709621Y506455I329J228D01*
G02X711636Y506486I1022J-959D01*
G03X712204I284J282D01*
G02X714199Y506484I997J-986D01*
G03X714798Y506517I285J280D01*
G02X714901Y504666I1102J-867D01*
G03X714302Y504633I-285J-280D01*
G02X712207Y504510I-1102J867D01*
G37*
G36*
G01X1650037Y503846D02*
G03X1649482Y503744I-226J-330D01*
G02X1648998Y505777I-1152J800D01*
G03X1649539Y505936I191J351D01*
G02X1650037Y503846I1405J-770D01*
G37*
G36*
G01X1568662Y504677D02*
G03X1569135Y505096I74J393D01*
G02X1570261Y502751I3463J220D01*
G03X1569638Y502643I-270J-296D01*
G02X1568662Y504677I-1238J657D01*
G37*
G36*
G01X1508625Y504540D02*
X1511126D01*
G02X1512628Y503048I0J-1502D01*
G01Y503038D01*
G02X1511126Y501536I-1502J0D01*
G01X1508625D01*
G02Y504540I0J1502D01*
G37*
G36*
G01X1549310Y503027D02*
G03Y502473I288J-277D01*
G02X1547290I-1010J-973D01*
G03Y503027I-288J277D01*
G02X1549310I1010J973D01*
G37*
G36*
G01X1528002Y503810D02*
Y501300D01*
G02X1524998I-1502J0D01*
G01Y503801D01*
G02X1528002Y503810I1502J-1D01*
G37*
G36*
G01X675626Y500292D02*
G03X675049Y500270I-278J-288D01*
G02X672987Y500231I-1049J930D01*
G03X672432Y500253I-289J-277D01*
G02X672513Y502269I-932J1047D01*
G03X673068Y502247I289J277D01*
G02X674974Y502208I932J-1047D01*
G03X675551Y502230I278J288D01*
G02X675626Y500292I1049J-930D01*
G37*
G36*
G01X1738703Y502186D02*
G03X1738508Y501612I149J-371D01*
G02X1736777Y502201I-1208J-712D01*
G03X1736972Y502775I-149J371D01*
G02X1738703Y502186I1208J712D01*
G37*
G36*
G01X1874950Y501383D02*
G03X1875469Y501146I376J136D01*
G02X1874655Y499359I504J-1308D01*
G03X1874136Y499596I-376J-136D01*
G02X1874950Y501383I-504J1308D01*
G37*
G36*
G01X648006Y500173D02*
G03X647601Y499757I-5J-400D01*
G02X646219Y501102I-1401J-57D01*
G03X646624Y501518I5J400D01*
G02X648006Y500173I1401J57D01*
G37*
G36*
G01X1269329Y500380D02*
G03X1268968Y499918I34J-398D01*
G02X1267464Y501091I-1384J-224D01*
G03X1267825Y501553I-34J398D01*
G02X1269329Y500380I1384J224D01*
G37*
G36*
G01X745051Y498664D02*
G03X744497I-277J-288D01*
G02X742514Y500647I-973J1010D01*
G03Y501201I-288J277D01*
G02X744497Y503184I1010J973D01*
G03X745051I277J288D01*
G02X746997I973J-1010D01*
G03X747551I277J288D01*
G02X749401Y501080I973J-1010D01*
G03Y500768I125J-156D01*
G02X749485Y500695I-877J-1094D01*
G03X749786Y500725I138J145D01*
G02X750099Y498788I1145J-809D01*
G03X749564Y498734I-238J-322D01*
G02X747551Y498664I-1040J940D01*
G03X746997I-277J-288D01*
G02X745051I-973J1010D01*
G37*
G36*
G01X1532695Y501067D02*
G03Y500513I288J-277D01*
G02X1530675I-1010J-973D01*
G03Y501067I-288J277D01*
G02X1532695I1010J973D01*
G37*
G36*
G01X1556520Y501002D02*
G03Y500448I288J-277D01*
G02X1554500I-1010J-973D01*
G03Y501002I-288J277D01*
G02X1556520I1010J973D01*
G37*
G36*
G01X1543485Y500927D02*
G03Y500373I288J-277D01*
G02X1541465I-1010J-973D01*
G03Y500927I-288J277D01*
G02X1543485I1010J973D01*
G37*
G36*
G01X710341Y498494D02*
G03X709755Y498476I-285J-281D01*
G02X709698Y500384I-1055J923D01*
G03X710284Y500402I285J281D01*
G02X710341Y498494I1055J-923D01*
G37*
G36*
G01X1336011Y498417D02*
G03X1335389I-311J-252D01*
G02Y500183I-1089J883D01*
G03X1336011I311J252D01*
G02Y498417I1089J-883D01*
G37*
G36*
G01X1705728Y500548D02*
G03X1705739Y499999I296J-269D01*
G02X1703425Y497782I-1143J-1123D01*
G03X1702908Y497840I-292J-273D01*
G02X1700748Y500156I-903J1323D01*
G03X1700722Y500682I-314J248D01*
G02X1703017Y502917I1152J1113D01*
G03X1703551Y502884I285J280D01*
G02X1705728Y500548I993J-1257D01*
G37*
G36*
G01X-17651Y498430D02*
G03X-17666Y499031I-271J294D01*
G02X-15815Y499076I900J1075D01*
G03X-15800Y498475I271J-294D01*
G02X-17651Y498430I-900J-1075D01*
G37*
G36*
G01X1673481Y498725D02*
G03X1673416Y498165I250J-313D01*
G02X1671438Y498395I-1103J-865D01*
G03X1671503Y498955I-250J313D01*
G02X1673481Y498725I1103J865D01*
G37*
G36*
G01X113060Y499007D02*
G03X113164Y498418I314J-248D01*
G02X111328Y498095I-737J-1193D01*
G03X111224Y498684I-314J248D01*
G02X113060Y499007I737J1193D01*
G37*
G36*
G01X1758575Y494894D02*
X1753575D01*
G02Y497918I0J1512D01*
G01X1758575D01*
G02X1760086Y496416I-1J-1512D01*
G01Y496321D01*
X1760077Y496237D01*
G02X1758575Y494894I-1502J169D01*
G37*
G36*
G01X1748125Y494888D02*
X1743124D01*
G02X1743125Y497912I1J1512D01*
G01X1748125D01*
G02X1749636Y496410I-1J-1512D01*
G01Y496315D01*
X1749627Y496231D01*
G02X1748125Y494888I-1502J168D01*
G37*
G36*
G01X1157348Y495140D02*
G03Y494594I292J-273D01*
G02X1155156I-1096J-1027D01*
G03Y495140I-292J273D01*
G02X1157348I1096J1027D01*
G37*
G36*
G01X507740D02*
G03Y494594I292J-273D01*
G02X505548I-1096J-1027D01*
G03Y495140I-292J273D01*
G02X507740I1096J1027D01*
G37*
G36*
G01X1194121Y495143D02*
G03Y494575I282J-284D01*
G02X1192005I-1058J-1066D01*
G03Y495143I-282J284D01*
G02X1194121I1058J1066D01*
G37*
G36*
G01X544513D02*
G03Y494575I282J-284D01*
G02X542397I-1058J-1066D01*
G03Y495143I-282J284D01*
G02X544513I1058J1066D01*
G37*
G36*
G01X1152226Y495101D02*
G03Y494533I282J-284D01*
G02X1150110I-1058J-1066D01*
G03Y495101I-282J284D01*
G02X1152226I1058J1066D01*
G37*
G36*
G01X502618D02*
G03Y494533I282J-284D01*
G02X500502I-1058J-1066D01*
G03Y495101I-282J284D01*
G02X502618I1058J1066D01*
G37*
G36*
G01X939828Y494917D02*
G03Y494371I292J-273D01*
G02X937636I-1096J-1027D01*
G03Y494917I-292J273D01*
G02X939828I1096J1027D01*
G37*
G36*
G01X934743D02*
G03Y494371I292J-273D01*
G02X932551I-1096J-1027D01*
G03Y494917I-292J273D01*
G02X934743I1096J1027D01*
G37*
G36*
G01X290220D02*
G03Y494371I292J-273D01*
G02X288028I-1096J-1027D01*
G03Y494917I-292J273D01*
G02X290220I1096J1027D01*
G37*
G36*
G01X285135D02*
G03Y494371I292J-273D01*
G02X282943I-1096J-1027D01*
G03Y494917I-292J273D01*
G02X285135I1096J1027D01*
G37*
G36*
G01X1296341Y494226D02*
G03X1296927Y494180I314J248D01*
G02X1296777Y492283I951J-1030D01*
G03X1296191Y492329I-314J-248D01*
G02X1296341Y494226I-951J1030D01*
G37*
G36*
G01X903017Y494787D02*
G03Y494241I292J-273D01*
G02X900825I-1096J-1027D01*
G03Y494787I-292J273D01*
G02X903017I1096J1027D01*
G37*
G36*
G01X253409D02*
G03Y494241I292J-273D01*
G02X251217I-1096J-1027D01*
G03Y494787I-292J273D01*
G02X253409I1096J1027D01*
G37*
G36*
G01X1189036Y494843D02*
G03Y494275I282J-284D01*
G02X1186920I-1058J-1066D01*
G03Y494843I-282J284D01*
G02X1189036I1058J1066D01*
G37*
G36*
G01X897894D02*
G03Y494275I282J-284D01*
G02X895778I-1058J-1066D01*
G03Y494843I-282J284D01*
G02X897894I1058J1066D01*
G37*
G36*
G01X539428D02*
G03Y494275I282J-284D01*
G02X537312I-1058J-1066D01*
G03Y494843I-282J284D01*
G02X539428I1058J1066D01*
G37*
G36*
G01X248286D02*
G03Y494275I282J-284D01*
G02X246170I-1058J-1066D01*
G03Y494843I-282J284D01*
G02X248286I1058J1066D01*
G37*
G36*
G01X694614Y493330D02*
G03Y492776I288J-277D01*
G02X692594I-1010J-973D01*
G03Y493330I-288J277D01*
G02X694614I1010J973D01*
G37*
G36*
G01X690835Y493282D02*
G03Y492728I288J-277D01*
G02X688815I-1010J-973D01*
G03Y493282I-288J277D01*
G02X690835I1010J973D01*
G37*
G36*
G01X1842089Y490529D02*
G03X1841511I-289J-277D01*
G02X1839529Y492511I-1011J971D01*
G03Y493089I-277J289D01*
G02X1841511Y495071I971J1011D01*
G03X1842089I289J277D01*
G02X1844071Y493089I1011J-971D01*
G03Y492511I277J-289D01*
G02X1842089Y490529I-971J-1011D01*
G37*
G36*
G01X89350Y490392D02*
G03X88830I-260J-304D01*
G02X86572Y492650I-1040J1218D01*
G03Y493170I-304J260D01*
G02X86592Y495274I1218J1041D01*
G03X86602Y495793I-299J265D01*
G02X86622Y497850I1238J1017D01*
G03Y498370I-304J260D01*
G02X88880Y500628I1218J1040D01*
G03X89400I260J304D01*
G02X91480I1040J-1218D01*
G03X92000I260J304D01*
G02X94080I1040J-1218D01*
G03X94600I260J304D01*
G02X96680I1040J-1218D01*
G03X97200I260J304D01*
G02X99458Y498370I1040J-1218D01*
G03Y497850I304J-260D01*
G02X97776Y495277I-1218J-1040D01*
G03X97283Y494758I-117J-383D01*
G02X94663Y493062I-1506J-545D01*
G03X94106Y493061I-278J-288D01*
G02X91834Y493101I-1116J1149D01*
G03X91546I-144J-139D01*
G02X91499Y493054I-1156J1109D01*
G03Y492766I139J-144D01*
G02X89350Y490392I-1109J-1156D01*
G37*
G36*
G01X1249880Y490086D02*
G03X1249721Y489554I196J-348D01*
G02X1247787Y490135I-1247J-641D01*
G03X1247946Y490667I-196J348D01*
G02X1249880Y490086I1247J641D01*
G37*
G36*
G01X1819124Y490442D02*
X1824125D01*
G02X1825636Y488940I-1J-1512D01*
G01Y488845D01*
X1825627Y488761D01*
G02X1824125Y487418I-1502J169D01*
G01X1819124D01*
G02Y490442I0J1512D01*
G37*
G36*
G01X1796124D02*
X1801125D01*
G02X1802636Y488940I-1J-1512D01*
G01Y488845D01*
X1802627Y488761D01*
G02X1801125Y487418I-1502J169D01*
G01X1796124D01*
G02Y490442I0J1512D01*
G37*
G36*
G01X1784524D02*
X1789525D01*
G02X1791036Y488940I-1J-1512D01*
G01Y488845D01*
X1791027Y488761D01*
G02X1789525Y487418I-1502J169D01*
G01X1784524D01*
G02Y490442I0J1512D01*
G37*
G36*
G01X1811975Y487218D02*
X1806975D01*
G02Y490242I0J1512D01*
G01X1811975D01*
G02X1813486Y488740I-1J-1512D01*
G01Y488645D01*
X1813477Y488561D01*
G02X1811975Y487218I-1502J169D01*
G37*
G36*
G01X1754300Y486344D02*
X1749299D01*
G02X1749300Y489366I1J1511D01*
G01X1754300D01*
G02X1755812Y487865I0J-1512D01*
G01Y487770D01*
X1755802Y487686D01*
G02X1754300Y486344I-1502J170D01*
G37*
G36*
G01X1741900Y486244D02*
X1736899D01*
G02X1736900Y489266I1J1511D01*
G01X1741900D01*
G02X1743412Y487765I0J-1512D01*
G01Y487670D01*
X1743402Y487586D01*
G02X1741900Y486244I-1502J170D01*
G37*
G36*
G01X1770325Y485844D02*
X1765324D01*
G02X1765325Y488866I1J1511D01*
G01X1770325D01*
G02X1771836Y487365I0J-1511D01*
G01Y487270D01*
X1771827Y487186D01*
G02X1770325Y485844I-1502J169D01*
G37*
G36*
G01X1450607Y488218D02*
G03X1451188Y488206I296J268D01*
G02X1451149Y486281I1000J-983D01*
G03X1450568Y486293I-296J-268D01*
G02X1450607Y488218I-1000J983D01*
G37*
G36*
G01X721807Y486893D02*
G03X721585Y486360I145J-373D01*
G02X719794Y487107I-1285J-560D01*
G03X720016Y487640I-145J373D01*
G02X721934Y489451I1285J560D01*
G03X722487Y489661I181J357D01*
G02X723159Y487897I1305J-513D01*
G03X722606Y487687I-181J-357D01*
G02X721807Y486893I-1304J514D01*
G37*
G36*
G01X676752Y484669D02*
G03X676148Y484662I-299J-266D01*
G02X676128Y486501I-1068J908D01*
G03X676732Y486508I299J266D01*
G02X678732Y486647I1068J-908D01*
G03X679287Y486669I266J299D01*
G02X679368Y484653I1013J-969D01*
G03X678813Y484631I-266J-299D01*
G02X676752Y484669I-1013J969D01*
G37*
G36*
G01X1841471Y486239D02*
G03Y485661I277J-289D01*
G02X1839529I-971J-1011D01*
G03Y486239I-277J289D01*
G02X1841471I971J1011D01*
G37*
G36*
G01X610478Y485035D02*
G03X611039Y485021I288J278D01*
G02X610992Y483025I961J-1021D01*
G03X610431Y483039I-288J-278D01*
G02X610478Y485035I-961J1021D01*
G37*
G36*
G01X709168Y482570D02*
G03X708585Y482538I-277J-289D01*
G02X708480Y484452I-1074J901D01*
G03X709063Y484484I277J289D01*
G02X709168Y482570I1074J-901D01*
G37*
G36*
G01X1652882Y483774D02*
G03X1652896Y483210I290J-275D01*
G02X1650911Y483164I-970J-1013D01*
G03X1650897Y483728I-290J275D01*
G02X1652882Y483774I970J1013D01*
G37*
G36*
G01X1616627Y480390D02*
G03X1616073I-277J-288D01*
G02Y482410I-973J1010D01*
G03X1616627I277J288D01*
G02Y480390I973J-1010D01*
G37*
G36*
G01X1672021Y482589D02*
G03Y482011I277J-289D01*
G02X1670079I-971J-1011D01*
G03Y482589I-277J289D01*
G02X1672021I971J1011D01*
G37*
G36*
G01X606268Y482376D02*
G03X606278Y481843I303J-261D01*
G02X604187Y481806I-1029J-952D01*
G03X604177Y482339I-303J261D01*
G02X606268Y482376I1029J952D01*
G37*
G36*
G01X1291510Y481727D02*
G03Y481173I288J-277D01*
G02X1289490I-1010J-973D01*
G03Y481727I-288J277D01*
G02X1291510I1010J973D01*
G37*
G36*
G01X1794975Y477788D02*
X1789974D01*
G02X1789975Y480812I1J1512D01*
G01X1794975D01*
G02X1796486Y479310I-1J-1512D01*
G01Y479215D01*
X1796477Y479131D01*
G02X1794975Y477788I-1502J168D01*
G37*
G36*
G01X658794Y478143D02*
G03X658229Y478136I-279J-287D01*
G02X658203Y480122I-1002J980D01*
G03X658768Y480129I279J287D01*
G02X660708Y480191I1002J-980D01*
G03X661243I267J297D01*
G02Y478107I938J-1042D01*
G03X660708I-268J-297D01*
G02X658794Y478143I-938J1042D01*
G37*
G36*
G01X1817375Y476808D02*
X1812375D01*
G02Y479832I0J1512D01*
G01X1817375D01*
G02X1818886Y478330I-1J-1512D01*
G01Y478235D01*
X1818877Y478151D01*
G02X1817375Y476808I-1502J169D01*
G37*
G36*
G01X1829967Y475416D02*
X1825297D01*
G02Y478438I0J1511D01*
G01X1829967D01*
G02X1831478Y476937I0J-1511D01*
G01Y476842D01*
X1831469Y476758D01*
G02X1829967Y475416I-1502J169D01*
G37*
G36*
G01X1766700Y474144D02*
X1761699D01*
G02X1761700Y477166I1J1511D01*
G01X1766700D01*
G02X1768212Y475665I0J-1512D01*
G01Y475570D01*
X1768202Y475486D01*
G02X1766700Y474144I-1502J170D01*
G37*
G36*
G01X15473Y476510D02*
G03X16027I277J288D01*
G02Y474490I973J-1010D01*
G03X15473I-277J-288D01*
G02X13549Y474470I-973J1010D01*
G03X12988Y474451I-271J-294D01*
G02X12923Y476447I-1016J966D01*
G03X13484Y476466I271J294D01*
G02X15473Y476510I1016J-966D01*
G37*
G36*
G01X1779300Y473544D02*
X1774299D01*
G02X1774300Y476566I1J1511D01*
G01X1779300D01*
G02X1780812Y475065I0J-1512D01*
G01Y474970D01*
X1780802Y474886D01*
G02X1779300Y473544I-1502J170D01*
G37*
G36*
G01X1806525Y472444D02*
X1801524D01*
G02X1801525Y475466I1J1511D01*
G01X1806525D01*
G02X1808036Y473965I0J-1511D01*
G01Y473870D01*
X1808027Y473786D01*
G02X1806525Y472444I-1502J169D01*
G37*
G36*
G01X-13140Y474769D02*
G03X-12540I300J265D01*
G02Y472911I1050J-929D01*
G03X-13140I-300J-265D01*
G02Y474769I-1050J929D01*
G37*
G36*
G01X1679576Y472270D02*
G03X1679022Y472244I-263J-301D01*
G02X1678925Y474260I-1021J961D01*
G03X1679479Y474286I263J301D01*
G02X1679576Y472270I1021J-961D01*
G37*
G36*
G01X1895789Y469229D02*
G03X1895211I-289J-277D01*
G02X1893117Y471090I-1011J971D01*
G03X1893095Y471623I-309J254D01*
G02X1895111Y473571I1005J977D01*
G03X1895689I289J277D01*
G02X1897634Y473646I1011J-971D01*
G03X1898166I266J298D01*
G02X1900111Y473571I934J-1046D01*
G03X1900689I289J277D01*
G02X1902632Y473647I1011J-971D01*
G03X1903187Y473669I266J299D01*
G02X1905283Y471810I1013J-969D01*
G03X1905305Y471277I309J-254D01*
G02X1903368Y469253I-1005J-977D01*
G03X1902813Y469231I-266J-299D01*
G02X1900789Y469229I-1013J969D01*
G03X1900211I-289J-277D01*
G02X1898266Y469154I-1011J971D01*
G03X1897734I-266J-298D01*
G02X1895789Y469229I-934J1046D01*
G37*
G36*
G01X1634422Y471660D02*
G03X1634365Y471124I265J-299D01*
G02X1632012Y471373I-1290J-950D01*
G03X1632069Y471909I-265J299D01*
G02X1634422Y471660I1290J950D01*
G37*
G36*
G01X1915424Y468001D02*
G03X1916048I312J250D01*
G02X1916047Y465998I1250J-1002D01*
G03X1915423I-312J-250D01*
G02X1912903Y466023I-1250J1002D01*
G03X1912269I-317J-243D01*
G02Y467977I-1270J977D01*
G03X1912903I317J243D01*
G02X1915424Y468001I1270J-977D01*
G37*
G36*
G01X1463389Y464529D02*
G03X1462811I-289J-277D01*
G02Y466471I-1011J971D01*
G03X1463389I289J277D01*
G02Y464529I1011J-971D01*
G37*
G36*
G01X1455589D02*
G03X1455011I-289J-277D01*
G02Y466471I-1011J971D01*
G03X1455589I289J277D01*
G02Y464529I1011J-971D01*
G37*
G36*
G01X1667496Y465448D02*
G03X1667236Y465939I-384J111D01*
G02X1666657Y466306I438J1332D01*
G03X1666074Y466303I-290J-276D01*
G02X1666064Y468222I-1027J954D01*
G03X1666647Y468225I290J276D01*
G02X1669021Y466883I1027J-954D01*
G03X1669281Y466392I384J-111D01*
G02X1667496Y465448I-438J-1332D01*
G37*
G36*
G01X1322493Y464943D02*
G03X1323080Y464737I377J134D01*
G02X1322494Y463074I735J-1194D01*
G03X1321907Y463280I-377J-134D01*
G02X1322493Y464943I-735J1194D01*
G37*
G36*
G01X1343133Y462606D02*
G03X1342564Y462583I-273J-292D01*
G02X1342485Y464552I-1036J945D01*
G03X1343054Y464575I273J292D01*
G02X1345126I1036J-945D01*
G03X1345714Y464571I296J269D01*
G02X1345703Y462670I1025J-956D01*
G03X1345115Y462674I-296J-269D01*
G02X1343133Y462606I-1025J956D01*
G37*
G36*
G01X1624247Y462902D02*
G03X1624014Y462389I142J-374D01*
G02X1622202Y463211I-1314J-489D01*
G03X1622435Y463724I-142J374D01*
G02X1624247Y462902I1314J489D01*
G37*
G36*
G01X1586502Y459200D02*
G03X1585948I-277J-288D01*
G02X1583863Y459356I-973J1010D01*
G03X1583247Y459378I-317J-244D01*
G02X1580798Y460293I-1047J932D01*
G03X1580392Y460688I-400J-5D01*
G02X1581772Y462107I-22J1402D01*
G03X1582178Y461712I400J5D01*
G02X1582413Y461696I23J-1402D01*
G03X1582857Y462206I61J395D01*
G02X1585455Y461984I1343J404D01*
G03X1585627Y461451I358J-179D01*
G02X1585948Y461220I-650J-1242D01*
G03X1586502I277J288D01*
G02Y459200I973J-1010D01*
G37*
G36*
G01X1463389Y458829D02*
G03X1462811I-289J-277D01*
G02Y460771I-1011J971D01*
G03X1463389I289J277D01*
G02Y458829I1011J-971D01*
G37*
G36*
G01X1455589D02*
G03X1455011I-289J-277D01*
G02Y460771I-1011J971D01*
G03X1455589I289J277D01*
G02Y458829I1011J-971D01*
G37*
G36*
G01X1640942Y458579D02*
G03X1640920Y457958I241J-319D01*
G02X1639158Y458021I-920J-1058D01*
G03X1639180Y458642I-241J319D01*
G02X1640942Y458579I920J1058D01*
G37*
G36*
G01X1685410Y458414D02*
G03Y457839I279J-288D01*
G02X1683460I-975J-1007D01*
G03Y458414I-279J287D01*
G02X1685410I975J1007D01*
G37*
G36*
G01X1676848Y457738D02*
G03X1676782Y457142I230J-327D01*
G02X1674937Y457346I-1038J-942D01*
G03X1675003Y457942I-230J327D01*
G02X1676848Y457738I1038J942D01*
G37*
G36*
G01X1529333Y455957D02*
G03X1529260Y455398I245J-316D01*
G02X1527289Y455655I-1113J-852D01*
G03X1527362Y456214I-245J316D01*
G02X1529333Y455957I1113J852D01*
G37*
G36*
G01X1463389Y453129D02*
G03X1462811I-289J-277D01*
G02Y455071I-1011J971D01*
G03X1463389I289J277D01*
G02Y453129I1011J-971D01*
G37*
G36*
G01X1455589D02*
G03X1455011I-289J-277D01*
G02Y455071I-1011J971D01*
G03X1455589I289J277D01*
G02Y453129I1011J-971D01*
G37*
G36*
G01X1411986Y457571D02*
Y453476D01*
X1411977Y453392D01*
G02X1408964Y453561I-1502J169D01*
G01Y457561D01*
G02X1411986Y457571I1511J0D01*
G37*
G36*
G01X1404286D02*
Y453476D01*
X1404277Y453392D01*
G02X1401264Y453561I-1502J169D01*
G01Y457561D01*
G02X1404286Y457571I1511J0D01*
G37*
G36*
G01X1396886D02*
Y453476D01*
X1396877Y453392D01*
G02X1393864Y453561I-1502J169D01*
G01Y457562D01*
G02X1396886Y457571I1511J-1D01*
G37*
G36*
G01X1589693Y453068D02*
G03X1590295Y453064I303J261D01*
G02X1590283Y451217I1049J-930D01*
G03X1589681Y451221I-303J-261D01*
G02X1587504Y451319I-1049J930D01*
G03X1586902Y451367I-322J-238D01*
G02X1584927Y451378I-982J1001D01*
G03X1584325Y451338I-284J-282D01*
G02X1584201Y453175I-1117J847D01*
G03X1584803Y453215I284J282D01*
G02X1587048Y453200I1117J-847D01*
G03X1587650Y453152I322J238D01*
G02X1589693Y453068I982J-1001D01*
G37*
G36*
G01X1620175Y453672D02*
G03X1620664Y453361I393J77D01*
G02X1619625Y451728I336J-1361D01*
G03X1619136Y452039I-393J-77D01*
G02X1620175Y453672I-336J1361D01*
G37*
G36*
G01X1662542Y452789D02*
G03X1662548Y452234I291J-274D01*
G02X1660529Y452213I-999J-983D01*
G03X1660523Y452768I-291J274D01*
G02X1660492Y454703I999J984D01*
G03X1660481Y455257I-294J271D01*
G02X1662500Y455299I989J994D01*
G03X1662511Y454745I294J-271D01*
G02X1662542Y452789I-989J-994D01*
G37*
G36*
G01X1867886Y451591D02*
G03X1867450Y451172I-36J-398D01*
G02X1866179Y452496I-1400J-72D01*
G03X1866615Y452915I36J398D01*
G02X1869093Y453883I1400J72D01*
G03X1869715Y453891I308J256D01*
G02X1869737Y452126I1100J-869D01*
G03X1869115Y452118I-308J-256D01*
G02X1867886Y451591I-1100J869D01*
G37*
G36*
G01X1836495Y449088D02*
X1831494D01*
G02X1831495Y452112I1J1512D01*
G01X1836495D01*
G02X1838006Y450610I-1J-1512D01*
G01Y450515D01*
X1837997Y450431D01*
G02X1836495Y449088I-1502J168D01*
G37*
G36*
G01X1818760Y451920D02*
X1823760D01*
G02X1825272Y450418I0J-1512D01*
G01Y450323D01*
X1825262Y450239D01*
G02X1823760Y448896I-1502J169D01*
G01X1818760D01*
G02Y451920I0J1512D01*
G37*
G36*
G01X1811161Y448896D02*
X1806161D01*
G02Y451920I0J1512D01*
G01X1811161D01*
G02X1812672Y450418I-1J-1512D01*
G01Y450323D01*
X1812663Y450239D01*
G02X1811161Y448896I-1502J169D01*
G37*
G36*
G01X1793562Y451920D02*
X1798563D01*
G02X1800074Y450418I-1J-1512D01*
G01Y450323D01*
X1800065Y450239D01*
G02X1798563Y448896I-1502J169D01*
G01X1793562D01*
G02Y451920I1J1512D01*
G37*
G36*
G01X1780963D02*
X1785964D01*
G02X1787476Y450418I0J-1512D01*
G01Y450323D01*
X1787466Y450239D01*
G02X1785964Y448896I-1502J168D01*
G01X1780963D01*
G02Y451920I0J1512D01*
G37*
G36*
G01X1768366D02*
X1773366D01*
G02X1774878Y450418I0J-1512D01*
G01Y450323D01*
X1774868Y450239D01*
G02X1773366Y448896I-1502J169D01*
G01X1768366D01*
G02Y451920I0J1512D01*
G37*
G36*
G01X1760767Y448896D02*
X1755767D01*
G02Y451920I0J1512D01*
G01X1760767D01*
G02X1762278Y450418I-1J-1512D01*
G01Y450323D01*
X1762269Y450239D01*
G02X1760767Y448896I-1502J169D01*
G37*
G36*
G01X1748169D02*
X1743169D01*
G02Y451920I0J1512D01*
G01X1748169D01*
G02X1749680Y450418I-1J-1512D01*
G01Y450323D01*
X1749671Y450239D01*
G02X1748169Y448896I-1502J169D01*
G37*
G36*
G01X1470989Y449026D02*
G03X1470411I-289J-277D01*
G02Y450968I-1011J971D01*
G03X1470989I289J277D01*
G02Y449026I1011J-971D01*
G37*
G36*
G01X1463189D02*
G03X1462611I-289J-277D01*
G02Y450968I-1011J971D01*
G03X1463189I289J277D01*
G02Y449026I1011J-971D01*
G37*
G36*
G01X1631268Y451086D02*
G03X1631263Y450513I277J-289D01*
G02X1629308Y450531I-987J-996D01*
G03X1629313Y451104I-277J289D01*
G02X1629282Y453064I987J996D01*
G03X1629260Y453635I-291J275D01*
G02X1629190Y455648I940J1040D01*
G03Y456202I-288J277D01*
G02X1631210I1010J973D01*
G03Y455648I288J-277D01*
G02X1631218Y453711I-1010J-973D01*
G03X1631240Y453140I291J-275D01*
G02X1631268Y451086I-940J-1040D01*
G37*
G36*
G01X1682201Y450789D02*
G03X1682187Y450234I281J-285D01*
G02X1680168Y450283I-1033J-948D01*
G03X1680182Y450838I-281J285D01*
G02X1682201Y450789I1033J948D01*
G37*
G36*
G01X1873831Y449539D02*
G03Y448961I277J-289D01*
G02X1871889I-971J-1011D01*
G03Y449539I-277J289D01*
G02X1873831I971J1011D01*
G37*
G36*
G01X1887937Y446834D02*
G03X1887409Y446826I-259J-304D01*
G02X1887369Y449230I-1079J1184D01*
G03X1887897Y449238I259J304D01*
G02X1890236Y449043I1079J-1184D01*
G03X1890866I315J247D01*
G02X1893386I1260J-989D01*
G03X1894015I315J247D01*
G02Y447065I1260J-989D01*
G03X1893386I-314J-247D01*
G02X1890866I-1260J989D01*
G03X1890236I-315J-247D01*
G02X1887937Y446834I-1260J989D01*
G37*
G36*
G01X1647500Y449140D02*
G03X1647513Y448585I294J-271D01*
G02X1645494Y448540I-988J-995D01*
G03X1645481Y449095I-294J271D01*
G02X1645452Y451055I988J995D01*
G03X1645448Y451610I-290J275D01*
G02X1647468Y451625I1003J980D01*
G03X1647472Y451070I290J-275D01*
G02X1647500Y449140I-1003J-980D01*
G37*
G36*
G01X1677288Y448795D02*
G03X1677284Y448229I281J-285D01*
G02X1675303Y448243I-998J-985D01*
G03X1675307Y448809I-281J285D01*
G02X1677288Y448795I998J985D01*
G37*
G36*
G01X1674076Y447548D02*
G03X1674075Y446993I288J-278D01*
G02X1672056Y446996I-1011J-971D01*
G03X1672057Y447551I-288J278D01*
G02X1674076Y447548I1011J971D01*
G37*
G36*
G01X-719Y455008D02*
G03X-446Y455489I-115J383D01*
G02X2653Y455455I1554J390D01*
G03X2899Y454974I386J-106D01*
G02X3557Y452433I-560J-1501D01*
G03Y451913I304J-260D01*
G02Y449833I-1218J-1040D01*
G03Y449313I304J-260D01*
G02Y447233I-1218J-1040D01*
G03Y446713I304J-260D01*
G02X1299Y444455I-1218J-1040D01*
G03X779I-260J-304D01*
G02X-1479Y446713I-1040J1218D01*
G03Y447233I-304J260D01*
G02Y449313I1218J1040D01*
G03Y449833I-304J260D01*
G02Y451913I1218J1040D01*
G03Y452433I-304J260D01*
G02X-719Y455008I1218J1040D01*
G37*
G36*
G01X6783Y448093D02*
G03X7303I260J304D01*
G02X9791Y447561I1040J-1218D01*
G03X10362Y447392I361J171D01*
G02X9895Y445483I738J-1192D01*
G03X9310Y445598I-344J-204D01*
G02X7187Y445766I-967J1277D01*
G03X6899I-144J-139D01*
G02X6852Y445719I-1156J1109D01*
G03Y445431I139J-144D01*
G02X4525Y445315I-1109J-1156D01*
G03Y445835I-304J260D01*
G02X6783Y448093I1218J1040D01*
G37*
G36*
G01X1670826Y445480D02*
G03Y444926I288J-277D01*
G02X1668806I-1010J-973D01*
G03Y445480I-288J277D01*
G02Y447426I1010J973D01*
G03Y447980I-288J277D01*
G02X1670826I1010J973D01*
G03Y447426I288J-277D01*
G02Y445480I-1010J-973D01*
G37*
G36*
G01X1718140Y442709D02*
G03X1717978Y443287I-335J218D01*
G02X1717595Y443559I609J1263D01*
G03X1717029I-283J-282D01*
G02Y445541I-992J991D01*
G03X1717595I283J282D01*
G02X1719764Y443788I992J-991D01*
G03X1719926Y443210I335J-218D01*
G02X1718140Y442709I-609J-1263D01*
G37*
G36*
G01X10786Y443296D02*
X15787D01*
G02X17298Y441795I0J-1512D01*
G01Y441700D01*
X17288Y441616D01*
G02X15786Y440274I-1502J170D01*
G01X10786D01*
G02Y443296I0J1511D01*
G37*
G36*
G01X1413300Y442491D02*
G03X1413324Y441870I264J-301D01*
G02X1411559Y441802I-841J-1122D01*
G03X1411535Y442423I-264J301D01*
G02X1413300Y442491I841J1122D01*
G37*
G36*
G01X1589900Y441497D02*
G03X1590472Y441480I294J271D01*
G02X1590416Y439521I974J-1008D01*
G03X1589844Y439538I-294J-271D01*
G02X1589900Y441497I-974J1008D01*
G37*
G36*
G01X1613207Y441666D02*
G03X1613223Y441103I292J-273D01*
G02X1611232Y441045I-967J-1015D01*
G03X1611216Y441608I-292J273D01*
G02X1613207Y441666I967J1015D01*
G37*
G36*
G01X22936Y444354D02*
G02X25958Y444364I1511J0D01*
G01Y439354D01*
X25959D01*
X25958Y439269D01*
X25949Y439185D01*
G02X22936Y439354I-1502J169D01*
G01Y444354D01*
G37*
G36*
G01X750525Y439327D02*
G03X749900Y438975I-226J-330D01*
G02X747401Y439770I-1400J-75D01*
G03X747278Y440369I-314J248D01*
G02X748440Y442914I672J1231D01*
G03X748971Y443205I140J375D01*
G02X750525Y439327I3670J-780D01*
G37*
G36*
G01X1409123Y439924D02*
G03Y439309I257J-307D01*
G02X1407327I-898J-1076D01*
G03Y439924I-257J307D01*
G02X1409123I898J1076D01*
G37*
G36*
G01X1506427Y436187D02*
G03X1506443Y435632I296J-269D01*
G02X1504427Y435576I-981J-1002D01*
G03X1504411Y436131I-296J269D01*
G02X1506427Y436187I981J1002D01*
G37*
G36*
G01X1640510Y434727D02*
G03Y434173I288J-277D01*
G02X1638490I-1010J-973D01*
G03Y434727I-288J277D01*
G02X1640510I1010J973D01*
G37*
G36*
G01X1461099Y431902D02*
G03X1460510I-294J-271D01*
G02Y433800I-1032J949D01*
G03X1461099I295J271D01*
G02Y431902I1032J-949D01*
G37*
G36*
G01X1468386Y433869D02*
G03X1468958Y433852I294J271D01*
G02X1468900Y431892I973J-1010D01*
G03X1468328Y431909I-294J-271D01*
G02X1468386Y433869I-973J1010D01*
G37*
G36*
G01X1588351Y433445D02*
G03X1588973Y433428I318J243D01*
G02X1588924Y431663I1064J-913D01*
G03X1588302Y431680I-318J-243D01*
G02X1588351Y433445I-1064J913D01*
G37*
G36*
G01X1410812Y434785D02*
Y429690D01*
X1410802Y429606D01*
G02X1407788Y429775I-1502J169D01*
G01Y434776D01*
G02X1410812Y434785I1512J-1D01*
G37*
G36*
G01X1402910D02*
Y429690D01*
X1402900Y429606D01*
G02X1399886Y429775I-1502J169D01*
G01Y434776D01*
G02X1402910Y434785I1512J-1D01*
G37*
G36*
G01X1468885Y427046D02*
G03X1468305I-290J-276D01*
G02Y428980I-1015J967D01*
G03X1468885I290J276D01*
G02Y427046I1015J-967D01*
G37*
G36*
G01X1548776Y429391D02*
G03Y428844I292J-274D01*
G02X1546732I-1022J-960D01*
G03Y429391I-292J274D01*
G02X1548097Y431710I1022J960D01*
G03X1548579Y431986I98J388D01*
G02X1549582Y430235I1346J-392D01*
G03X1549100Y429959I-98J-388D01*
G02X1548776Y429391I-1346J392D01*
G37*
G36*
G01X1583820Y426607D02*
G03X1583311Y426307I-118J-382D01*
G02X1582352Y427934I-1372J287D01*
G03X1582861Y428234I118J382D01*
G02X1583820Y426607I1372J-287D01*
G37*
G36*
G01X17025Y423338D02*
X12024D01*
G02X12025Y426362I1J1512D01*
G01X17025D01*
G02X18536Y424860I-1J-1512D01*
G01Y424765D01*
X18527Y424681D01*
G02X17025Y423338I-1502J168D01*
G37*
G36*
G01X7025D02*
X2024D01*
G02X2025Y426362I1J1512D01*
G01X7025D01*
G02X8536Y424860I-1J-1512D01*
G01Y424765D01*
X8527Y424681D01*
G02X7025Y423338I-1502J168D01*
G37*
G36*
G01X62516Y424220D02*
X62507Y424136D01*
G02X59494Y424305I-1502J169D01*
G01Y429306D01*
G02X62516Y429315I1511J-1D01*
G01Y424220D01*
G37*
G36*
G01X1589368Y424272D02*
G03X1588961Y423864I-7J-400D01*
G02X1587587Y425237I-1402J-29D01*
G03X1587994Y425645I7J400D01*
G02X1589368Y424272I1402J29D01*
G37*
G36*
G01X1559675Y420042D02*
X1555775D01*
G02Y422866I0J1412D01*
G01X1559676D01*
G02X1561086Y421464I-1J-1412D01*
G01Y421370D01*
X1561076Y421286D01*
G02X1559675Y420042I-1401J167D01*
G37*
G36*
G01X1548790Y422624D02*
G03Y422084I295J-270D01*
G02X1546720I-1035J-946D01*
G03Y422624I-295J270D01*
G02X1548139Y424918I1035J946D01*
G03X1548629Y425181I109J385D01*
G02X1549580Y423405I1335J-428D01*
G03X1549090Y423142I-109J-385D01*
G02X1548790Y422624I-1335J427D01*
G37*
G36*
G01X1504996Y419784D02*
G03X1504478Y419514I-133J-377D01*
G02X1501738Y419711I-1350J378D01*
G03X1501304Y420058I-397J-51D01*
G02X1502565Y421635I-129J1396D01*
G03X1502999Y421288I397J51D01*
G02X1503591Y421215I128J-1396D01*
G03X1504109Y421485I133J377D01*
G02X1504508Y422137I1350J-378D01*
G03X1504541Y422692I-271J295D01*
G02X1506556Y422574I1064J912D01*
G03X1506523Y422019I271J-295D01*
G02X1504996Y419784I-1065J-912D01*
G37*
G36*
G01X50776Y424005D02*
Y418910D01*
X50767Y418826D01*
G02X47754Y418995I-1502J169D01*
G01Y423996D01*
G02X50776Y424005I1511J-1D01*
G37*
G36*
G01X1557725Y416662D02*
X1553824D01*
G02X1553825Y419486I1J1412D01*
G01X1554448D01*
G02X1554998Y418963I0J-551D01*
G03X1555016Y418813I777J17D01*
G02X1555159Y418507I-1189J-742D01*
G03X1556391I616J472D01*
G02X1556534Y418813I1332J-436D01*
G03X1556550Y419022I-759J163D01*
G02X1557050Y419486I500J-37D01*
G01X1557725D01*
G02X1559136Y418084I0J-1411D01*
G01Y417990D01*
X1559126Y417906D01*
G02X1557725Y416662I-1401J167D01*
G37*
G36*
G01X1413476Y416907D02*
X1413461Y417081D01*
X1413626Y421997D01*
X1413634Y422005D01*
X1413640Y422078D01*
G02X1416647Y422124I1506J-131D01*
G01X1416668Y421948D01*
X1416504Y417042D01*
X1416505D01*
X1416502Y416988D01*
X1416477Y416817D01*
G02X1413476Y416907I-1495J222D01*
G37*
G36*
G01X1405646Y421576D02*
G02X1408670Y421585I1512J-1D01*
G01Y416490D01*
X1408660Y416406D01*
G02X1405646Y416572I-1502J167D01*
G01Y421576D01*
G37*
G36*
G01X1567475Y413282D02*
X1563574D01*
G02X1563575Y416106I1J1412D01*
G01X1564198D01*
G02X1564748Y415583I0J-551D01*
G03X1564766Y415433I777J17D01*
G02X1564909Y415127I-1189J-742D01*
G03X1566141I616J472D01*
G02X1566284Y415433I1332J-436D01*
G03X1566300Y415642I-759J163D01*
G02X1566800Y416106I500J-37D01*
G01X1567475D01*
G02X1568886Y414704I0J-1411D01*
G01Y414610D01*
X1568876Y414526D01*
G02X1567475Y413282I-1401J167D01*
G37*
G36*
G01X767237Y416062D02*
G03X767281Y415483I296J-269D01*
G02X765357Y415340I-887J-1086D01*
G03X765313Y415919I-296J269D01*
G02X766261Y418406I887J1086D01*
G03X766678Y418800I17J399D01*
G02X768019Y417379I1402J-20D01*
G03X767602Y416985I-17J-399D01*
G02X767237Y416062I-1402J21D01*
G37*
G36*
G01X47006Y415201D02*
G03Y414590I258J-306D01*
G02X45194I-906J-1070D01*
G03Y415201I-258J305D01*
G02X47006I906J1070D01*
G37*
G36*
G01X1471147Y413091D02*
G03X1471720Y413069I297J268D01*
G02X1471647Y411116I968J-1014D01*
G03X1471074Y411138I-297J-268D01*
G02X1471147Y413091I-968J1014D01*
G37*
G36*
G01X1588551Y411003D02*
G03X1587996Y410990I-271J-295D01*
G02X1587949Y413008I-996J986D01*
G03X1588504Y413021I271J295D01*
G02X1588551Y411003I996J-986D01*
G37*
G36*
G01X120018Y413220D02*
G03X120037Y412643I286J-279D01*
G02X118098Y412581I-937J-1043D01*
G03X118079Y413158I-286J279D01*
G02X120018Y413220I937J1043D01*
G37*
G36*
G01X20473Y414391D02*
G03X21740Y414794I-2J2199D01*
G02X21756Y410156I1488J-2314D01*
G03X20502Y410569I-1283J-1786D01*
G01X20471D01*
G03X19204Y410166I2J-2199D01*
G02X19188Y414804I-1488J2314D01*
G03X20442Y414391I1283J1786D01*
G01X20473D01*
G37*
G36*
G01X3938D02*
G03X5205Y414794I-2J2199D01*
G02X5221Y410156I1488J-2314D01*
G03X3967Y410569I-1283J-1786D01*
G01X3936D01*
G03X2669Y410166I2J-2199D01*
G02X2653Y414804I-1488J2314D01*
G03X3907Y414391I1283J1786D01*
G01X3938D01*
G37*
G36*
G01X-12598D02*
G03X-11331Y414794I-2J2199D01*
G02X-11315Y410156I1488J-2314D01*
G03X-12569Y410569I-1283J-1786D01*
G01X-12599D01*
G03X-13866Y410166I2J-2199D01*
G02X-13882Y414804I-1488J2314D01*
G03X-12628Y414391I1283J1786D01*
G01X-12598D01*
G37*
G36*
G01X749612Y408828D02*
G03X749058I-277J-288D01*
G02X747075Y410811I-973J1010D01*
G03Y411365I-288J277D01*
G02X749058Y413348I1010J973D01*
G03X749612I277J288D01*
G02X751558I973J-1010D01*
G03X752112I277J288D01*
G02X753991Y413408I973J-1010D01*
G03X754524Y413422I259J305D01*
G02X755905Y413741I963J-1019D01*
G03X756424Y414133I119J382D01*
G02X758799Y415177I1402J34D01*
G03X759353I277J288D01*
G02X761303Y415172I972J-1010D01*
G03X761912Y415233I279J287D01*
G02X763960Y413358I1157J-793D01*
G03X763942Y412756I254J-309D01*
G02X761975Y410760I-953J-1028D01*
G03X761384Y410747I-290J-276D01*
G02X759353Y410657I-1058J920D01*
G03X758799I-277J-288D01*
G02X757408Y410329I-972J1010D01*
G03X756889Y409937I-119J-382D01*
G02X754581Y408833I-1402J-34D01*
G03X754048Y408819I-259J-305D01*
G02X752112Y408828I-963J1019D01*
G03X751558I-277J-288D01*
G02X749612I-973J1010D01*
G37*
G36*
G01X1403912Y408281D02*
Y413282D01*
G02X1406934Y413291I1511J-1D01*
G01Y408281D01*
X1406935D01*
X1406934Y408196D01*
X1406925Y408112D01*
G02X1403912Y408281I-1502J169D01*
G37*
G36*
G01X1571375Y406522D02*
X1567474D01*
G02X1567475Y409346I1J1412D01*
G01X1568098D01*
G02X1568648Y408823I0J-551D01*
G03X1568666Y408673I777J17D01*
G02X1568809Y408367I-1189J-742D01*
G03X1570041I616J472D01*
G02X1570184Y408673I1332J-436D01*
G03X1570200Y408882I-759J163D01*
G02X1570700Y409346I500J-37D01*
G01X1571375D01*
G02X1572786Y407944I0J-1411D01*
G01Y407850D01*
X1572776Y407766D01*
G02X1571375Y406522I-1401J167D01*
G37*
G36*
G01X1444049Y407876D02*
G03X1443955Y407308I227J-329D01*
G02X1442033Y407625I-1125J-836D01*
G03X1442127Y408193I-227J329D01*
G02X1444049Y407876I1125J836D01*
G37*
G36*
G01X106158Y407656D02*
G03X105910Y407071I100J-387D01*
G02X104120Y407831I-1393J-792D01*
G03X104368Y408416I-100J387D01*
G02X105975Y410796I1393J792D01*
G03X106425Y411249I54J396D01*
G02X107796Y409891I1585J230D01*
G03X107346Y409438I-54J-396D01*
G02X106158Y407656I-1585J-230D01*
G37*
G36*
G01X120709Y404984D02*
G03X120136Y405156I-363J-168D01*
G02X120670Y406937I-738J1192D01*
G03X121243Y406765I363J168D01*
G02X120709Y404984I738J-1192D01*
G37*
G36*
G01X53088Y406598D02*
X55227Y409137D01*
G02X57894Y408173I1156J-974D01*
G01Y408078D01*
X57885Y407994D01*
G02X57539Y407189I-1503J169D01*
G01X56228Y405632D01*
X56227D01*
X55422Y404678D01*
X55421Y404676D01*
G02X53088Y406598I-1177J948D01*
G37*
G36*
G01X1589833Y402984D02*
G03X1589253Y402806I-214J-338D01*
G02X1588716Y404554I-1285J562D01*
G03X1589296Y404732I214J338D01*
G02X1589833Y402984I1285J-562D01*
G37*
G36*
G01X25591Y406517D02*
G03X26858Y406920I-2J2199D01*
G02X26874Y402282I1488J-2314D01*
G03X25620Y402695I-1283J-1786D01*
G01X25590D01*
G03X24323Y402292I2J-2199D01*
G02X24307Y406930I-1488J2314D01*
G03X25561Y406517I1283J1786D01*
G01X25591D01*
G37*
G36*
G01X9056D02*
G03X10323Y406920I-2J2199D01*
G02X10339Y402282I1488J-2314D01*
G03X9085Y402695I-1283J-1786D01*
G01X9054D01*
G03X7787Y402292I2J-2199D01*
G02X7771Y406930I-1488J2314D01*
G03X9025Y406517I1283J1786D01*
G01X9056D01*
G37*
G36*
G01X-7480D02*
G03X-6213Y406920I-2J2199D01*
G02X-6197Y402282I1488J-2314D01*
G03X-7451Y402695I-1283J-1786D01*
G01X-7481D01*
G03X-8748Y402292I2J-2199D01*
G02X-8764Y406930I-1488J2314D01*
G03X-7510Y406517I1283J1786D01*
G01X-7480D01*
G37*
G36*
G01X66896Y403268D02*
Y403173D01*
X66886Y403089D01*
G02X64311Y402193I-1502J169D01*
G01X61973Y404550D01*
X61972Y404551D01*
G02X64097Y406701I1052J1085D01*
G01X65153Y405638D01*
X66457Y404323D01*
G02X66896Y403268I-1073J-1065D01*
G37*
G36*
G01X1383327Y397890D02*
G03X1382773I-277J-288D01*
G02X1380751Y399830I-973J1010D01*
G03X1380740Y400372I-299J265D01*
G02X1380658Y400466I1015J968D01*
G03X1380346I-156J-125D01*
G02X1378023Y400669I-1094J877D01*
G03X1377479Y400826I-350J-193D01*
G02X1375827Y401043I-679J1227D01*
G03X1375273I-277J-288D01*
G02Y403063I-973J1010D01*
G03X1375827I277J288D01*
G02X1378029Y402727I973J-1010D01*
G03X1378573Y402570I350J193D01*
G02X1380225Y402353I679J-1227D01*
G03X1380779I277J288D01*
G02X1382725I973J-1010D01*
G03X1383279I277J288D01*
G02X1385225I973J-1010D01*
G03X1385779I277J288D01*
G02X1387801Y400413I973J-1010D01*
G03X1387812Y399871I299J-265D01*
G02X1385827Y397890I-1012J-971D01*
G03X1385273I-277J-288D01*
G02X1383327I-973J1010D01*
G37*
G36*
G01X1586703Y396411D02*
G03X1586141Y396408I-279J-286D01*
G02X1586130Y398403I-991J992D01*
G03X1586692Y398406I279J286D01*
G02X1586703Y396411I991J-992D01*
G37*
G36*
G01X102620Y396017D02*
G03X102080I-270J-295D01*
G02X99817Y398280I-1080J1183D01*
G03Y398820I-295J270D01*
G02X102080Y401083I1183J1080D01*
G03X102620I270J295D01*
G02X104780I1080J-1183D01*
G03X105320I270J295D01*
G02X107480I1080J-1183D01*
G03X108020I270J295D01*
G02X110562Y400555I1080J-1183D01*
G03X111054Y400339I365J163D01*
G02X111173Y397265I507J-1520D01*
G03X110681Y396941I-97J-388D01*
G02X108020Y396017I-1581J259D01*
G03X107480I-270J-295D01*
G02X105320I-1080J1183D01*
G03X104780I-270J-295D01*
G02X102620I-1080J1183D01*
G37*
G36*
G01X1370996Y395697D02*
G03X1370418I-289J-277D01*
G02Y397639I-1011J971D01*
G03X1370996I289J277D01*
G02Y395697I1011J-971D01*
G37*
G36*
G01X1655811Y398206D02*
G03X1655831Y397649I297J-268D01*
G02X1653820Y397576I-970J-1012D01*
G03X1653800Y398133I-297J268D01*
G02X1653776Y400133I970J1012D01*
G03X1653784Y400688I-284J282D01*
G02X1655803Y400657I1024J957D01*
G03X1655795Y400102I284J-282D01*
G02X1655811Y398206I-1025J-957D01*
G37*
G36*
G01X3938Y398643D02*
G03X5205Y399046I-2J2199D01*
G02X5221Y394408I1488J-2314D01*
G03X3967Y394821I-1283J-1786D01*
G01X3936D01*
G03X2669Y394418I2J-2199D01*
G02X2653Y399056I-1488J2314D01*
G03X3907Y398643I1283J1786D01*
G01X3938D01*
G37*
G36*
G01X-12598D02*
G03X-11331Y399046I-2J2199D01*
G02X-11315Y394408I1488J-2314D01*
G03X-12569Y394821I-1283J-1786D01*
G01X-12599D01*
G03X-13866Y394418I2J-2199D01*
G02X-13882Y399056I-1488J2314D01*
G03X-12628Y398643I1283J1786D01*
G01X-12598D01*
G37*
G36*
G01X776372Y395822D02*
G03X776297Y395251I238J-322D01*
G02X774170Y395478I-1175J-935D01*
G03X774217Y396052I-253J310D01*
G02X774190Y396084I1211J1049D01*
G03X773893Y396095I-153J-128D01*
G02X771901Y395846I-1151J1114D01*
G03X771307Y395618I-210J-340D01*
G02X768542Y395042I-1537J452D01*
G03X767960Y395076I-307J-257D01*
G02X768088Y397268I-1100J1164D01*
G03X768670Y397234I307J257D01*
G02X770611Y397433I1100J-1164D01*
G03X771205Y397661I210J340D01*
G02X773857Y398359I1537J-452D01*
G03X774392Y398339I279J287D01*
G02X776372Y395822I1028J-1228D01*
G37*
G36*
G01X188611Y394532D02*
G03X189210Y394332I377J133D01*
G02X188589Y392468I890J-1332D01*
G03X187990Y392668I-377J-133D01*
G02X188611Y394532I-890J1332D01*
G37*
G36*
G01X66236Y391560D02*
X66227Y391476D01*
G02X63214Y391645I-1502J169D01*
G01Y396645D01*
G02X66236Y396655I1511J0D01*
G01Y391560D01*
G37*
G36*
G01X1662125Y389274D02*
G03X1662056Y388723I251J-311D01*
G02X1660052Y388973I-1122J-840D01*
G03X1660121Y389524I-251J311D01*
G02X1660264Y391367I1122J840D01*
G03Y391940I-280J286D01*
G02X1662222I979J1003D01*
G03Y391367I280J-286D01*
G02X1662125Y389274I-979J-1003D01*
G37*
G36*
G01X25591Y390769D02*
G03X26858Y391172I-2J2199D01*
G02X26874Y386534I1488J-2314D01*
G03X25620Y386947I-1283J-1786D01*
G01X25590D01*
G03X24323Y386544I2J-2199D01*
G02X24307Y391182I-1488J2314D01*
G03X25561Y390769I1283J1786D01*
G01X25591D01*
G37*
G36*
G01X702030Y383117D02*
G03X701477Y383037I-236J-323D01*
G02X698986Y385050I-1273J972D01*
G03Y385570I-304J260D01*
G02X699283Y387921I1218J1040D01*
G03X699320Y388545I-230J327D01*
G02X699248Y390859I1071J1191D01*
G03X699228Y391439I-285J281D01*
G02X699243Y393849I1063J1198D01*
G03X699276Y394421I-262J302D01*
G02X701339Y396841I1181J1082D01*
G03X701880Y396938I219J334D01*
G02X704312Y397109I1289J-952D01*
G03X704910Y397140I285J280D01*
G02X707276Y397296I1254J-997D01*
G03X707838Y397302I278J288D01*
G02X710027Y397383I1138J-1128D01*
G03X710546Y397378I262J302D01*
G02X712636Y394950I1028J-1229D01*
G03Y394350I265J-300D01*
G02Y391950I-1061J-1200D01*
G03Y391350I265J-300D01*
G02X712388Y388770I-1061J-1200D01*
G03X712308Y388143I203J-345D01*
G02X712356Y385932I-1135J-1131D01*
G03Y385392I295J-270D01*
G02X710012Y383208I-1184J-1079D01*
G03X709452Y383228I-290J-275D01*
G02X707293Y383229I-1079J1184D01*
G03X706753I-270J-295D01*
G02X704593I-1080J1183D01*
G03X704053I-270J-295D01*
G02X702030Y383117I-1080J1183D01*
G37*
G36*
G01X175811Y385108D02*
G03Y384508I265J-300D01*
G02X173689I-1061J-1200D01*
G03Y385108I-265J300D01*
G02Y387508I1061J1200D01*
G03Y388108I-265J300D01*
G02X175811I1061J1200D01*
G03Y387508I265J-300D01*
G02Y385108I-1061J-1200D01*
G37*
G36*
G01X822018Y381889D02*
G03X821418I-300J-265D01*
G02X819157Y384150I-1200J1061D01*
G03Y384750I-265J300D01*
G02X821418Y387011I1061J1200D01*
G03X822018I300J265D01*
G02X824380Y387052I1200J-1061D01*
G03X824956Y387047I290J275D01*
G02X827282Y384845I1141J-1124D01*
G03X827306Y384282I296J-269D01*
G02X825072Y381986I-1090J-1174D01*
G03X824473Y381955I-286J-280D01*
G02X822018Y381889I-1255J995D01*
G37*
G36*
G01X1465365Y384296D02*
G03X1465373Y383729I286J-280D01*
G02X1463396Y383699I-973J-1009D01*
G03X1463388Y384266I-286J280D01*
G02X1465365Y384296I973J1009D01*
G37*
G36*
G01X172219Y384568D02*
G03Y383968I265J-300D01*
G02X170097I-1061J-1200D01*
G03Y384568I-265J300D01*
G02Y386968I1061J1200D01*
G03Y387568I-265J300D01*
G02X172219I1061J1200D01*
G03Y386968I265J-300D01*
G02Y384568I-1061J-1200D01*
G37*
G36*
G01X1571657Y384060D02*
G03X1571944Y383585I390J-89D01*
G02X1570217Y382538I-359J-1355D01*
G03X1569930Y383013I-390J89D01*
G02X1571657Y384060I359J1355D01*
G37*
G36*
G01X3938Y382895D02*
G03X5205Y383298I-2J2199D01*
G02X5221Y378660I1488J-2314D01*
G03X3967Y379073I-1283J-1786D01*
G01X3936D01*
G03X2669Y378670I2J-2199D01*
G02X2653Y383308I-1488J2314D01*
G03X3907Y382895I1283J1786D01*
G01X3938D01*
G37*
G36*
G01X-12598D02*
G03X-11331Y383298I-2J2199D01*
G02X-11315Y378660I1488J-2314D01*
G03X-12569Y379073I-1283J-1786D01*
G01X-12599D01*
G03X-13866Y378670I2J-2199D01*
G02X-13882Y383308I-1488J2314D01*
G03X-12628Y382895I1283J1786D01*
G01X-12598D01*
G37*
G36*
G01X1665868Y378253D02*
G03X1665885Y377698I296J-269D01*
G02X1663866Y377636I-980J-1003D01*
G03X1663849Y378191I-296J269D01*
G02X1665868Y378253I980J1003D01*
G37*
G36*
G01X1600490Y380354D02*
Y376261D01*
X1600480Y376176D01*
G02X1597266Y376346I-1603J170D01*
G01Y380344D01*
G02X1600490Y380354I1612J0D01*
G37*
G36*
G01X1609758Y380332D02*
Y376086D01*
X1609748Y376001D01*
G02X1606534Y376171I-1603J170D01*
G01Y380322D01*
G02X1609758Y380332I1612J0D01*
G37*
G36*
G01X852495Y375114D02*
G03X852599Y374541I322J-238D01*
G02X850584Y372074I-873J-1344D01*
G03X850026Y372086I-285J-280D01*
G02X847676Y374252I-1094J1171D01*
G03X847612Y374814I-313J249D01*
G02X847568Y374850I992J1257D01*
G03X847048I-260J-304D01*
G02X844790Y377108I-1040J1218D01*
G03Y377628I-304J260D01*
G02X847048Y379886I1218J1040D01*
G03X847568I260J304D01*
G02X849648I1040J-1218D01*
G03X850168I260J304D01*
G02X852426Y377628I1040J-1218D01*
G03Y377108I304J-260D01*
G02X852495Y375114I-1218J-1040D01*
G37*
G36*
G01X778810Y371129D02*
G03X778193Y371122I-306J-258D01*
G02X778172Y372904I-1093J878D01*
G03X778789Y372911I306J258D01*
G02X778810Y371129I1093J-878D01*
G37*
G36*
G01X25591Y375021D02*
G03X26858Y375424I-2J2199D01*
G02X26874Y370786I1488J-2314D01*
G03X25620Y371199I-1283J-1786D01*
G01X25590D01*
G03X24323Y370796I2J-2199D01*
G02X24307Y375434I-1488J2314D01*
G03X25561Y375021I1283J1786D01*
G01X25591D01*
G37*
G36*
G01X9056D02*
G03X10323Y375424I-2J2199D01*
G02X10339Y370786I1488J-2314D01*
G03X9085Y371199I-1283J-1786D01*
G01X9054D01*
G03X7787Y370796I2J-2199D01*
G02X7771Y375434I-1488J2314D01*
G03X9025Y375021I1283J1786D01*
G01X9056D01*
G37*
G36*
G01X197777Y376372D02*
G03X198245Y376627I91J389D01*
G02X200996Y375078I1509J-537D01*
G03X201025Y374541I310J-253D01*
G02X200961Y372200I-1125J-1141D01*
G03Y371600I265J-300D01*
G02X198839I-1061J-1200D01*
G03Y372200I-265J300D01*
G02X198351Y372990I1060J1201D01*
G03X197854Y373272I-386J-102D01*
G02X197777Y376372I-442J1540D01*
G37*
G36*
G01X102761Y370050D02*
G03X102792Y369428I266J-298D01*
G02X101032Y369342I-827J-1132D01*
G03X101001Y369964I-266J298D01*
G02X102761Y370050I827J1132D01*
G37*
G36*
G01X1598821Y368943D02*
G03X1598810Y368350I263J-301D01*
G02X1596929Y368386I-960J-1021D01*
G03X1596940Y368979I-263J301D01*
G02X1598821Y368943I960J1021D01*
G37*
G36*
G01X835874Y367906D02*
G03X836174Y367903I151J131D01*
G02X836266Y365662I1189J-1074D01*
G03X835725Y365668I-274J-292D01*
G02X833618Y365645I-1067J1195D01*
G03X833098I-260J-304D01*
G02X831018I-1040J1218D01*
G03X830498I-260J-304D01*
G02X828418I-1040J1218D01*
G03X827898I-260J-304D01*
G02X825818I-1040J1218D01*
G03X825298I-260J-304D01*
G02X823218I-1040J1218D01*
G03X822698I-260J-304D01*
G02X820440Y367903I-1040J1218D01*
G03Y368423I-304J260D01*
G02X822698Y370681I1218J1040D01*
G03X823218I260J304D01*
G02X825298I1040J-1218D01*
G03X825818I260J304D01*
G02X827898I1040J-1218D01*
G03X828418I260J304D01*
G02X830498I1040J-1218D01*
G03X831018I260J304D01*
G02X833098I1040J-1218D01*
G03X833618I260J304D01*
G02X835767Y368307I1040J-1218D01*
G03Y368019I139J-144D01*
G02X835874Y367906I-1108J-1157D01*
G37*
G36*
G01X20473Y367147D02*
G03X21740Y367550I-2J2199D01*
G02X21756Y362912I1488J-2314D01*
G03X20502Y363325I-1283J-1786D01*
G01X20471D01*
G03X19204Y362922I2J-2199D01*
G02X19188Y367560I-1488J2314D01*
G03X20442Y367147I1283J1786D01*
G01X20473D01*
G37*
G36*
G01X3938D02*
G03X5205Y367550I-2J2199D01*
G02X5221Y362912I1488J-2314D01*
G03X3967Y363325I-1283J-1786D01*
G01X3936D01*
G03X2669Y362922I2J-2199D01*
G02X2653Y367560I-1488J2314D01*
G03X3907Y367147I1283J1786D01*
G01X3938D01*
G37*
G36*
G01X-12598D02*
G03X-11331Y367550I-2J2199D01*
G02X-11315Y362912I1488J-2314D01*
G03X-12569Y363325I-1283J-1786D01*
G01X-12599D01*
G03X-13866Y362922I2J-2199D01*
G02X-13882Y367560I-1488J2314D01*
G03X-12628Y367147I1283J1786D01*
G01X-12598D01*
G37*
G36*
G01X746633Y362791D02*
G03X746113I-260J-304D01*
G02X743930Y365131I-1040J1218D01*
G03X743910Y365711I-285J281D01*
G02X746013Y368127I1063J1198D01*
G03X746533I260J304D01*
G02X748613I1040J-1218D01*
G03X749133I260J304D01*
G02X751316Y365787I1040J-1218D01*
G03X751336Y365207I285J-281D01*
G02X749233Y362791I-1063J-1198D01*
G03X748713I-260J-304D01*
G02X746633I-1040J1218D01*
G37*
G36*
G01X776217Y363952D02*
G03X776224Y363388I287J-278D01*
G02X774043Y363308I-1053J-1072D01*
G03X774008Y363871I-301J264D01*
G02X773978Y363897I1034J1223D01*
G03X773423Y363887I-272J-293D01*
G02X771547Y363601I-1133J1133D01*
G03X770977Y363359I-186J-354D01*
G02X768209Y364835I-1537J451D01*
G03X768197Y365360I-308J256D01*
G02X770958Y366719I1183J1080D01*
G03X771539Y366435I394J69D01*
G02X773382Y366193I752J-1415D01*
G03X773937Y366203I272J293D01*
G02X776217Y363952I1133J-1132D01*
G37*
G36*
G01X126754Y363789D02*
G03X126731Y363260I288J-278D01*
G02X124229Y361625I-1168J-944D01*
G03X123566Y361696I-355J-184D01*
G02X121298Y363940I-1236J1019D01*
G03X121351Y364496I-258J305D01*
G02X124003Y366273I1249J1003D01*
G03X124602Y366153I350J193D01*
G02X126754Y363789I998J-1253D01*
G37*
G36*
G01X1544310Y362427D02*
G03Y361873I288J-277D01*
G02X1542290I-1010J-973D01*
G03Y362427I-288J277D01*
G02X1544310I1010J973D01*
G37*
G36*
G01X1653798Y365610D02*
Y360515D01*
X1653788Y360430D01*
G02X1650574Y360600I-1603J170D01*
G01Y365601D01*
G02X1653798Y365610I1612J-1D01*
G37*
G36*
G01X1641878Y365510D02*
Y360415D01*
X1641868Y360330D01*
G02X1638654Y360500I-1603J170D01*
G01Y365501D01*
G02X1641878Y365510I1612J-1D01*
G37*
G36*
G01X1534756Y361839D02*
G03X1534771Y361284I295J-270D01*
G02X1532753Y361227I-982J-1001D01*
G03X1532738Y361782I-295J270D01*
G02X1534756Y361839I982J1001D01*
G37*
G36*
G01X823910Y358757D02*
G03X823310Y358745I-295J-271D01*
G02X821028Y360982I-1221J1036D01*
G03Y361582I-265J300D01*
G02X823289Y363843I1061J1200D01*
G03X823889I300J265D01*
G02X826289I1200J-1061D01*
G03X826889I300J265D01*
G02X829289I1200J-1061D01*
G03X829889I300J265D01*
G02X832289I1200J-1061D01*
G03X832889I300J265D01*
G02X835176Y361605I1200J-1061D01*
G03Y361018I271J-294D01*
G02X832889Y358780I-1087J-1177D01*
G03X832289I-300J-265D01*
G02X829889I-1200J1061D01*
G03X829289I-300J-265D01*
G02X826889I-1200J1061D01*
G03X826289I-300J-265D01*
G02X823910Y358757I-1200J1061D01*
G37*
G36*
G01X175224Y358560D02*
G03X174624I-300J-265D01*
G02Y360682I-1200J1061D01*
G03X175224I300J265D01*
G02X177624I1200J-1061D01*
G03X178224I300J265D01*
G02X180624I1200J-1061D01*
G03X181224I300J265D01*
G02X183624I1200J-1061D01*
G03X184224I300J265D01*
G02X186624I1200J-1061D01*
G03X187224I300J265D01*
G02Y358560I1200J-1061D01*
G03X186624I-300J-265D01*
G02X184224I-1200J1061D01*
G03X183624I-300J-265D01*
G02X181224I-1200J1061D01*
G03X180624I-300J-265D01*
G02X178224I-1200J1061D01*
G03X177624I-300J-265D01*
G02X175224I-1200J1061D01*
G37*
G36*
G01X49402Y358381D02*
G03X48839Y358449I-315J-246D01*
G02X49078Y360409I-869J1101D01*
G03X49641Y360341I315J246D01*
G02X49402Y358381I869J-1101D01*
G37*
G36*
G01X1479586Y360661D02*
G03X1479585Y360087I278J-287D01*
G02X1477633Y360091I-978J-1005D01*
G03X1477634Y360665I-278J287D01*
G02X1479586Y360661I978J1005D01*
G37*
G36*
G01X1588089Y357429D02*
G03X1587511I-289J-277D01*
G02Y359371I-1011J971D01*
G03X1588089I289J277D01*
G02Y357429I1011J-971D01*
G37*
G36*
G01X1489450Y359356D02*
G03Y358778I277J-289D01*
G02X1487508I-971J-1011D01*
G03Y359356I-277J289D01*
G02Y361378I971J1011D01*
G03Y361956I-277J289D01*
G02X1489450I971J1011D01*
G03Y361378I277J-289D01*
G02Y359356I-971J-1011D01*
G37*
G36*
G01X1484671Y358502D02*
G03X1484699Y357881I266J-299D01*
G02X1482936Y357801I-832J-1128D01*
G03X1482908Y358422I-266J299D01*
G02X1484671Y358502I832J1128D01*
G37*
G36*
G01X25591Y359273D02*
G03X26858Y359676I-2J2199D01*
G02X26874Y355038I1488J-2314D01*
G03X25620Y355451I-1283J-1786D01*
G01X25590D01*
G03X24323Y355048I2J-2199D01*
G02X24307Y359686I-1488J2314D01*
G03X25561Y359273I1283J1786D01*
G01X25591D01*
G37*
G36*
G01X9056D02*
G03X10323Y359676I-2J2199D01*
G02X10339Y355038I1488J-2314D01*
G03X9085Y355451I-1283J-1786D01*
G01X9054D01*
G03X7787Y355048I2J-2199D01*
G02X7771Y359686I-1488J2314D01*
G03X9025Y359273I1283J1786D01*
G01X9056D01*
G37*
G36*
G01X-7480D02*
G03X-6213Y359676I-2J2199D01*
G02X-6197Y355038I1488J-2314D01*
G03X-7451Y355451I-1283J-1786D01*
G01X-7481D01*
G03X-8748Y355048I2J-2199D01*
G02X-8764Y359686I-1488J2314D01*
G03X-7510Y359273I1283J1786D01*
G01X-7480D01*
G37*
G36*
G01X1631382Y356595D02*
G03X1631410Y355995I278J-288D01*
G02X1629560Y355908I-876J-1095D01*
G03X1629532Y356508I-278J288D01*
G02X1629425Y358603I876J1095D01*
G03X1629440Y359158I-280J285D01*
G02X1629414Y361018I1036J945D01*
G03X1629383Y361573I-303J261D01*
G02X1629291Y363533I954J1027D01*
G03X1629269Y364088I-299J266D01*
G02X1629267Y366108I971J1011D01*
G03X1629258Y366692I-278J288D01*
G02X1631173Y366721I942J1038D01*
G03X1631182Y366137I278J-288D01*
G02X1631286Y364166I-942J-1038D01*
G03X1631308Y363611I299J-266D01*
G02X1631399Y361685I-971J-1011D01*
G03X1631430Y361130I303J-261D01*
G02X1631459Y359103I-954J-1027D01*
G03X1631444Y358548I280J-285D01*
G02X1631382Y356595I-1036J-945D01*
G37*
G36*
G01X1521289Y356063D02*
G03X1521315Y355466I279J-287D01*
G02X1519453Y355385I-885J-1087D01*
G03X1519427Y355982I-279J287D01*
G02X1521289Y356063I885J1087D01*
G37*
G36*
G01X1525756Y355744D02*
G03Y355190I288J-277D01*
G02X1523736I-1010J-973D01*
G03Y355744I-288J277D01*
G02Y357690I1010J973D01*
G03Y358244I-288J277D01*
G02X1525756I1010J973D01*
G03Y357690I288J-277D01*
G02Y355744I-1010J-973D01*
G37*
G36*
G01X1499217Y353894D02*
G03Y353316I277J-289D01*
G02X1497275I-971J-1011D01*
G03Y353894I-277J289D01*
G02Y355916I971J1011D01*
G03Y356494I-277J289D01*
G02X1497261Y358503I971J1011D01*
G03X1497275Y359058I-281J285D01*
G02X1497356Y361034I1034J947D01*
G03X1497342Y361633I-272J293D01*
G02X1497293Y363734I904J1072D01*
G03X1497279Y364333I-272J293D01*
G02X1499136Y364376I904J1072D01*
G03X1499150Y363777I272J-293D01*
G02X1499199Y361676I-904J-1072D01*
G03X1499213Y361077I272J-293D01*
G02X1499294Y359007I-904J-1072D01*
G03X1499280Y358452I281J-285D01*
G02X1499217Y356494I-1034J-947D01*
G03Y355916I277J-289D01*
G02Y353894I-971J-1011D01*
G37*
G36*
G01X1653157Y353689D02*
G03Y353111I277J-289D01*
G02X1651215I-971J-1011D01*
G03Y353689I-277J289D01*
G02X1653157I971J1011D01*
G37*
G36*
G01X767955Y352504D02*
G03X768121Y351953I349J-195D01*
G02X766254Y351393I-644J-1245D01*
G03X766088Y351944I-349J195D01*
G02X767955Y352504I644J1245D01*
G37*
G36*
G01X1539449Y352283D02*
G03Y351705I277J-289D01*
G02X1537507I-971J-1011D01*
G03Y352283I-277J289D01*
G02Y354305I971J1011D01*
G03Y354883I-277J289D01*
G02X1539449I971J1011D01*
G03Y354305I277J-289D01*
G02Y352283I-971J-1011D01*
G37*
G36*
G01X1416430Y352151D02*
G03X1416419Y351563I266J-299D01*
G02X1414520Y351599I-969J-1013D01*
G03X1414531Y352187I-266J299D01*
G02X1416430Y352151I969J1013D01*
G37*
G36*
G01X1447394Y350654D02*
G03X1446911Y350277I-83J-391D01*
G02X1445801Y351698I-1401J50D01*
G03X1446284Y352075I83J391D01*
G02X1447394Y350654I1401J-50D01*
G37*
G36*
G01X1490844Y351587D02*
G03X1490827Y351004I265J-299D01*
G02X1488909Y351061I-989J-993D01*
G03X1488926Y351644I-265J299D01*
G02X1490844Y351587I989J993D01*
G37*
G36*
G01X1544538Y351473D02*
G03Y350919I288J-277D01*
G02X1542518I-1010J-973D01*
G03Y351473I-288J277D01*
G02X1544538I1010J973D01*
G37*
G36*
G01X1331153Y351026D02*
G03X1331708Y350981I301J264D01*
G02X1331547Y348974I892J-1082D01*
G03X1330992Y349019I-301J-264D01*
G02X1331153Y351026I-892J1082D01*
G37*
G36*
G01X115528Y351963D02*
G03X115764Y352490I-135J377D01*
G02X117535Y351696I1299J526D01*
G03X117299Y351169I135J-377D01*
G02X117398Y350750I-1299J-528D01*
G03X117844Y350383I399J30D01*
G02X116610Y348884I164J-1392D01*
G03X116164Y349251I-399J-30D01*
G02X115528Y351963I-163J1392D01*
G37*
G36*
G01X746378Y343688D02*
G03X745818I-280J-286D01*
G02X743637Y346033I-1120J1145D01*
G03Y346633I-265J300D01*
G02X745818Y348978I1061J1200D01*
G03X746378I280J286D01*
G02X748618I1120J-1145D01*
G03X749178I280J286D01*
G02X751359Y346633I1120J-1145D01*
G03Y346033I265J-300D01*
G02X749178Y343688I-1061J-1200D01*
G03X748618I-280J-286D01*
G02X746378I-1120J1145D01*
G37*
G36*
G01X1643534Y343999D02*
G03X1643594Y343437I312J-251D01*
G02X1641621Y343227I-882J-1090D01*
G03X1641561Y343789I-312J251D01*
G02X1643534Y343999I882J1090D01*
G37*
G36*
G01X1556480Y340194D02*
G03X1555870I-305J-259D01*
G02Y342006I-1070J906D01*
G03X1556480I305J259D01*
G02Y340194I1070J-906D01*
G37*
G36*
G01X778862Y339127D02*
G03X778252I-305J-259D01*
G02Y340939I-1070J906D01*
G03X778862I305J259D01*
G02Y339127I1070J-906D01*
G37*
G36*
G01X700168Y337953D02*
G03X699613Y337931I-266J-299D01*
G02X699532Y339947I-1013J969D01*
G03X700087Y339969I266J299D01*
G02X700168Y337953I1013J-969D01*
G37*
G36*
G01X1582841Y337739D02*
G03X1582273Y337715I-272J-293D01*
G02X1579704Y339598I-1183J1080D01*
G03X1579581Y340130I-346J200D01*
G02X1581408Y342230I785J1162D01*
G03X1581962Y342189I298J267D01*
G02X1584152Y340570I897J-1077D01*
G03X1584360Y340050I369J-154D01*
G02X1582841Y337739I-566J-1283D01*
G37*
G36*
G01X824282Y335966D02*
G03X823682I-300J-265D01*
G02X821337Y338147I-1200J1061D01*
G03Y338707I-286J280D01*
G02X821421Y341027I1145J1120D01*
G03Y341627I-265J300D01*
G02X823682Y343888I1061J1200D01*
G03X824282I300J265D01*
G02X826682I1200J-1061D01*
G03X827282I300J265D01*
G02X829682I1200J-1061D01*
G03X830282I300J265D01*
G02X832682I1200J-1061D01*
G03X833282I300J265D01*
G02X835623Y343951I1200J-1061D01*
G03X836203Y343961I285J281D01*
G02X838483Y344041I1179J-1084D01*
G03X839058Y344068I274J291D01*
G02X841421Y341905I1204J-1057D01*
G03X841425Y341349I290J-276D01*
G02X841466Y339148I-1143J-1122D01*
G03X841486Y338588I295J-270D01*
G02X839304Y336242I-1103J-1162D01*
G03X838704Y336172I-270J-295D01*
G02X836241Y335953I-1322J905D01*
G03X835661Y335943I-285J-281D01*
G02X833282Y335966I-1179J1084D01*
G03X832682I-300J-265D01*
G02X830282I-1200J1061D01*
G03X829682I-300J-265D01*
G02X827282I-1200J1061D01*
G03X826682I-300J-265D01*
G02X824282I-1200J1061D01*
G37*
G36*
G01X1620907Y337663D02*
G03Y337109I288J-277D01*
G02X1618887I-1010J-973D01*
G03Y337663I-288J277D01*
G02Y339609I1010J973D01*
G03Y340163I-288J277D01*
G02X1620907I1010J973D01*
G03Y339609I288J-277D01*
G02Y337663I-1010J-973D01*
G37*
G36*
G01X746378Y334371D02*
G03X745818I-280J-286D01*
G02X743553Y336636I-1120J1145D01*
G03Y337196I-286J280D01*
G02X745818Y339461I1145J1120D01*
G03X746378I280J286D01*
G02X748618I1120J-1145D01*
G03X749178I280J286D01*
G02X751443Y337196I1120J-1145D01*
G03Y336636I286J-280D01*
G02X749178Y334371I-1145J-1120D01*
G03X748618I-280J-286D01*
G02X746378I-1120J1145D01*
G37*
G36*
G01X852875Y334344D02*
G03X852275I-300J-265D01*
G02X849944Y336539I-1200J1061D01*
G03X849925Y337123I-283J283D01*
G02X849782Y337266I1059J1202D01*
G03X849182I-300J-265D01*
G02X846921Y339527I-1200J1061D01*
G03Y340127I-265J300D01*
G02Y342527I1061J1200D01*
G03Y343127I-265J300D01*
G02X849182Y345388I1061J1200D01*
G03X849782I300J265D01*
G02X852182I1200J-1061D01*
G03X852782I300J265D01*
G02X855182I1200J-1061D01*
G03X855782I300J265D01*
G02X858043Y343127I1200J-1061D01*
G03Y342527I265J-300D01*
G02Y340127I-1061J-1200D01*
G03Y339527I265J-300D01*
G02X858113Y337193I-1061J-1200D01*
G03X858132Y336609I283J-283D01*
G02X855875Y334344I-1057J-1204D01*
G03X855275I-300J-265D01*
G02X852875I-1200J1061D01*
G37*
G36*
G01X81379Y334629D02*
G03X80813Y334496I-220J-334D01*
G02X80371Y336371I-1213J704D01*
G03X80937Y336504I220J334D01*
G02X81379Y334629I1213J-704D01*
G37*
G36*
G01X102187Y334221D02*
G03X101599Y334210I-289J-277D01*
G02X101563Y336109I-1049J930D01*
G03X102151Y336120I289J277D01*
G02X102187Y334221I1049J-930D01*
G37*
G36*
G01X1497795Y336516D02*
G03X1498283Y336166I398J40D01*
G02X1497205Y334660I317J-1366D01*
G03X1496717Y335010I-398J-40D01*
G02X1495105Y336914I-317J1366D01*
G03X1494893Y337435I-369J153D01*
G02X1494589Y339834I552J1289D01*
G03X1494670Y340384I-244J317D01*
G02X1496666Y340090I1140J816D01*
G03X1496585Y339540I244J-317D01*
G02X1496620Y339488I-1145J-808D01*
G03X1496939Y339466I168J109D01*
G02X1498126Y337150I1058J-920D01*
G03X1497771Y336668I36J-398D01*
G02X1497795Y336516I-1371J-294D01*
G37*
G36*
G01X1473398Y336467D02*
G03X1473409Y335868I270J-295D01*
G02X1471552Y335833I-909J-1068D01*
G03X1471541Y336432I-270J295D01*
G02X1473398Y336467I909J1068D01*
G37*
G36*
G01X1416971Y334489D02*
G03Y333911I277J-289D01*
G02X1415029I-971J-1011D01*
G03Y334489I-277J289D01*
G02Y336511I971J1011D01*
G03Y337089I-277J289D01*
G02X1416971I971J1011D01*
G03Y336511I277J-289D01*
G02Y334489I-971J-1011D01*
G37*
G36*
G01X1570182Y333131D02*
G03Y332553I277J-289D01*
G02X1568240I-971J-1011D01*
G03Y333131I-277J289D01*
G02X1570182I971J1011D01*
G37*
G36*
G01X1548600Y333102D02*
G03X1548734Y332556I343J-205D01*
G02X1546798Y332082I-733J-1195D01*
G03X1546664Y332628I-343J205D01*
G02X1548600Y333102I733J1195D01*
G37*
G36*
G01X200006Y337822D02*
G03X200004Y338371I-292J273D01*
G02X199866Y338536I1157J1108D01*
G03X199257Y338583I-324J-234D01*
G02X196987Y340843I-1138J1127D01*
G03X197007Y341387I-283J283D01*
G02X197154Y343623I1216J1043D01*
G03X197156Y344216I-267J297D01*
G02X197033Y344341I1079J1184D01*
G03X196433I-300J-265D01*
G02X194299Y346704I-1200J1061D01*
G03X194325Y347334I-233J325D01*
G02Y349470I908J1068D01*
G03X194299Y350100I-259J305D01*
G02X196433Y352463I934J1302D01*
G03X197033I300J265D01*
G02X199294Y350202I1200J-1061D01*
G03Y349602I265J-300D01*
G02X199339Y349561I-1056J-1204D01*
G03X199901Y349570I276J289D01*
G02X202106Y347249I1144J-1121D01*
G03Y346649I265J-300D01*
G02X202224Y346534I-1058J-1203D01*
G03X202826Y346549I294J270D01*
G02X205121Y344327I1234J-1022D01*
G03Y343727I265J-300D01*
G02X205137Y341341I-1061J-1200D01*
G03X205158Y340732I269J-296D01*
G02X205334Y338382I-995J-1256D01*
G03X205336Y337833I292J-273D01*
G02X202977Y335667I-1159J-1105D01*
G03X202377I-300J-265D01*
G02X202238Y335528I-1200J1061D01*
G03Y334928I265J-300D01*
G02Y332528I-1061J-1200D01*
G03Y331928I265J-300D01*
G02X200116I-1061J-1200D01*
G03Y332528I-265J300D01*
G02Y334928I1061J1200D01*
G03Y335528I-265J300D01*
G02X200006Y337822I1061J1201D01*
G37*
G36*
G01X776587Y331634D02*
G03X776458Y331090I214J-338D01*
G02X773785Y329738I-1286J-775D01*
G03X773079Y329800I-369J-154D01*
G02X770216Y331188I-1349J864D01*
G03X769926Y331709I-378J131D01*
G02X771463Y334350I352J1563D01*
G03X771997Y334297I296J269D01*
G02X774071Y334153I953J-1288D01*
G03X774627Y334149I280J285D01*
G02X776587Y331634I1105J-1160D01*
G37*
G36*
G01X1526765Y328878D02*
G03X1526213Y328768I-220J-334D01*
G02X1525823Y330723I-1162J785D01*
G03X1526375Y330833I220J334D01*
G02X1526765Y328878I1162J-785D01*
G37*
G36*
G01X1560995Y330789D02*
G03Y330211I277J-289D01*
G02X1559053I-971J-1011D01*
G03Y330789I-277J289D01*
G02X1560995I971J1011D01*
G37*
G36*
G01X1654016Y328102D02*
G03X1654038Y327534I292J-273D01*
G02X1652066Y327457I-947J-1034D01*
G03X1652044Y328025I-292J273D01*
G02X1654016Y328102I947J1034D01*
G37*
G36*
G01X645706Y326977D02*
G03X645589Y327576I-312J250D01*
G02X647366Y327923I683J1224D01*
G03X647483Y327324I312J-250D01*
G02X645706Y326977I-683J-1224D01*
G37*
G36*
G01X1493775Y327586D02*
G03X1493930Y327048I352J-190D01*
G02X1492005Y326492I-690J-1220D01*
G03X1491850Y327030I-352J190D01*
G02X1493775Y327586I690J1220D01*
G37*
G36*
G01X1017937Y325288D02*
G03X1017717Y324783I156J-368D01*
G02X1015855Y325596I-1318J-479D01*
G03X1016075Y326101I-156J368D01*
G02X1018366Y327590I1318J480D01*
G03X1018920I277J288D01*
G02X1020866I973J-1010D01*
G03X1021420I277J288D01*
G02X1023366I973J-1010D01*
G03X1023920I277J288D01*
G02X1024287Y327844I971J-1011D01*
G03X1024479Y328371I-172J361D01*
G02X1026567Y330094I1276J580D01*
G03X1027153Y330233I232J326D01*
G02X1028642Y328200I1240J-653D01*
G03X1028420Y327534I71J-394D01*
G02X1026420Y325570I-1027J-955D01*
G03X1025866I-277J-288D01*
G02X1023920I-973J1010D01*
G03X1023366I-277J-288D01*
G02X1021420I-973J1010D01*
G03X1020866I-277J-288D01*
G02X1018920I-973J1010D01*
G03X1018366I-277J-288D01*
G02X1017937Y325288I-972J1011D01*
G37*
G36*
G01X376998Y330627D02*
G03X377585Y330641I287J279D01*
G02X379464Y328129I1200J-1061D01*
G03X379286Y327569I170J-362D01*
G02X376816Y325592I-1392J-792D01*
G03X376282Y325596I-269J-296D01*
G02X374111Y325645I-1059J1202D01*
G03X373545Y325635I-278J-288D01*
G02X371263Y325609I-1154J1111D01*
G03X370735Y325640I-282J-284D01*
G02X368626Y325759I-987J1262D01*
G03X368101Y325790I-280J-286D01*
G02X368083Y325776I-992J1257D01*
G03X368050Y325488I120J-160D01*
G02X365736Y325637I-1228J-1029D01*
G03X365796Y326156I-271J294D01*
G02X368243Y328200I1325J901D01*
G03X368768Y328169I280J286D01*
G02X370876Y328039I980J-1267D01*
G03X371404Y328008I282J284D01*
G02X373503Y327899I987J-1262D01*
G03X374069Y327909I278J288D01*
G02X374351Y328142I1155J-1110D01*
G03X374476Y328684I-217J336D01*
G02X376998Y330627I1371J828D01*
G37*
G36*
G01X1543591Y324428D02*
G03X1543924Y323984I397J-49D01*
G02X1542309Y322772I-224J-1384D01*
G03X1541976Y323216I-397J49D01*
G02X1543591Y324428I224J1384D01*
G37*
G36*
G01X1590800Y323413D02*
G03X1591385Y323202I378J131D01*
G02X1590786Y321542I725J-1200D01*
G03X1590201Y321753I-378J-131D01*
G02X1590800Y323413I-725J1200D01*
G37*
G36*
G01X688320Y318775D02*
G03X688262Y318235I263J-301D01*
G02X686218Y318455I-1124J-838D01*
G03X686276Y318995I-263J301D01*
G02X688320Y318775I1124J838D01*
G37*
G36*
G01X647783Y319011D02*
G03Y318389I252J-311D01*
G02X646017I-883J-1089D01*
G03Y319011I-252J311D01*
G02X647783I883J1089D01*
G37*
G36*
G01X115528Y319963D02*
G03X115764Y320490I-135J377D01*
G02X117535Y319696I1299J526D01*
G03X117299Y319169I135J-377D01*
G02X117398Y318750I-1299J-528D01*
G03X117844Y318383I399J30D01*
G02X116610Y316884I164J-1392D01*
G03X116164Y317251I-399J-30D01*
G02X115528Y319963I-163J1392D01*
G37*
G36*
G01X1549195Y318450D02*
G03X1549443Y317930I374J-141D01*
G02X1547687Y317092I-443J-1330D01*
G03X1547439Y317612I-374J141D01*
G02X1549195Y318450I443J1330D01*
G37*
G36*
G01X82378Y317044D02*
G03X82972Y317036I301J264D01*
G02X82946Y315158I1028J-953D01*
G03X82352Y315166I-301J-264D01*
G02X82378Y317044I-1028J953D01*
G37*
G36*
G01X64971Y315489D02*
G03Y314911I277J-289D01*
G02X63029I-971J-1011D01*
G03Y315489I-277J289D01*
G02X64971I971J1011D01*
G37*
G36*
G01X1568271Y314778D02*
G03X1568629Y314283I388J-96D01*
G02X1567163Y313224I-105J-1398D01*
G03X1566805Y313719I-388J96D01*
G02X1565900Y314144I104J1398D01*
G03X1565346Y314165I-288J-277D01*
G02X1565421Y316183I-935J1045D01*
G03X1565975Y316162I288J277D01*
G02X1568271Y314778I935J-1045D01*
G37*
G36*
G01X1517245Y312208D02*
G03X1517209Y311654I269J-296D01*
G02X1515194Y311785I-1071J-905D01*
G03X1515230Y312339I-269J296D01*
G02X1517245Y312208I1071J905D01*
G37*
G36*
G01X1640423Y311762D02*
G03Y311208I288J-277D01*
G02X1638403I-1010J-973D01*
G03Y311762I-288J277D01*
G02X1640423I1010J973D01*
G37*
G36*
G01X1054857Y310895D02*
G03X1055487Y310894I315J246D01*
G02X1055484Y308919I1260J-989D01*
G03X1054854Y308920I-315J-246D01*
G02X1054857Y310895I-1260J989D01*
G37*
G36*
G01X1047789Y310997D02*
G03X1048375Y310996I293J272D01*
G02X1048370Y308817I1172J-1092D01*
G03X1047784Y308818I-293J-272D01*
G02X1047789Y310997I-1172J1092D01*
G37*
G36*
G01X1040571Y310985D02*
G03X1041163Y310983I297J268D01*
G02X1041159Y308829I1184J-1079D01*
G03X1040567Y308831I-297J-268D01*
G02X1040571Y310985I-1184J1079D01*
G37*
G36*
G01X1033286Y310919D02*
G03X1033907Y310918I311J252D01*
G02X1033903Y308895I1240J-1014D01*
G03X1033282Y308896I-311J-252D01*
G02X1033286Y310919I-1240J1014D01*
G37*
G36*
G01X405310Y310979D02*
G03X405905Y310978I298J267D01*
G02X405901Y308835I1189J-1074D01*
G03X405306Y308836I-298J-267D01*
G02X405310Y310979I-1189J1074D01*
G37*
G36*
G01X397985Y310878D02*
G03X398621Y310877I318J242D01*
G02X398618Y308936I1273J-972D01*
G03X397982Y308937I-318J-242D01*
G02X397985Y310878I-1273J972D01*
G37*
G36*
G01X390781Y310875D02*
G03X391419Y310874I319J241D01*
G02X391415Y308939I1275J-970D01*
G03X390777Y308940I-319J-241D01*
G02X390781Y310875I-1275J970D01*
G37*
G36*
G01X383698Y310970D02*
G03X384297Y310969I300J265D01*
G02X384293Y308844I1197J-1065D01*
G03X383694Y308845I-300J-265D01*
G02X383698Y310970I-1197J1065D01*
G37*
G36*
G01X1022960Y308827D02*
G03X1022346Y308796I-294J-271D01*
G02X1022245Y310842I-1281J962D01*
G03X1022859Y310873I294J271D01*
G02X1022960Y308827I1281J-962D01*
G37*
G36*
G01X1565345Y310023D02*
G03X1565339Y309424I262J-302D01*
G02X1563482Y309443I-939J-1041D01*
G03X1563488Y310042I-262J302D01*
G02X1565345Y310023I939J1041D01*
G37*
G36*
G01X714980Y309887D02*
G03Y309333I288J-277D01*
G02X712960I-1010J-973D01*
G03Y309887I-288J277D01*
G02X714980I1010J973D01*
G37*
G36*
G01X455158Y309368D02*
G03Y308814I288J-277D01*
G02X452981Y307064I-1010J-972D01*
G03X452426Y307175I-333J-222D01*
G02X450266Y308104I-778J1166D01*
G03X449789Y308428I-394J-67D01*
G02X448527Y308790I-289J1372D01*
G03X447973I-277J-288D01*
G02Y310810I-973J1010D01*
G03X448527I277J288D01*
G02X450882Y310037I973J-1010D01*
G03X451359Y309713I394J67D01*
G02X452218Y309622I289J-1372D01*
G03X452773Y310066I163J365D01*
G02X455158Y309368I1375J275D01*
G37*
G36*
G01X1561087Y309435D02*
G03X1561176Y308850I311J-252D01*
G02X1559310Y308565I-776J-1167D01*
G03X1559221Y309150I-311J252D01*
G02X1561087Y309435I776J1167D01*
G37*
G36*
G01X1306859Y308248D02*
G03X1306876Y307664I281J-284D01*
G02X1304964Y307608I-926J-1053D01*
G03X1304947Y308192I-281J284D01*
G02X1304824Y308315I928J1051D01*
G03X1304271Y308358I-299J-266D01*
G02X1304429Y310371I-891J1083D01*
G03X1304982Y310328I299J266D01*
G02X1306859Y308248I891J-1083D01*
G37*
G36*
G01X198917Y305660D02*
G03X198404Y305796I-333J-221D01*
G02X196532Y308340I-720J1431D01*
G03X196541Y308886I-288J278D01*
G02X198882Y308846I1189J1073D01*
G03X198873Y308300I288J-278D01*
G02X199018Y308115I-1185J-1078D01*
G03X199531Y307979I333J221D01*
G02X198917Y305660I720J-1431D01*
G37*
G36*
G01X1537386Y305392D02*
G03X1537870Y305102I388J98D01*
G02X1536847Y303397I336J-1361D01*
G03X1536363Y303687I-388J-98D01*
G02X1537386Y305392I-336J1361D01*
G37*
G36*
G01X1637893Y304142D02*
G03X1637906Y303586I294J-271D01*
G02X1635890Y303537I-984J-998D01*
G03X1635877Y304093I-294J271D01*
G02X1637893Y304142I984J998D01*
G37*
G36*
G01X1564358Y302020D02*
G03X1564356Y302642I-253J310D01*
G02X1566121Y302648I879J1092D01*
G03X1566123Y302026I253J-310D01*
G02X1564358Y302020I-879J-1092D01*
G37*
G36*
G01X1584487Y302124D02*
G03Y301556I281J-284D01*
G02X1582513I-987J-996D01*
G03Y302124I-281J284D01*
G02X1584487I987J996D01*
G37*
G36*
G01X1300631Y300220D02*
G03X1300624Y299612I256J-307D01*
G02X1298804Y299635I-923J-1055D01*
G03X1298811Y300243I-256J307D01*
G02X1300631Y300220I923J1055D01*
G37*
G36*
G01X776240Y299981D02*
G03X776220Y299391I260J-304D01*
G02X773762Y297796I-1049J-1075D01*
G03X773189Y298006I-376J-138D01*
G02X771445Y298114I-789J1394D01*
G03X770853Y297981I-239J-321D01*
G02X768107Y299624I-1414J754D01*
G03X767877Y300232I-333J222D01*
G02X769325Y303003I413J1548D01*
G03X769846Y303007I258J305D01*
G02X772461Y301440I1054J-1207D01*
G03X772761Y300961I390J-89D01*
G02X773039Y300869I-362J-1561D01*
G03X773598Y301229I159J367D01*
G02X776240Y299981I1602J-29D01*
G37*
G36*
G01X824482Y294466D02*
G03X823882I-300J-265D01*
G02X821621Y296727I-1200J1061D01*
G03Y297327I-265J300D01*
G02X821499Y299607I1061J1200D01*
G03Y300147I-295J270D01*
G02Y302307I1183J1080D01*
G03Y302847I-295J270D01*
G02X823882Y304988I1183J1080D01*
G03X824482I300J265D01*
G02X826882I1200J-1061D01*
G03X827482I300J265D01*
G02X829882I1200J-1061D01*
G03X830482I300J265D01*
G02X832882I1200J-1061D01*
G03X833482I300J265D01*
G02X835922Y304941I1200J-1061D01*
G03X836542I310J253D01*
G02X838887Y302767I1240J-1014D01*
G03Y302187I275J-290D01*
G02Y299867I-1105J-1160D01*
G03Y299287I275J-290D01*
G02X836414Y297294I-1105J-1160D01*
G03X835794Y297374I-342J-208D01*
G02X833482Y297466I-1112J1153D01*
G03X832882I-300J-265D01*
G02X830482I-1200J1061D01*
G03X829882I-300J-265D01*
G02X827482I-1200J1061D01*
G03X826882I-300J-265D01*
G02X826743Y297327I-1200J1061D01*
G03Y296727I265J-300D01*
G02X824482Y294466I-1061J-1200D01*
G37*
G36*
G01X189138Y307917D02*
G03X189444Y307915I154J127D01*
G02X189544Y308022I1219J-1039D01*
G03X189534Y308317I-140J143D01*
G02X191803Y308517I1036J1222D01*
G03X191822Y307985I308J-255D01*
G02X189549Y305728I-1157J-1108D01*
G03X188997Y305732I-278J-287D01*
G02X188963Y305702I-1077J1186D01*
G03X188943Y305122I265J-299D01*
G02X188905Y302840I-1143J-1122D01*
G03Y302260I275J-290D01*
G02X188983Y300020I-1105J-1160D01*
G03Y299480I295J-270D01*
G02X188997Y297336I-1183J-1080D01*
G03X189029Y296773I299J-265D01*
G02X189127Y296676I-1077J-1186D01*
G03X189695Y296660I292J273D01*
G02X192000Y296561I1105J-1160D01*
G03X192600I300J265D01*
G02X195037Y296518I1200J-1061D01*
G03X195667Y296535I308J254D01*
G02X195719Y294565I1289J-952D01*
G03X195089Y294548I-308J-254D01*
G02X192600Y294439I-1289J952D01*
G03X192000I-300J-265D01*
G02X189629Y294407I-1200J1061D01*
G03X189061Y294423I-292J-273D01*
G02X186719Y294565I-1105J1160D01*
G03X186089Y294548I-308J-254D01*
G02X183600Y294439I-1289J952D01*
G03X183000I-300J-265D01*
G02X180629Y294407I-1200J1061D01*
G03X180061Y294423I-292J-273D01*
G02X177719Y294565I-1105J1160D01*
G03X177089Y294548I-308J-254D01*
G02X174600Y294439I-1289J952D01*
G03X174000I-300J-265D01*
G02X171695Y296660I-1200J1061D01*
G03Y297240I-275J290D01*
G02X171617Y299480I1105J1160D01*
G03Y300020I-295J270D01*
G02X171695Y302260I1183J1080D01*
G03Y302840I-275J290D01*
G02X174000Y305061I1105J1160D01*
G03X174600I300J265D01*
G02X177000I1200J-1061D01*
G03X177600I300J265D01*
G02X180000I1200J-1061D01*
G03X180600I300J265D01*
G02X183000I1200J-1061D01*
G03X183600I300J265D01*
G02X186000I1200J-1061D01*
G03X186600I300J265D01*
G02X186737Y305198I1199J-1062D01*
G03X186757Y305778I-265J299D01*
G02X189138Y307917I1143J1123D01*
G37*
G36*
G01X657627Y294985D02*
G03X657426Y295549I-350J193D01*
G02X659176Y296170I524J1301D01*
G03X659377Y295606I350J-193D01*
G02X657627Y294985I-524J-1301D01*
G37*
G36*
G01X1054894Y293960D02*
G03X1055497Y293959I302J262D01*
G02X1055492Y291854I1205J-1055D01*
G03X1054889Y291855I-302J-262D01*
G02X1054894Y293960I-1205J1055D01*
G37*
G36*
G01X1040435Y293917D02*
G03X1041058Y293914I313J249D01*
G02X1041049Y291906I1244J-1010D01*
G03X1040426Y291909I-313J-249D01*
G02X1040435Y293917I-1244J1010D01*
G37*
G36*
G01X1033215Y293897D02*
G03X1033844Y293896I315J247D01*
G02X1033840Y291917I1258J-992D01*
G03X1033211Y291918I-315J-247D01*
G02X1033215Y293897I-1258J992D01*
G37*
G36*
G01X1026163Y294014D02*
G03X1026744Y294011I292J273D01*
G02X1026733Y291808I1158J-1107D01*
G03X1026152Y291811I-292J-273D01*
G02X1026163Y294014I-1158J1107D01*
G37*
G36*
G01X1018861Y293935D02*
G03X1019475Y293934I307J256D01*
G02X1019471Y291879I1227J-1030D01*
G03X1018857Y291880I-307J-256D01*
G02X1018861Y293935I-1227J1030D01*
G37*
G36*
G01X405448Y294111D02*
G03X406013Y294086I295J270D01*
G02X405912Y291823I1081J-1182D01*
G03X405347Y291848I-295J-270D01*
G02X405448Y294111I-1081J1182D01*
G37*
G36*
G01X398151Y294056D02*
G03X398749Y294025I313J249D01*
G02X398640Y291906I1145J-1121D01*
G03X398042Y291937I-313J-249D01*
G02X398151Y294056I-1145J1121D01*
G37*
G36*
G01X390797Y293888D02*
G03X391429Y293887I316J245D01*
G02X391425Y291926I1265J-983D01*
G03X390793Y291927I-316J-245D01*
G02X390797Y293888I-1265J983D01*
G37*
G36*
G01X383890Y294190D02*
G03X384463Y294130I315J246D01*
G02X384229Y291921I1031J-1226D01*
G03X383656Y291981I-315J-246D01*
G02X383890Y294190I-1031J1226D01*
G37*
G36*
G01X372753Y291803D02*
G03X372226Y291770I-245J-316D01*
G02X369837Y291911I-1132J1134D01*
G03X369242Y291947I-314J-248D01*
G02X369373Y294080I-1126J1140D01*
G03X369968Y294044I314J248D01*
G02X372077Y294169I1126J-1140D01*
G03X372604Y294202I245J316D01*
G02X372753Y291803I1132J-1134D01*
G37*
G36*
G01X1637832Y293973D02*
G03Y293419I288J-277D01*
G02X1635812I-1010J-973D01*
G03Y293973I-288J277D01*
G02X1635853Y295959I1010J973D01*
G03X1635876Y296514I-276J289D01*
G02X1637894Y296431I1049J930D01*
G03X1637871Y295876I276J-289D01*
G02X1637832Y293973I-1049J-930D01*
G37*
G36*
G01X1305637Y292913D02*
G03X1305262Y292476I23J-399D01*
G02X1303787Y293745I-1396J-131D01*
G03X1304162Y294182I-23J399D01*
G02X1305637Y292913I1396J131D01*
G37*
G36*
G01X1335501Y292918D02*
G03X1336123Y292909I315J247D01*
G02X1336099Y291144I1077J-897D01*
G03X1335477Y291153I-315J-247D01*
G02X1335501Y292918I-1077J897D01*
G37*
G36*
G01X1627281Y302600D02*
X1627279Y302503D01*
G02Y302891I-14210J194D01*
G01X1627280Y302796D01*
X1627281Y302702D01*
Y302600D01*
G37*
G36*
G01X49683Y291311D02*
G03Y290689I252J-311D01*
G02X47917I-883J-1089D01*
G03Y291311I-252J311D01*
G02X49683I883J1089D01*
G37*
G36*
G01X1534824Y287709D02*
G03X1534841Y287125I281J-284D01*
G02X1532928Y287070I-927J-1052D01*
G03X1532911Y287654I-281J284D01*
G02X1534824Y287709I927J1052D01*
G37*
G36*
G01X1548006Y287663D02*
G03X1548358Y287223I398J-43D01*
G02X1546805Y285979I-159J-1393D01*
G03X1546453Y286419I-398J43D01*
G02X1548006Y287663I159J1393D01*
G37*
G36*
G01X637881Y287185D02*
G03X637839Y286610I255J-308D01*
G02X636064Y286864I-1040J-940D01*
G03X636087Y287187I-105J170D01*
G02X635967Y287300I900J1076D01*
G03X635645Y287257I-146J-137D01*
G02X635280Y289012I-1238J658D01*
G03X635852Y289090I249J313D01*
G02X637881Y287185I1133J-827D01*
G37*
G36*
G01X115528Y287963D02*
G03X115764Y288490I-135J377D01*
G02X117535Y287696I1299J526D01*
G03X117299Y287169I135J-377D01*
G02X117398Y286750I-1299J-528D01*
G03X117844Y286383I399J30D01*
G02X116610Y284884I164J-1392D01*
G03X116164Y285251I-399J-30D01*
G02X115528Y287963I-163J1392D01*
G37*
G36*
G01X663911Y283917D02*
G03X663289I-311J-252D01*
G02X660957Y285448I-1089J883D01*
G03X660742Y286007I-355J184D01*
G02X662475Y286673I490J1314D01*
G03X662690Y286114I355J-184D01*
G02X663289Y285683I-491J-1314D01*
G03X663911I311J252D01*
G02Y283917I1089J-883D01*
G37*
G36*
G01X1580115Y283805D02*
G03X1579560Y283799I-274J-291D01*
G02X1579539Y285819I-983J1000D01*
G03X1580094Y285825I274J291D01*
G02X1580115Y283805I983J-1000D01*
G37*
G36*
G01X1570790Y286064D02*
G03X1571021Y286576I-144J373D01*
G02X1573704Y286758I1315J487D01*
G03X1574027Y286277I391J-87D01*
G02X1572875Y283833I-237J-1382D01*
G03X1572321Y283802I-261J-303D01*
G02X1570790Y286064I-1028J953D01*
G37*
G36*
G01X560979Y284997D02*
G03X560608Y284565I28J-399D01*
G02X559116Y285846I-1397J-118D01*
G03X559487Y286278I-28J399D01*
G02X560979Y284997I1397J118D01*
G37*
G36*
G01X1315646Y285315D02*
G03X1315579Y284745I243J-318D01*
G02X1313636Y284974I-1089J-883D01*
G03X1313703Y285544I-243J318D01*
G02X1315646Y285315I1089J883D01*
G37*
G36*
G01X69311Y282571D02*
G03X69889I289J277D01*
G02Y280629I1011J-971D01*
G03X69311I-289J-277D01*
G02Y282571I-1011J971D01*
G37*
G36*
G01X1399552Y283306D02*
G03X1399680Y282764I343J-205D01*
G02X1397721Y282299I-754J-1182D01*
G03X1397593Y282841I-343J205D01*
G02X1399552Y283306I754J1182D01*
G37*
G36*
G01X1097703Y279975D02*
G03X1098242I269J295D01*
G02X1098239Y277904I944J-1037D01*
G03X1097700I-269J-295D01*
G02X1097703Y279975I-944J1037D01*
G37*
G36*
G01X448798Y277912D02*
G03X448198I-300J-265D01*
G02Y279770I-1050J929D01*
G03X448798I300J265D01*
G02Y277912I1050J-929D01*
G37*
G36*
G01X1434372Y279771D02*
G03Y279217I288J-277D01*
G02X1432352I-1010J-973D01*
G03Y279771I-288J277D01*
G02X1434372I1010J973D01*
G37*
G36*
G01X662303Y279878D02*
G03X662721Y279485I400J6D01*
G02X661384Y278062I65J-1401D01*
G03X660966Y278455I-400J-6D01*
G02X662303Y279878I-65J1401D01*
G37*
G36*
G01X60473Y279010D02*
G03X61027I277J288D01*
G02Y276990I973J-1010D01*
G03X60473I-277J-288D01*
G02Y279010I-973J1010D01*
G37*
G36*
G01X648422Y279263D02*
G03X648418Y278671I267J-298D01*
G02X646534Y278684I-949J-1032D01*
G03X646538Y279276I-267J298D01*
G02X648422Y279263I949J1032D01*
G37*
G36*
G01X1333680Y274524D02*
X1330171D01*
G02Y277546I0J1511D01*
G01X1333681D01*
G02X1335192Y276045I0J-1512D01*
G01Y275950D01*
X1335182Y275866D01*
G02X1333680Y274524I-1502J169D01*
G37*
G36*
G01X452389Y274629D02*
G03X451811I-289J-277D01*
G02Y276571I-1011J971D01*
G03X452389I289J277D01*
G02Y274629I1011J-971D01*
G37*
G36*
G01X778572Y275068D02*
G03X777973Y274913I-236J-323D01*
G02X777528Y276632I-1273J588D01*
G03X778127Y276787I236J323D01*
G02X778572Y275068I1273J-588D01*
G37*
G36*
G01X1637694Y276342D02*
G03Y275788I288J-277D01*
G02X1635674I-1010J-973D01*
G03Y276342I-288J277D01*
G02Y278288I1010J973D01*
G03Y278842I-288J277D01*
G02X1637694I1010J973D01*
G03Y278288I288J-277D01*
G02Y276342I-1010J-973D01*
G37*
G36*
G01X199827Y276169D02*
G03X199847Y276768I-254J308D01*
G02X199776Y276839I1097J1168D01*
G03X199204Y276852I-292J-273D01*
G02X197062Y279231I-1122J1144D01*
G03X197082Y279830I-254J308D01*
G02X199314Y282128I1100J1165D01*
G03X199867Y282116I283J283D01*
G02X202249Y281867I1080J-1183D01*
G03X202879Y281841I325J233D01*
G02X204855Y279865I1068J-908D01*
G03X204881Y279235I259J-305D01*
G02X204967Y276697I-934J-1302D01*
G03X204947Y276098I254J-308D01*
G02X202647Y273872I-1100J-1165D01*
G03X202047I-300J-265D01*
G02X199827Y276169I-1200J1062D01*
G37*
G36*
G01X824264Y273849D02*
G03X823664I-300J-265D01*
G02X821246Y275950I-1200J1061D01*
G03Y276470I-304J260D01*
G02Y278550I1218J1040D01*
G03Y279070I-304J260D01*
G02X823664Y281171I1218J1040D01*
G03X824264I300J265D01*
G02X826664I1200J-1061D01*
G03X827264I300J265D01*
G02X829664I1200J-1061D01*
G03X830264I300J265D01*
G02X832664I1200J-1061D01*
G03X833264I300J265D01*
G02X835584Y281255I1200J-1061D01*
G03X836144I280J286D01*
G02X838384I1120J-1145D01*
G03X838944I280J286D01*
G02X841282Y279070I1120J-1145D01*
G03Y278550I304J-260D01*
G02X838944Y276365I-1218J-1040D01*
G03X838384I-280J-286D01*
G02X838373Y276354I-1138J1127D01*
G03Y276066I139J-144D01*
G02X836144Y273765I-1109J-1156D01*
G03X835584I-280J-286D01*
G02X833264Y273849I-1120J1145D01*
G03X832664I-300J-265D01*
G02X830264I-1200J1061D01*
G03X829664I-300J-265D01*
G02X827264I-1200J1061D01*
G03X826664I-300J-265D01*
G02X824264I-1200J1061D01*
G37*
G36*
G01X850182Y273366D02*
G03X849582I-300J-265D01*
G02X847164Y275467I-1200J1061D01*
G03Y275987I-304J260D01*
G02X847199Y278107I1218J1040D01*
G03Y278647I-295J270D01*
G02X847164Y280767I1183J1080D01*
G03Y281287I-304J260D01*
G02X849582Y283388I1218J1040D01*
G03X850182I300J265D01*
G02X852582I1200J-1061D01*
G03X853182I300J265D01*
G02X855582I1200J-1061D01*
G03X856182I300J265D01*
G02X858600Y281287I1200J-1061D01*
G03Y280767I304J-260D01*
G02X858565Y278647I-1218J-1040D01*
G03Y278107I295J-270D01*
G02X858600Y275987I-1183J-1080D01*
G03Y275467I304J-260D01*
G02X856182Y273366I-1218J-1040D01*
G03X855582I-300J-265D01*
G02X853182I-1200J1061D01*
G03X852582I-300J-265D01*
G02X850182I-1200J1061D01*
G37*
G36*
G01X1340248Y270244D02*
X1336448D01*
G02Y273266I0J1511D01*
G01X1340249D01*
G02X1341760Y271765I0J-1512D01*
G01Y271670D01*
X1341750Y271586D01*
G02X1340248Y270244I-1502J169D01*
G37*
G36*
G01X184648Y273848D02*
G03X184644Y274431I-276J290D01*
G02X184615Y274459I1098J1166D01*
G03X184055I-280J-286D01*
G02X181823Y274451I-1120J1145D01*
G03X181203Y274371I-278J-288D01*
G02X178635Y274143I-1368J833D01*
G03X178035I-300J-265D01*
G02X175635I-1200J1061D01*
G03X175035I-300J-265D01*
G02X172617Y276244I-1200J1061D01*
G03Y276764I-304J260D01*
G02X175035Y278865I1218J1040D01*
G03X175635I300J265D01*
G02X178035I1200J-1061D01*
G03X178635I300J265D01*
G02X180947Y278957I1200J-1061D01*
G03X181567Y279037I278J288D01*
G02X184055Y279349I1368J-833D01*
G03X184615I280J286D01*
G02X186844Y279360I1120J-1145D01*
G03X187416Y279379I277J289D01*
G02X189679Y279484I1184J-1079D01*
G03X190239Y279504I270J295D01*
G02X190321Y277216I1161J-1104D01*
G03X189761Y277196I-270J-295D01*
G02X189758Y277193I-1134J1131D01*
G03X189745Y276654I289J-277D01*
G02X189613Y274419I-1210J-1050D01*
G03X189608Y273832I269J-296D01*
G02X189714Y271609I-1098J-1166D01*
G03X189707Y271089I300J-264D01*
G02X187392Y268885I-1232J-1023D01*
G03X186851I-271J-295D01*
G02X184552Y271108I-1083J1181D01*
G03X184550Y271633I-303J261D01*
G02X184648Y273848I1204J1056D01*
G37*
G36*
G01X1412345Y270158D02*
G03X1412700Y269670I390J-90D01*
G02X1411213Y268588I-121J-1397D01*
G03X1410858Y269076I-390J90D01*
G02X1412345Y270158I121J1397D01*
G37*
G36*
G01X1010655Y269874D02*
G03X1011064Y269502I399J28D01*
G02X1009701Y268003I36J-1402D01*
G03X1009292Y268375I-399J-28D01*
G02X1007949Y269270I-36J1402D01*
G03X1007382Y269475I-373J-145D01*
G02X1005785Y271762I-682J1225D01*
G03X1005777Y272375I-261J303D01*
G02X1007580Y272398I888J1085D01*
G03X1007588Y271785I261J-303D01*
G02X1008007Y271207I-888J-1085D01*
G03X1008574Y271002I373J145D01*
G02X1010655Y269874I682J-1225D01*
G37*
G36*
G01X361047D02*
G03X361456Y269502I399J28D01*
G02X360093Y268003I36J-1402D01*
G03X359684Y268375I-399J-28D01*
G02X358341Y269270I-36J1402D01*
G03X357774Y269475I-373J-145D01*
G02X356177Y271762I-682J1225D01*
G03X356169Y272375I-261J303D01*
G02X357972Y272398I888J1085D01*
G03X357980Y271785I261J-303D01*
G02X358399Y271207I-888J-1085D01*
G03X358966Y271002I373J145D01*
G02X361047Y269874I682J-1225D01*
G37*
G36*
G01X1347468Y266584D02*
X1343668D01*
G02Y269606I0J1511D01*
G01X1347469D01*
G02X1348980Y268105I0J-1512D01*
G01Y268010D01*
X1348970Y267926D01*
G02X1347468Y266584I-1502J169D01*
G37*
G36*
G01X748148Y268571D02*
G03X748170Y269192I-241J319D01*
G02X749932Y269129I920J1058D01*
G03X749910Y268508I241J-319D01*
G02X748148Y268571I-920J-1058D01*
G37*
G36*
G01X773929Y267748D02*
G03X774446Y267632I324J234D01*
G02X774006Y265368I725J-1316D01*
G03X773483Y265454I-310J-253D01*
G02X771490Y265684I-853J1356D01*
G03X770892Y265652I-285J-281D01*
G02X768945Y268092I-1255J995D01*
G03X769114Y268660I-173J361D01*
G02X771987Y268933I1371J829D01*
G03X772416Y268398I375J-139D01*
G02X773929Y267748I214J-1588D01*
G37*
G36*
G01X1356268Y264184D02*
X1352468D01*
G02Y267206I0J1511D01*
G01X1356269D01*
G02X1357780Y265705I0J-1512D01*
G01Y265610D01*
X1357770Y265526D01*
G02X1356268Y264184I-1502J170D01*
G37*
G36*
G01X1217244Y267082D02*
G03Y266528I288J-277D01*
G02X1215224I-1010J-973D01*
G03Y267082I-288J277D01*
G02X1217244I1010J973D01*
G37*
G36*
G01X567936D02*
G03Y266528I288J-277D01*
G02X565916I-1010J-973D01*
G03Y267082I-288J277D01*
G02X567936I1010J973D01*
G37*
G36*
G01X1381031Y264088D02*
X1377522D01*
G02Y267112I0J1512D01*
G01X1381032D01*
G02X1382542Y265610I-1J-1512D01*
G01Y265515D01*
X1382533Y265431D01*
G02X1381031Y264088I-1502J168D01*
G37*
G36*
G01X1362803Y267036D02*
X1366313D01*
G02X1367824Y265535I0J-1512D01*
G01Y265440D01*
X1367814Y265356D01*
G02X1366312Y264014I-1502J169D01*
G01X1362803D01*
G02Y267036I1J1511D01*
G37*
G36*
G01X437620Y263877D02*
G03X437658Y263359I322J-237D01*
G02X435228Y263181I-1139J-1127D01*
G03X435190Y263699I-322J237D01*
G02X437620Y263877I1139J1127D01*
G37*
G36*
G01X1628763Y261318D02*
G03X1628481Y260782I90J-390D01*
G02X1626286Y261349I-1304J-515D01*
G03X1626299Y261955I-255J309D01*
G02X1628763Y261318I1843J2044D01*
G37*
G36*
G01X1160308Y261401D02*
G03X1160313Y260793I262J-302D01*
G02X1158492Y260779I-902J-1073D01*
G03X1158487Y261387I-262J302D01*
G02X1160308Y261401I902J1073D01*
G37*
G36*
G01X1455205Y261089D02*
G03X1455127Y260534I244J-317D01*
G02X1453298Y260914I-1127J-834D01*
G03X1453342Y261226I-100J173D01*
G02X1453256Y261323I1005J978D01*
G03X1452944I-156J-125D01*
G02X1452823Y263210I-1094J877D01*
G03X1453377I277J288D01*
G02X1455205Y261089I972J-1010D01*
G37*
G36*
G01X1226918Y260827D02*
G03Y260273I288J-277D01*
G02X1224898I-1010J-973D01*
G03Y260827I-288J277D01*
G02X1226918I1010J973D01*
G37*
G36*
G01X576610D02*
G03Y260273I288J-277D01*
G02X574590I-1010J-973D01*
G03Y260827I-288J277D01*
G02X576610I1010J973D01*
G37*
G36*
G01X510478Y259111D02*
G03X510102Y258672I22J-399D01*
G02X508630Y259932I-1395J-140D01*
G03X509006Y260371I-22J399D01*
G02X510478Y259111I1395J140D01*
G37*
G36*
G01X1494858Y254727D02*
G03X1494307Y254648I-235J-324D01*
G02X1494023Y256641I-1108J859D01*
G03X1494574Y256720I235J324D01*
G02X1494678Y256839I1106J-861D01*
G03X1494681Y257394I-287J279D01*
G02X1496700Y257383I1015J967D01*
G03X1496697Y256828I287J-279D01*
G02X1494858Y254727I-1015J-967D01*
G37*
G36*
G01X1465810Y255243D02*
G03X1465890Y254676I316J-244D01*
G02X1463781Y252976I-827J-1132D01*
G03X1463257Y253182I-366J-161D01*
G02X1462861Y255863I-553J1288D01*
G03X1463304Y256225I44J398D01*
G02X1465810Y255243I1396J-125D01*
G37*
G36*
G01X621974Y254930D02*
G03X621904Y254340I231J-327D01*
G02X620041Y254561I-1054J-924D01*
G03X620111Y255151I-231J327D01*
G02X621974Y254930I1054J924D01*
G37*
G36*
G01X1275468Y254991D02*
G03X1275795Y254508I390J-88D01*
G02X1274209Y253432I-218J-1385D01*
G03X1273882Y253915I-390J88D01*
G02X1275468Y254991I218J1385D01*
G37*
G36*
G01X116610Y252884D02*
G03X116164Y253251I-399J-30D01*
G02X115528Y255963I-163J1392D01*
G03X115764Y256490I-135J377D01*
G02X117535Y255696I1299J526D01*
G03X117299Y255169I135J-377D01*
G02X117398Y254750I-1299J-528D01*
G03X117844Y254383I399J30D01*
G02X116610Y252884I164J-1392D01*
G37*
G36*
G01X1469444Y253888D02*
G03X1469999Y253876I284J282D01*
G02X1469956Y251858I951J-1030D01*
G03X1469401Y251870I-284J-282D01*
G02X1469444Y253888I-951J1030D01*
G37*
G36*
G01X766693Y253259D02*
G03X766354Y252751I45J-397D01*
G02X764846Y253756I-1347J-388D01*
G03X765185Y254264I-45J397D01*
G02X765602Y255701I1347J388D01*
G03X765624Y256278I-266J299D01*
G02X767562Y256203I1008J974D01*
G03X767540Y255626I266J-299D01*
G02X766693Y253259I-1008J-974D01*
G37*
G36*
G01X1479777Y253333D02*
G03X1479666Y252778I222J-333D01*
G02X1477723Y253167I-1166J-778D01*
G03X1477834Y253722I-222J333D01*
G02X1477627Y254782I1166J778D01*
G03X1477271Y255261I-392J80D01*
G02X1478770Y256375I126J1396D01*
G03X1479126Y255896I392J-80D01*
G02X1479777Y253333I-126J-1396D01*
G37*
G36*
G01X1434852Y253400D02*
G03X1434985Y252823I328J-228D01*
G02X1433148Y252400I-686J-1223D01*
G03X1433015Y252977I-328J228D01*
G02X1434852Y253400I686J1223D01*
G37*
G36*
G01X1817282Y248886D02*
X1812281D01*
G02X1812282Y252110I1J1612D01*
G01X1817282D01*
G02X1818894Y250508I0J-1612D01*
G01Y250413D01*
X1818884Y250328D01*
G02X1817282Y248886I-1602J169D01*
G37*
G36*
G01X1798384D02*
X1793384D01*
G02Y252110I0J1612D01*
G01X1798385D01*
G02X1799996Y250508I-1J-1612D01*
G01Y250413D01*
X1799986Y250328D01*
G02X1798384Y248886I-1602J169D01*
G37*
G36*
G01X1825702Y251794D02*
G03X1826143Y251395I400J-1D01*
G02X1824885Y250006I144J-1395D01*
G03X1824444Y250405I-400J1D01*
G02X1825702Y251794I-144J1395D01*
G37*
G36*
G01X1736800Y248939D02*
G03X1736200I-300J-265D01*
G02Y251061I-1200J1061D01*
G03X1736800I300J265D01*
G02X1739200I1200J-1061D01*
G03X1739800I300J265D01*
G02Y248939I1200J-1061D01*
G03X1739200I-300J-265D01*
G02X1736800I-1200J1061D01*
G37*
G36*
G01X1690282Y249679D02*
G03X1689813Y249382I-80J-392D01*
G02X1687183Y249118I-1362J334D01*
G03X1686664Y249315I-362J-171D01*
G02X1685186Y249552I-551J1289D01*
G03X1684632Y249528I-265J-300D01*
G02X1684542Y251545I-1017J965D01*
G03X1685096Y251569I265J300D01*
G02X1687381Y251202I1017J-965D01*
G03X1687900Y251005I362J171D01*
G02X1688734Y251089I551J-1289D01*
G03X1689203Y251386I80J392D01*
G02X1690282Y249679I1362J-334D01*
G37*
G36*
G01X1597653Y247276D02*
G03X1598245Y247267I300J264D01*
G02X1598217Y245384I1025J-957D01*
G03X1597625Y245393I-300J-264D01*
G02X1597653Y247276I-1025J957D01*
G37*
G36*
G01X199940Y245395D02*
G03X199360I-290J-275D01*
G02X197139Y247700I-1160J1105D01*
G03Y248300I-265J300D01*
G02Y250700I1061J1200D01*
G03Y251300I-265J300D01*
G02X197118Y251319I1064J1197D01*
G03X196499Y251219I-270J-295D01*
G02X196182Y253181I-1399J781D01*
G03X196801Y253281I270J295D01*
G02X199400Y253561I1399J-781D01*
G03X200000I300J265D01*
G02X202400I1200J-1061D01*
G03X203000I300J265D01*
G02X205400I1200J-1061D01*
G03X206000I300J265D01*
G02X208261Y251300I1200J-1061D01*
G03Y250700I265J-300D01*
G02X207939Y248078I-1061J-1200D01*
G03X207829Y247452I184J-355D01*
G02X205774Y245545I-1029J-952D01*
G03X205165Y245517I-293J-273D01*
G02X202780Y245355I-1265J983D01*
G03X202220I-280J-286D01*
G02X199940Y245395I-1120J1145D01*
G37*
G36*
G01X1468298Y245076D02*
G03X1467721Y244868I-201J-345D01*
G02X1467110Y246561I-1317J482D01*
G03X1467687Y246769I201J345D01*
G02X1470015Y247258I1317J-482D01*
G03X1470593I289J277D01*
G02Y245316I1011J-971D01*
G03X1470015I-289J-277D01*
G02X1468298Y245076I-1011J971D01*
G37*
G36*
G01X1510804Y246222D02*
G03X1510800Y245658I282J-284D01*
G02X1508810Y245669I-1000J-982D01*
G03X1508814Y246233I-282J284D01*
G02X1510804Y246222I1000J982D01*
G37*
G36*
G01X89240Y260118D02*
G03X89760I260J304D01*
G02X91840I1040J-1218D01*
G03X92360I260J304D01*
G02X94440I1040J-1218D01*
G03X94960I260J304D01*
G02X97040I1040J-1218D01*
G03X97560I260J304D01*
G02X99818Y257860I1040J-1218D01*
G03Y257340I304J-260D01*
G02X99705Y255140I-1218J-1040D01*
G03Y254560I275J-290D01*
G02X99661Y252200I-1105J-1160D01*
G03Y251600I265J-300D01*
G02Y249200I-1061J-1200D01*
G03Y248600I265J-300D01*
G02Y246200I-1061J-1200D01*
G03Y245600I265J-300D01*
G02X97560Y243182I-1061J-1200D01*
G03X97040I-260J-304D01*
G02X94960I-1040J1218D01*
G03X94440I-260J-304D01*
G02X92360I-1040J1218D01*
G03X91840I-260J-304D01*
G02X89760I-1040J1218D01*
G03X89240I-260J-304D01*
G02X87139Y245600I-1040J1218D01*
G03Y246200I-265J300D01*
G02Y248600I1061J1200D01*
G03Y249200I-265J300D01*
G02Y251600I1061J1200D01*
G03Y252200I-265J300D01*
G02X87095Y254560I1061J1200D01*
G03Y255140I-275J290D01*
G02X86982Y257340I1105J1160D01*
G03Y257860I-304J260D01*
G02X89240Y260118I1218J1040D01*
G37*
G36*
G01X1662588Y245377D02*
G03X1662981Y244984I400J7D01*
G02X1661554Y243557I-25J-1402D01*
G03X1661161Y243950I-400J-7D01*
G02X1662588Y245377I25J1402D01*
G37*
G36*
G01X1215804Y244399D02*
G03X1216413Y244396I306J258D01*
G02X1216404Y242579I1063J-914D01*
G03X1215795Y242582I-306J-258D01*
G02X1215804Y244399I-1063J914D01*
G37*
G36*
G01X569422Y242495D02*
G03X568860Y242491I-279J-286D01*
G02X566796Y242579I-992J991D01*
G03X566187Y242582I-306J-258D01*
G02X566196Y244399I-1063J914D01*
G03X566805Y244396I306J258D01*
G02X568846Y244487I1063J-914D01*
G03X569408Y244491I279J286D01*
G02X569422Y242495I992J-991D01*
G37*
G36*
G01X1548542Y245073D02*
G03X1548652Y244519I333J-222D01*
G02X1546702Y244133I-783J-1163D01*
G03X1546592Y244687I-333J222D01*
G02X1548542Y245073I783J1163D01*
G37*
G36*
G01X1515570Y244955D02*
G03Y244424I299J-266D01*
G02X1513172Y244422I-1198J-1063D01*
G03Y244953I-299J265D01*
G02X1513153Y247057I1198J1063D01*
G03Y247577I-304J260D01*
G02X1515589Y247575I1219J1039D01*
G03Y247055I304J-260D01*
G02X1515570Y244955I-1219J-1039D01*
G37*
G36*
G01X1626025Y242615D02*
G03X1626599Y242478I350J194D01*
G02X1625390Y240152I1543J-2279D01*
G03X1624948Y240543I-400J-7D01*
G02X1626025Y242615I-150J1394D01*
G37*
G36*
G01X1779451Y236100D02*
X1774450D01*
G02X1774451Y239324I1J1612D01*
G01X1779451D01*
G02X1781062Y237722I0J-1611D01*
G01Y237627D01*
X1781053Y237542D01*
G02X1779451Y236100I-1602J169D01*
G37*
G36*
G01X1760554D02*
X1755554D01*
G02Y239324I0J1612D01*
G01X1760555D01*
G02X1762166Y237722I-1J-1612D01*
G01Y237627D01*
X1762156Y237542D01*
G02X1760554Y236100I-1602J169D01*
G37*
G36*
G01X642759Y237588D02*
G03Y237068I304J-260D01*
G02X640323I-1218J-1040D01*
G03Y237588I-304J260D01*
G02Y239668I1218J1040D01*
G03Y240188I-304J260D01*
G02Y242268I1218J1040D01*
G03Y242788I-304J260D01*
G02X642759I1218J1040D01*
G03Y242268I304J-260D01*
G02Y240188I-1218J-1040D01*
G03Y239668I304J-260D01*
G02Y237588I-1218J-1040D01*
G37*
G36*
G01X1572141Y234659D02*
G03X1571596Y234427I-167J-363D01*
G02X1570861Y236161I-1324J462D01*
G03X1571406Y236393I167J363D01*
G02X1572753Y237333I1324J-462D01*
G03X1573159Y237717I6J400D01*
G02X1573165Y237800I1401J-60D01*
G03X1572933Y238017I-199J20D01*
G02X1572213Y238085I-233J1383D01*
G03X1571684Y237800I-139J-375D01*
G02X1570805Y239431I-1366J316D01*
G03X1571334Y239716I139J375D01*
G02X1573024Y240764I1366J-316D01*
G03X1573512Y241097I92J389D01*
G02X1574377Y239599I1388J-197D01*
G03X1574102Y239412I-75J-185D01*
G02X1574095Y239260I-1402J-12D01*
G03X1574327Y239043I199J-20D01*
G02X1574537Y236258I232J-1383D01*
G03X1574131Y235874I-6J-400D01*
G02X1572141Y234659I-1401J57D01*
G37*
G36*
G01X772003Y236299D02*
G03X771937Y235762I260J-304D01*
G02X769730Y236157I-1305J-929D01*
G03X769767Y236455I-112J165D01*
G02X769672Y236574I1203J1058D01*
G03X769385Y236612I-162J-118D01*
G02X769575Y238930I-1003J1249D01*
G03X770091Y238862I298J267D01*
G02X772027Y238718I873J-1343D01*
G03X772594Y238754I266J299D01*
G02X772738Y236501I1206J-1054D01*
G03X772171Y236465I-266J-299D01*
G02X772003Y236299I-1207J1053D01*
G37*
G36*
G01X1844293Y237781D02*
G03X1844175Y237187I197J-348D01*
G02X1839851Y237383I-2246J-1757D01*
G03X1839724Y238022I-291J274D01*
G02X1841617Y238819I576J1278D01*
G03X1841985Y238281I376J-138D01*
G02X1842075Y238278I-50J-2851D01*
G03X1842275Y238543I11J200D01*
G02X1844293Y237781I1325J457D01*
G37*
G36*
G01X1682700Y234573D02*
G03X1683292Y234554I305J259D01*
G02X1683232Y232671I1008J-975D01*
G03X1682640Y232690I-305J-259D01*
G02X1682700Y234573I-1008J975D01*
G37*
G36*
G01X1767985Y232438D02*
G03X1767403Y232224I-204J-344D01*
G02X1766792Y233887I-1326J457D01*
G03X1767374Y234101I204J344D01*
G02X1767985Y232438I1326J-457D01*
G37*
G36*
G01X1804379Y233482D02*
G03X1805001Y233476I313J248D01*
G02X1804984Y231713I1082J-892D01*
G03X1804362Y231719I-313J-248D01*
G02X1804379Y233482I-1082J892D01*
G37*
G36*
G01X1794608Y234126D02*
G03X1794630Y233549I288J-278D01*
G02X1792692Y233474I-930J-1049D01*
G03X1792670Y234051I-288J278D01*
G02X1794608Y234126I930J1049D01*
G37*
G36*
G01X1883239Y233459D02*
G03X1883271Y232890I296J-269D01*
G02X1881306Y232778I-926J-1053D01*
G03X1881274Y233347I-296J269D01*
G02X1882924Y235600I926J1052D01*
G03X1883468Y235728I206J343D01*
G02X1883927Y233775I1183J-752D01*
G03X1883383Y233647I-206J-343D01*
G02X1883239Y233459I-1181J755D01*
G37*
G36*
G01X824272Y230535D02*
G03X823747Y230530I-260J-304D01*
G02X821464Y232767I-1064J1197D01*
G03Y233287I-304J260D01*
G02X821499Y235407I1218J1040D01*
G03Y235947I-295J270D01*
G02X821464Y238067I1183J1080D01*
G03Y238587I-304J260D01*
G02X823882Y240688I1218J1040D01*
G03X824482I300J265D01*
G02X826882I1200J-1061D01*
G03X827482I300J265D01*
G02X829882I1200J-1061D01*
G03X830482I300J265D01*
G02X832882I1200J-1061D01*
G03X833482I300J265D01*
G02X835861Y240712I1200J-1061D01*
G03X836424Y240687I294J271D01*
G02X838625Y238360I1076J-1187D01*
G03Y237790I281J-285D01*
G02X839043Y236218I-1125J-1141D01*
G03X839573Y235738I385J-108D01*
G02X839180Y232974I582J-1493D01*
G03X838650Y232935I-243J-318D01*
G02X836319Y232968I-1150J1115D01*
G03X835759Y232998I-295J-270D01*
G02X833448Y233200I-1059J1202D01*
G03X832845Y233226I-313J-249D01*
G02X830482Y233266I-1163J1101D01*
G03X829882I-300J-265D01*
G02X829668Y233064I-1202J1059D01*
G03X829567Y232549I246J-316D01*
G02X827031Y230632I-1387J-800D01*
G03X826458Y230633I-287J-279D01*
G02X824272Y230535I-1145J1120D01*
G37*
G36*
G01X1926924Y232852D02*
G03X1926983Y232289I311J-252D01*
G02X1925011Y232083I-883J-1089D01*
G03X1924952Y232646I-311J252D01*
G02X1926924Y232852I883J1089D01*
G37*
G36*
G01X186410Y240955D02*
G03X186979Y240945I289J276D01*
G02X189200Y238635I1121J-1145D01*
G03X189220Y238036I274J-291D01*
G02X189384Y235721I-1020J-1236D01*
G03X189404Y235161I295J-270D01*
G02X186995Y233070I-1105J-1160D01*
G03X186386Y233120I-326J-232D01*
G02X184090Y233145I-1136J1130D01*
G03X183521Y233155I-289J-276D01*
G02X181200Y233239I-1121J1145D01*
G03X180600I-300J-265D01*
G02X178200I-1200J1061D01*
G03X177600I-300J-265D01*
G02X177512Y233147I-1201J1060D01*
G03X177524Y232848I139J-144D01*
G02X175332Y230521I-1017J-1238D01*
G03X174711Y230479I-294J-272D01*
G02X172295Y232560I-1311J921D01*
G03Y233140I-275J290D01*
G02X172217Y235380I1105J1160D01*
G03Y235920I-295J270D01*
G02X172295Y238160I1183J1080D01*
G03Y238740I-275J290D01*
G02X174600Y240961I1105J1160D01*
G03X175200I300J265D01*
G02X177600I1200J-1061D01*
G03X178200I300J265D01*
G02X180600I1200J-1061D01*
G03X181200I300J265D01*
G02X183560Y241005I1200J-1061D01*
G03X184129Y240995I289J276D01*
G02X186410Y240955I1121J-1145D01*
G37*
G36*
G01X1499741Y233065D02*
G03X1499981Y232510I360J-174D01*
G02X1498296Y231783I-422J-1337D01*
G03X1498056Y232338I-360J174D01*
G02X1499741Y233065I422J1337D01*
G37*
G36*
G01X578805Y232720D02*
G03X578809Y232141I278J-288D01*
G02X576876Y232128I-960J-1022D01*
G03X576872Y232707I-278J288D01*
G02X578805Y232720I960J1022D01*
G37*
G36*
G01X1387761Y232456D02*
G03X1388231Y232161I388J96D01*
G02X1387157Y230451I287J-1372D01*
G03X1386687Y230746I-388J-96D01*
G02X1387761Y232456I-287J1372D01*
G37*
G36*
G01X1968220Y228637D02*
G03X1967580I-320J-240D01*
G02Y230563I-1280J963D01*
G03X1968220I320J240D01*
G02Y228637I1280J-963D01*
G37*
G36*
G01X571477Y230511D02*
G03X571449Y229950I270J-295D01*
G02X569455Y230047I-1045J-935D01*
G03X569483Y230608I-270J295D01*
G02X571477Y230511I1045J935D01*
G37*
G36*
G01X1939229Y229179D02*
G03X1939773Y229172I276J290D01*
G02X1939745Y226821I1074J-1188D01*
G03X1939201Y226828I-276J-290D01*
G02X1939229Y229179I-1074J1188D01*
G37*
G36*
G01X89640Y237668D02*
G03X90160I260J304D01*
G02X92240I1040J-1218D01*
G03X92760I260J304D01*
G02X94840I1040J-1218D01*
G03X95360I260J304D01*
G02X97440I1040J-1218D01*
G03X97960I260J304D01*
G02X100061Y235250I1040J-1218D01*
G03Y234650I265J-300D01*
G02Y232250I-1061J-1200D01*
G03Y231650I265J-300D01*
G02Y229250I-1061J-1200D01*
G03Y228650I265J-300D01*
G02X97960Y226232I-1061J-1200D01*
G03X97440I-260J-304D01*
G02X95360I-1040J1218D01*
G03X94840I-260J-304D01*
G02X92760I-1040J1218D01*
G03X92240I-260J-304D01*
G02X90160I-1040J1218D01*
G03X89640I-260J-304D01*
G02X87539Y228650I-1040J1218D01*
G03Y229250I-265J300D01*
G02Y231650I1061J1200D01*
G03Y232250I-265J300D01*
G02Y234650I1061J1200D01*
G03Y235250I-265J300D01*
G02X89640Y237668I1061J1200D01*
G37*
G36*
G01X703380Y225694D02*
G03X702770I-305J-259D01*
G02Y227506I-1070J906D01*
G03X703380I305J259D01*
G02Y225694I1070J-906D01*
G37*
G36*
G01X1253531Y228169D02*
G03X1253880Y227627I374J-143D01*
G02X1252796Y225241I-89J-1399D01*
G03X1252264Y225273I-284J-282D01*
G02X1250295Y225504I-869J1100D01*
G03X1249691Y225531I-314J-248D01*
G02X1249772Y227363I-1019J963D01*
G03X1250376Y227336I314J248D01*
G02X1250745Y227615I1018J-963D01*
G03X1250929Y228125I-185J355D01*
G02X1253531Y228169I1292J543D01*
G37*
G36*
G01X1945635Y227689D02*
G03X1945738Y227143I334J-220D01*
G02X1943753Y226770I-813J-1142D01*
G03X1943650Y227316I-334J220D01*
G02X1945635Y227689I813J1142D01*
G37*
G36*
G01X1627679Y224282D02*
G03X1627124Y224267I-270J-295D01*
G02X1627069Y226286I-1000J983D01*
G03X1627624Y226301I270J295D01*
G02X1627679Y224282I1000J-983D01*
G37*
G36*
G01X1883427Y223090D02*
G03X1882873I-277J-288D01*
G02Y225110I-973J1010D01*
G03X1883427I277J288D01*
G02Y223090I973J-1010D01*
G37*
G36*
G01X1401311Y222717D02*
G03X1400689I-311J-252D01*
G02Y224483I-1089J883D01*
G03X1401311I311J252D01*
G02Y222717I1089J-883D01*
G37*
G36*
G01X1622167Y224930D02*
G03Y224372I286J-279D01*
G02X1620161I-1003J-980D01*
G03Y224930I-286J279D01*
G02X1622167I1003J980D01*
G37*
G36*
G01X1245144Y223407D02*
G03X1244700Y223029I-44J-398D01*
G02X1243456Y224493I-1400J71D01*
G03X1243900Y224871I44J398D01*
G02X1245144Y223407I1400J-71D01*
G37*
G36*
G01X767662Y224140D02*
G03X767640Y223563I266J-299D01*
G02X765702Y223638I-1008J-974D01*
G03X765724Y224215I-266J299D01*
G02X767662Y224140I1008J974D01*
G37*
G36*
G01X638219Y223697D02*
G03Y223177I304J-260D01*
G02X635783I-1218J-1040D01*
G03Y223697I-304J260D01*
G02Y225777I1218J1040D01*
G03Y226297I-304J260D01*
G02Y228377I1218J1040D01*
G03Y228897I-304J260D01*
G02X638219I1218J1040D01*
G03Y228377I304J-260D01*
G02Y226297I-1218J-1040D01*
G03Y225777I304J-260D01*
G02Y223697I-1218J-1040D01*
G37*
G36*
G01X714708Y223170D02*
G03X714730Y222593I288J-278D01*
G02X712792Y222518I-930J-1049D01*
G03X712770Y223095I-288J278D01*
G02X714708Y223170I930J1049D01*
G37*
G36*
G01X115652Y224178D02*
G03X115823Y224709I-187J353D01*
G02X117738Y224092I1257J621D01*
G03X117567Y223561I187J-353D01*
G02X117707Y222824I-1257J-621D01*
G03X118084Y222391I399J-34D01*
G02X116611Y221107I-76J-1400D01*
G03X116234Y221540I-399J34D01*
G02X115652Y224178I76J1400D01*
G37*
G36*
G01X1911372Y222246D02*
G03X1911367Y221696I288J-278D01*
G02X1909230Y221597I-1027J-955D01*
G03X1909174Y222144I-317J244D01*
G02X1909022Y224423I1045J1214D01*
G03X1909009Y224969I-299J266D01*
G02X1911350Y225025I1144J1121D01*
G03X1911363Y224479I299J-266D01*
G02X1911372Y222246I-1144J-1121D01*
G37*
G36*
G01X1627988Y218701D02*
G03X1628578Y218690I300J264D01*
G02X1628542Y216799I1017J-965D01*
G03X1627952Y216810I-300J-264D01*
G02X1627988Y218701I-1017J965D01*
G37*
G36*
G01X94077Y218891D02*
G03X94053Y219509I-266J299D01*
G02X93755Y219794I1088J1436D01*
G03X93150Y219805I-307J-256D01*
G02X90389Y219899I-1341J1204D01*
G03X89779Y219922I-315J-247D01*
G02X87038Y220013I-1332J1214D01*
G03X86446Y220050I-313J-249D01*
G02X86597Y222464I-1258J1290D01*
G03X87189Y222427I313J249D01*
G02X89867Y222246I1258J-1291D01*
G03X90477Y222223I315J247D01*
G02X93194Y222161I1332J-1214D01*
G03X93799Y222150I307J256D01*
G02X96338Y219600I1341J-1204D01*
G03X96362Y218982I266J-299D01*
G02X94077Y218891I-1087J-1437D01*
G37*
G36*
G01X1592264Y213948D02*
G03X1591703Y213814I-216J-337D01*
G02X1589500Y215513I-1208J711D01*
G03X1589507Y216069I-284J282D01*
G02X1590941Y218372I1018J964D01*
G03X1591421Y218583I118J382D01*
G02X1593973Y216738I1449J-683D01*
G03X1593975Y216155I275J-291D01*
G02X1592264Y213948I-955J-1026D01*
G37*
G36*
G01X1898421Y215540D02*
G03Y214962I277J-289D01*
G02X1896479I-971J-1011D01*
G03Y215540I-277J289D01*
G02X1898421I971J1011D01*
G37*
G36*
G01X1612670Y215183D02*
G03Y214574I260J-305D01*
G02X1610852I-909J-1067D01*
G03Y215183I-260J304D01*
G02X1612670I909J1067D01*
G37*
G36*
G01X715613Y215122D02*
G03X715771Y214575I349J-196D01*
G02X713878Y214031I-671J-1231D01*
G03X713720Y214578I-349J196D01*
G02X714134Y217187I671J1231D01*
G03X714431Y217733I-73J393D01*
G02X715984Y216889I1296J534D01*
G03X715687Y216343I73J-393D01*
G02X715613Y215122I-1296J-534D01*
G37*
G36*
G01X591383Y214711D02*
G03Y214089I252J-311D01*
G02X589617I-883J-1089D01*
G03Y214711I-252J311D01*
G02X591383I883J1089D01*
G37*
G36*
G01X824127Y213264D02*
G03X823755Y212761I14J-400D01*
G02X821097Y212917I-1355J-361D01*
G03X820873Y213437I-372J148D01*
G02X820418Y216137I593J1488D01*
G03X820480Y216674I-262J302D01*
G02X822907Y218751I1295J944D01*
G03X823440Y218723I282J283D01*
G02X825615Y218572I1006J-1247D01*
G03X826189Y218563I291J274D01*
G02X828825Y216876I1133J-1133D01*
G03X829226Y216339I375J-138D01*
G02X830502Y215829I101J-1599D01*
G03X831091Y215832I293J272D01*
G02X831101Y213665I1185J-1078D01*
G03X830512Y213662I-293J-272D01*
G02X828247Y213556I-1185J1078D01*
G03X827723Y213569I-269J-295D01*
G02X825620Y213619I-1023J1233D01*
G03X825095Y213632I-270J-295D01*
G02X824127Y213264I-1023J1233D01*
G37*
G36*
G01X1814125Y210720D02*
X1809125D01*
G02Y213742I0J1511D01*
G01X1814126D01*
G02X1815636Y212241I-1J-1511D01*
G01Y212146D01*
X1815627Y212062D01*
G02X1814125Y210720I-1502J169D01*
G37*
G36*
G01X1801526D02*
X1796526D01*
G02Y213742I0J1511D01*
G01X1801527D01*
G02X1803038Y212241I0J-1512D01*
G01Y212146D01*
X1803028Y212062D01*
G02X1801526Y210720I-1502J169D01*
G37*
G36*
G01X1826685Y210650D02*
X1821685D01*
G02Y213672I0J1511D01*
G01X1826686D01*
G02X1828196Y212171I-1J-1511D01*
G01Y212076D01*
X1828187Y211992D01*
G02X1826685Y210650I-1502J169D01*
G37*
G36*
G01X778862Y211127D02*
G03X778252I-305J-259D01*
G02Y212939I-1070J906D01*
G03X778862I305J259D01*
G02Y211127I1070J-906D01*
G37*
G36*
G01X129393Y210985D02*
G03X128822Y210945I-266J-299D01*
G02X128685Y212901I-1068J908D01*
G03X129256Y212941I266J299D01*
G02X129393Y210985I1068J-908D01*
G37*
G36*
G01X1788925Y210120D02*
X1783925D01*
G02Y213142I0J1511D01*
G01X1788926D01*
G02X1790436Y211641I-1J-1511D01*
G01Y211546D01*
X1790427Y211462D01*
G02X1788925Y210120I-1502J169D01*
G37*
G36*
G01X1776325D02*
X1771325D01*
G02Y213142I0J1511D01*
G01X1776326D01*
G02X1777836Y211641I-1J-1511D01*
G01Y211546D01*
X1777827Y211462D01*
G02X1776325Y210120I-1502J169D01*
G37*
G36*
G01X1763725D02*
X1758725D01*
G02Y213142I0J1511D01*
G01X1763726D01*
G02X1765236Y211641I-1J-1511D01*
G01Y211546D01*
X1765227Y211462D01*
G02X1763725Y210120I-1502J169D01*
G37*
G36*
G01X1751125D02*
X1746125D01*
G02Y213142I0J1511D01*
G01X1751126D01*
G02X1752636Y211641I-1J-1511D01*
G01Y211546D01*
X1752627Y211462D01*
G02X1751125Y210120I-1502J169D01*
G37*
G36*
G01X1738484D02*
X1733484D01*
G02Y213142I0J1511D01*
G01X1738485D01*
G02X1739996Y211641I0J-1512D01*
G01Y211546D01*
X1739986Y211462D01*
G02X1738484Y210120I-1502J169D01*
G37*
G36*
G01X1863263Y210799D02*
G03X1862670Y210713I-259J-305D01*
G02X1860096Y211423I-1173J768D01*
G03X1859676Y211806I-400J-16D01*
G02X1861005Y213264I-72J1400D01*
G03X1861425Y212881I400J16D01*
G02X1862404Y212551I73J-1400D01*
G03X1862997Y212637I259J305D01*
G02X1863263Y210799I1173J-769D01*
G37*
G36*
G01X1726480Y210155D02*
G03X1725920I-280J-286D01*
G02Y212445I-1120J1145D01*
G03X1726480I280J286D01*
G02Y210155I1120J-1145D01*
G37*
G36*
G01X89628Y210958D02*
G03X89293Y210468I54J-396D01*
G02X85796Y210488I-1751J-425D01*
G03X85362Y210984I-388J99D01*
G02X83439Y213322I-206J1790D01*
G03X83114Y213840I-381J122D01*
G02X85083Y215076I252J1784D01*
G03X85408Y214558I381J-122D01*
G02X85527Y214537I-253J-1784D01*
G03X85753Y214810I41J196D01*
G02X89158Y215043I1663J694D01*
G03X89516Y214541I387J-103D01*
G02X89697Y214519I-127J-1797D01*
G03X89921Y214781I35J197D01*
G02X91562Y213563I1705J583D01*
G03X91155Y213087I-14J-400D01*
G02X89628Y210958I-1769J-343D01*
G37*
G36*
G01X1358537Y208181D02*
G03X1357965Y208159I-275J-290D01*
G02X1357889Y210119I-1039J941D01*
G03X1358461Y210141I275J290D01*
G02X1360432Y210247I1039J-941D01*
G03X1360987Y210269I266J299D01*
G02X1361068Y208253I1013J-969D01*
G03X1360513Y208231I-266J-299D01*
G02X1358537Y208181I-1013J969D01*
G37*
G36*
G01X1227826Y209464D02*
G03X1227844Y208909I297J-268D01*
G02X1225826Y208843I-977J-1005D01*
G03X1225808Y209398I-297J268D01*
G02X1225814Y211414I977J1005D01*
G03Y211992I-277J289D01*
G02X1225978Y214149I971J1011D01*
G03X1226070Y214713I-230J327D01*
G02X1228007Y214397I1130J830D01*
G03X1227915Y213833I230J-327D01*
G02X1227756Y211992I-1130J-830D01*
G03Y211414I277J-289D01*
G02X1227826Y209464I-971J-1011D01*
G37*
G36*
G01X1475934Y208720D02*
G03X1475721Y208189I153J-369D01*
G02X1473906Y208918I-1282J-568D01*
G03X1474119Y209449I-153J369D01*
G02X1475934Y208720I1282J568D01*
G37*
G36*
G01X1479760Y208891D02*
G03X1479846Y208343I328J-229D01*
G02X1477851Y208029I-846J-1118D01*
G03X1477765Y208577I-328J229D01*
G02X1479760Y208891I846J1118D01*
G37*
G36*
G01X617675Y205984D02*
G03X617121I-277J-288D01*
G02Y208004I-973J1010D01*
G03X617675I277J288D01*
G02X617771Y208088I970J-1012D01*
G03Y208400I-125J156D01*
G02X619658Y208521I877J1094D01*
G03Y207967I288J-277D01*
G02X619742Y207871I-1012J-970D01*
G03X620054I156J125D01*
G02X622121Y208004I1094J-877D01*
G03X622675I277J288D01*
G02X622771Y208088I970J-1012D01*
G03Y208400I-125J156D01*
G02X622638Y210467I877J1094D01*
G03Y211021I-288J277D01*
G02X622554Y211117I1012J970D01*
G03X622242I-156J-125D01*
G02X622121Y213004I-1094J877D01*
G03X622675I277J288D01*
G02X622771Y213088I970J-1012D01*
G03Y213400I-125J156D01*
G02X622638Y215467I877J1094D01*
G03Y216021I-288J277D01*
G02X622554Y216117I1012J970D01*
G03X622242I-156J-125D01*
G02X622121Y218004I-1094J877D01*
G03X622675I277J288D01*
G02X622771Y218088I970J-1012D01*
G03Y218400I-125J156D01*
G02X622638Y220467I877J1094D01*
G03Y221021I-288J277D01*
G02X622554Y221117I1012J970D01*
G03X622242I-156J-125D01*
G02X622121Y223004I-1094J877D01*
G03X622675I277J288D01*
G02X622771Y223088I970J-1012D01*
G03Y223400I-125J156D01*
G02X622638Y225467I877J1094D01*
G03Y226021I-288J277D01*
G02X622554Y226117I1012J970D01*
G03X622242I-156J-125D01*
G02X620175Y225984I-1094J877D01*
G03X619621I-277J-288D01*
G02X619525Y225900I-970J1012D01*
G03Y225588I125J-156D01*
G02X617638Y225467I-877J-1094D01*
G03Y226021I-288J277D01*
G02X617554Y226117I1012J970D01*
G03X617242I-156J-125D01*
G02X615175Y225984I-1094J877D01*
G03X614621I-277J-288D01*
G02X614525Y225900I-970J1012D01*
G03Y225588I125J-156D01*
G02X614658Y223521I-877J-1094D01*
G03Y222967I288J-277D01*
G02X614742Y222871I-1012J-970D01*
G03X615054I156J125D01*
G02X615175Y220984I1094J-877D01*
G03X614621I-277J-288D01*
G02X614525Y220900I-970J1012D01*
G03Y220588I125J-156D01*
G02X614658Y218521I-877J-1094D01*
G03Y217967I288J-277D01*
G02X614742Y217871I-1012J-970D01*
G03X615054I156J125D01*
G02X615175Y215984I1094J-877D01*
G03X614621I-277J-288D01*
G02X614525Y215900I-970J1012D01*
G03Y215588I125J-156D01*
G02X614658Y213521I-877J-1094D01*
G03Y212967I288J-277D01*
G02X614742Y212871I-1012J-970D01*
G03X615054I156J125D01*
G02X615175Y210984I1094J-877D01*
G03X614621I-277J-288D01*
G02X614525Y210900I-970J1012D01*
G03Y210588I125J-156D01*
G02X612638Y210467I-877J-1094D01*
G03Y211021I-288J277D01*
G02Y212967I1010J973D01*
G03Y213521I-288J277D01*
G02Y215467I1010J973D01*
G03Y216021I-288J277D01*
G02Y217967I1010J973D01*
G03Y218521I-288J277D01*
G02Y220467I1010J973D01*
G03Y221021I-288J277D01*
G02X612554Y221117I1012J970D01*
G03X612242I-156J-125D01*
G02X610138Y222967I-1094J877D01*
G03Y223521I-288J277D01*
G02X610054Y223617I1012J970D01*
G03X609742I-156J-125D01*
G02X607638Y225467I-1094J877D01*
G03Y226021I-288J277D01*
G02X609658I1010J973D01*
G03Y225467I288J-277D01*
G02X609742Y225371I-1012J-970D01*
G03X610054I156J125D01*
G02X612121Y225504I1094J-877D01*
G03X612675I277J288D01*
G02X612771Y225588I970J-1012D01*
G03Y225900I-125J156D01*
G02X612638Y227967I877J1094D01*
G03Y228521I-288J277D01*
G02X612554Y228617I1012J970D01*
G03X612242I-156J-125D01*
G02X612121Y230504I-1094J877D01*
G03X612675I277J288D01*
G02X614658Y228521I973J-1010D01*
G03Y227967I288J-277D01*
G02X614742Y227871I-1012J-970D01*
G03X615054I156J125D01*
G02X617121Y228004I1094J-877D01*
G03X617675I277J288D01*
G02X617771Y228088I970J-1012D01*
G03Y228400I-125J156D01*
G02X619621Y230504I877J1094D01*
G03X620175I277J288D01*
G02X622158Y228521I973J-1010D01*
G03Y227967I288J-277D01*
G02X622242Y227871I-1012J-970D01*
G03X622554I156J125D01*
G02X624658Y226021I1094J-877D01*
G03Y225467I288J-277D01*
G02Y223521I-1010J-973D01*
G03Y222967I288J-277D01*
G02Y221021I-1010J-973D01*
G03Y220467I288J-277D01*
G02Y218521I-1010J-973D01*
G03Y217967I288J-277D01*
G02Y216021I-1010J-973D01*
G03Y215467I288J-277D01*
G02Y213521I-1010J-973D01*
G03Y212967I288J-277D01*
G02Y211021I-1010J-973D01*
G03Y210467I288J-277D01*
G02Y208521I-1010J-973D01*
G03Y207967I288J-277D01*
G02X622675Y205984I-1010J-973D01*
G03X622121I-277J-288D01*
G02X620175I-973J1010D01*
G03X619621I-277J-288D01*
G02X617675I-973J1010D01*
G37*
G36*
G01X1856789Y207274D02*
G03X1857411Y207253I319J241D01*
G02X1857351Y205491I1059J-918D01*
G03X1856729Y205512I-319J-241D01*
G02X1856789Y207274I-1059J918D01*
G37*
G36*
G01X1222271Y206989D02*
G03Y206411I277J-289D01*
G02X1220329I-971J-1011D01*
G03Y206989I-277J289D01*
G02X1222271I971J1011D01*
G37*
G36*
G01X1517619Y204557D02*
G03X1517615Y204002I286J-280D01*
G02X1515595Y204017I-1017J-965D01*
G03X1515599Y204572I-286J280D01*
G02X1517619Y204557I1017J965D01*
G37*
G36*
G01X708189Y200329D02*
G03X707611I-289J-277D01*
G02X705698Y202374I-1011J972D01*
G03X705677Y203003I-257J306D01*
G02X707756Y205127I884J1214D01*
G03X708320Y205054I318J242D01*
G02X710479Y204479I862J-1106D01*
G03X711061Y204291I370J152D01*
G02X711171Y201847I739J-1191D01*
G03X710594Y201447I-179J-358D01*
G02X708189Y200329I-1394J-147D01*
G37*
G36*
G01X1884247Y201333D02*
G03X1884271Y201009I128J-153D01*
G02X1882499Y200753I-732J-1196D01*
G03X1882457Y201329I-297J268D01*
G02X1884491Y203224I893J1081D01*
G03X1885100Y203174I326J232D01*
G02X1884952Y201370I993J-990D01*
G03X1884343Y201420I-326J-232D01*
G02X1884247Y201333I-988J994D01*
G37*
G36*
G01X1227471Y201389D02*
G03Y200811I277J-289D01*
G02X1225529I-971J-1011D01*
G03Y201389I-277J289D01*
G02X1227471I971J1011D01*
G37*
G36*
G01X1546924Y199009D02*
G03X1546944Y198437I289J-276D01*
G02X1544986Y198368I-944J-1037D01*
G03X1544966Y198940I-289J276D01*
G02X1546924Y199009I944J1037D01*
G37*
G36*
G01X1763668Y195332D02*
X1758668D01*
G02Y198354I0J1511D01*
G01X1763669D01*
G02X1765180Y196853I0J-1512D01*
G01Y196758D01*
X1765170Y196674D01*
G02X1763668Y195332I-1502J169D01*
G37*
G36*
G01X1751082D02*
X1746082D01*
G02Y198354I0J1511D01*
G01X1751083D01*
G02X1752594Y196853I0J-1512D01*
G01Y196758D01*
X1752584Y196674D01*
G02X1751082Y195332I-1502J169D01*
G37*
G36*
G01X1826682Y195330D02*
X1821682D01*
G02Y198352I0J1511D01*
G01X1826683D01*
G02X1828194Y196851I0J-1512D01*
G01Y196756D01*
X1828184Y196672D01*
G02X1826682Y195330I-1502J169D01*
G37*
G36*
G01X1814041D02*
X1809041D01*
G02Y198352I0J1511D01*
G01X1814042D01*
G02X1815552Y196851I-1J-1511D01*
G01Y196756D01*
X1815543Y196672D01*
G02X1814041Y195330I-1502J169D01*
G37*
G36*
G01X1801441D02*
X1796441D01*
G02Y198352I0J1511D01*
G01X1801442D01*
G02X1802952Y196851I-1J-1511D01*
G01Y196756D01*
X1802943Y196672D01*
G02X1801441Y195330I-1502J169D01*
G37*
G36*
G01X1788841D02*
X1783841D01*
G02Y198352I0J1511D01*
G01X1788842D01*
G02X1790352Y196851I-1J-1511D01*
G01Y196756D01*
X1790343Y196672D01*
G02X1788841Y195330I-1502J169D01*
G37*
G36*
G01X1776241D02*
X1771241D01*
G02Y198352I0J1511D01*
G01X1776242D01*
G02X1777752Y196851I-1J-1511D01*
G01Y196756D01*
X1777743Y196672D01*
G02X1776241Y195330I-1502J169D01*
G37*
G36*
G01X720641Y196447D02*
G03X721181Y196442I273J293D01*
G02X721162Y194373I936J-1043D01*
G03X720622Y194378I-273J-293D01*
G02X720641Y196447I-936J1043D01*
G37*
G36*
G01X1638880Y196604D02*
G03Y196050I288J-277D01*
G02X1636860I-1010J-973D01*
G03Y196604I-288J277D01*
G02X1638880I1010J973D01*
G37*
G36*
G01X11160Y191980D02*
X11101Y192039D01*
X11100D01*
X7096Y196043D01*
Y230657D01*
X2126Y235627D01*
Y264824D01*
X8820Y271518D01*
Y338949D01*
X14153Y344282D01*
X14154D01*
X14246Y344375D01*
X40819D01*
X44734Y340460D01*
Y269503D01*
X44856Y269451D01*
G02Y266869I-546J-1291D01*
G01X44734Y266817D01*
Y197413D01*
X39301Y191980D01*
X11160D01*
G37*
G36*
G01X1708794Y193293D02*
G02X1712894Y191735I3218J2294D01*
G02X1708794Y193293I-882J3852D01*
G37*
G36*
G01X1209145Y193611D02*
G03X1209161Y194233I-243J317D01*
G02X1210925Y194189I909J1067D01*
G03X1210909Y193567I243J-317D01*
G02X1209145Y193611I-909J-1067D01*
G37*
G36*
G01X1685249Y190205D02*
G03X1684650Y190129I-266J-298D01*
G02X1684418Y191953I-1166J778D01*
G03X1685017Y192029I266J298D01*
G02X1685249Y190205I1166J-778D01*
G37*
G36*
G01X1621217Y184110D02*
G03X1620607Y184084I-294J-271D01*
G02X1620531Y185894I-1107J860D01*
G03X1621141Y185920I294J271D01*
G02X1621217Y184110I1107J-860D01*
G37*
G36*
G01X1609625Y183827D02*
G03X1609071Y183803I-265J-300D01*
G02X1608985Y185821I-1015J968D01*
G03X1609539Y185845I265J300D01*
G02X1611497Y185914I1014J-968D01*
G03X1612052Y185930I269J296D01*
G02X1614042Y185943I1001J-981D01*
G03X1614597Y185934I282J283D01*
G02X1614564Y183914I956J-1026D01*
G03X1614009Y183923I-282J-283D01*
G02X1612110Y183912I-955J1026D01*
G03X1611555Y183896I-269J-296D01*
G02X1609625Y183827I-1001J981D01*
G37*
G36*
G01X1682294Y182678D02*
G03X1681795Y182531I-164J-365D01*
G02X1679261Y184475I-1345J870D01*
G03X1679252Y184752I-148J134D01*
G02X1681967Y186024I1118J1148D01*
G03X1682483Y185672I399J31D01*
G02X1682294Y182678I467J-1532D01*
G37*
G36*
G01X1656005Y183496D02*
G03X1656044Y182887I277J-288D01*
G02X1654235Y182770I-835J-1126D01*
G03X1654196Y183379I-277J288D01*
G02X1656005Y183496I835J1126D01*
G37*
G36*
G01X1493491Y178427D02*
G03X1493498Y177872I291J-274D01*
G02X1491478Y177847I-998J-985D01*
G03X1491471Y178402I-291J274D01*
G02X1493491Y178427I998J985D01*
G37*
G36*
G01X1615361Y178138D02*
G03X1615868Y177853I388J97D01*
G02X1614925Y176177I418J-1338D01*
G03X1614418Y176462I-388J-97D01*
G02X1615361Y178138I-418J1338D01*
G37*
G36*
G01X1820382Y175014D02*
X1815382D01*
G02Y178036I0J1511D01*
G01X1820383D01*
G02X1821894Y176535I0J-1512D01*
G01Y176440D01*
X1821884Y176356D01*
G02X1820382Y175014I-1502J169D01*
G37*
G36*
G01X1807784D02*
X1802784D01*
G02Y178036I0J1511D01*
G01X1807785D01*
G02X1809296Y176535I0J-1512D01*
G01Y176440D01*
X1809286Y176356D01*
G02X1807784Y175014I-1502J169D01*
G37*
G36*
G01X1795185D02*
X1790185D01*
G02Y178036I0J1511D01*
G01X1795185D01*
G02X1796696Y176535I0J-1511D01*
G01Y176440D01*
X1796687Y176356D01*
G02X1795185Y175014I-1502J169D01*
G37*
G36*
G01X1782587D02*
X1777587D01*
G02Y178036I0J1511D01*
G01X1782588D01*
G02X1784098Y176535I-1J-1511D01*
G01Y176440D01*
X1784089Y176356D01*
G02X1782587Y175014I-1502J169D01*
G37*
G36*
G01X1764988Y178036D02*
X1769989D01*
G02X1771500Y176535I0J-1512D01*
G01Y176440D01*
X1771490Y176356D01*
G02X1769988Y175014I-1502J169D01*
G01X1764987D01*
G02X1764988Y178036I1J1511D01*
G37*
G36*
G01X1739792D02*
X1744793D01*
G02X1746304Y176535I0J-1512D01*
G01Y176440D01*
X1746294Y176356D01*
G02X1744792Y175014I-1502J169D01*
G01X1739792D01*
G02Y178036I1J1511D01*
G37*
G36*
G01X1732193Y175014D02*
X1727193D01*
G02Y178036I1J1511D01*
G01X1732193D01*
G02X1733704Y176535I0J-1511D01*
G01Y176440D01*
X1733695Y176356D01*
G02X1732193Y175014I-1502J169D01*
G37*
G36*
G01X1254266Y174954D02*
G03X1253734I-266J-298D01*
G02Y177046I-934J1046D01*
G03X1254266I266J298D01*
G02Y174954I934J-1046D01*
G37*
G36*
G01X1856427Y174890D02*
G03X1855873I-277J-288D01*
G02Y176910I-973J1010D01*
G03X1856427I277J288D01*
G02Y174890I973J-1010D01*
G37*
G36*
G01X1876467Y175734D02*
G03X1876859Y175321I400J-13D01*
G02X1875431Y173967I-27J-1402D01*
G03X1875039Y174380I-400J13D01*
G02X1876467Y175734I27J1402D01*
G37*
G36*
G01X1472924Y172703D02*
G03X1472369Y172698I-275J-290D01*
G02X1472352Y174718I-981J1002D01*
G03X1472907Y174723I275J290D01*
G02X1472924Y172703I981J-1002D01*
G37*
G36*
G01X1245937Y172140D02*
G03X1245383I-277J-288D01*
G02X1243022Y173350I-973J1010D01*
G03X1242665Y173805I-396J57D01*
G02X1244188Y175000I135J1395D01*
G03X1244545Y174545I396J-57D01*
G02X1245383Y174160I-134J-1396D01*
G03X1245937I277J288D01*
G02Y172140I973J-1010D01*
G37*
G36*
G01X1614926Y174330D02*
G03X1615426Y174119I364J166D01*
G02X1614624Y172220I474J-1319D01*
G03X1614124Y172431I-364J-166D01*
G02X1613209Y172419I-475J1319D01*
G03X1612732Y172230I-126J-380D01*
G02X1610389Y172044I-1232J670D01*
G03X1609884Y172153I-317J-244D01*
G02X1610333Y174245I-662J1236D01*
G03X1610838Y174136I317J244D01*
G02X1611941Y174231I662J-1236D01*
G03X1612418Y174420I126J380D01*
G02X1614926Y174330I1232J-670D01*
G37*
G36*
G01X43144Y170972D02*
X43129Y170974D01*
X36880D01*
Y177224D01*
X36877Y177239D01*
G02Y179533I7414J1147D01*
G01X36880Y179548D01*
Y185798D01*
X43129D01*
X43144Y185800D01*
G02X45438I1147J-7414D01*
G01X45453Y185798D01*
X51702D01*
Y179548D01*
X51705Y179533D01*
G02Y177239I-7414J-1147D01*
G01X51702Y177224D01*
Y170974D01*
X45453D01*
X45438Y170972D01*
G02X43144I-1147J7414D01*
G37*
G36*
G01X1596631Y171213D02*
G03X1596053I-289J-277D01*
G02Y173155I-1011J971D01*
G03X1596631I289J277D01*
G02Y171213I1011J-971D01*
G37*
G36*
G01X1887371Y171589D02*
G03Y171011I277J-289D01*
G02X1885429I-971J-1011D01*
G03Y171589I-277J289D01*
G02X1887371I971J1011D01*
G37*
G36*
G01X1701968Y162401D02*
G03X1702523Y162390I283J283D01*
G02X1702478Y160081I1087J-1176D01*
G03X1701923Y160092I-283J-283D01*
G02X1701968Y162401I-1087J1176D01*
G37*
G36*
G01X1840909Y158413D02*
G03X1840924Y157858I295J-270D01*
G02X1838905Y157803I-983J-1000D01*
G03X1838890Y158358I-295J270D01*
G02X1840909Y158413I983J1000D01*
G37*
G36*
G01X1531912Y157489D02*
G03X1532143Y156930I358J-179D01*
G02X1530362Y155182I-443J-1330D01*
G03X1529807Y155424I-382J-119D01*
G02X1531912Y157489I-1963J4107D01*
G37*
G36*
G01X20473Y158250D02*
G03X21740Y158653I-2J2199D01*
G02X21756Y154015I1488J-2314D01*
G03X20502Y154428I-1283J-1786D01*
G01X20471D01*
G03X19204Y154025I2J-2199D01*
G02X19188Y158663I-1488J2314D01*
G03X20442Y158250I1283J1786D01*
G01X20473D01*
G37*
G36*
G01X3938D02*
G03X5205Y158653I-2J2199D01*
G02X5221Y154015I1488J-2314D01*
G03X3967Y154428I-1283J-1786D01*
G01X3936D01*
G03X2669Y154025I2J-2199D01*
G02X2653Y158663I-1488J2314D01*
G03X3907Y158250I1283J1786D01*
G01X3938D01*
G37*
G36*
G01X-12598D02*
G03X-11331Y158653I-2J2199D01*
G02X-11315Y154015I1488J-2314D01*
G03X-12569Y154428I-1283J-1786D01*
G01X-12599D01*
G03X-13866Y154025I2J-2199D01*
G02X-13882Y158663I-1488J2314D01*
G03X-12628Y158250I1283J1786D01*
G01X-12598D01*
G37*
G36*
G01X51309Y152844D02*
X47309D01*
G02Y155868I0J1512D01*
G01X51310D01*
G02X52820Y154366I-1J-1512D01*
G01Y154271D01*
X52811Y154187D01*
G02X51309Y152844I-1502J168D01*
G37*
G36*
G01X1788818Y155649D02*
G03X1789375Y155428I376J136D01*
G02X1788550Y153595I725J-1428D01*
G03X1788016Y153866I-387J-101D01*
G02X1788818Y155649I-516J1304D01*
G37*
G36*
G01X1700076Y154255D02*
G03X1700357Y154249I144J140D01*
G02X1700306Y151967I1098J-1166D01*
G03X1700025Y151973I-144J-140D01*
G02X1700076Y154255I-1098J1166D01*
G37*
G36*
G01X1876493Y153833D02*
G03X1877086Y153815I305J259D01*
G02X1877028Y151935I1010J-972D01*
G03X1876435Y151953I-305J-259D01*
G02X1876493Y153833I-1010J972D01*
G37*
G36*
G01X1913160Y153727D02*
G03X1913765Y153634I342J208D01*
G02X1913491Y151853I925J-1054D01*
G03X1912886Y151946I-342J-208D01*
G02X1913160Y153727I-925J1054D01*
G37*
G36*
G01X1514888Y153600D02*
G03X1515300Y153144I396J-57D01*
G02X1513970Y151943I58J-1401D01*
G03X1513558Y152399I-396J57D01*
G02X1514888Y153600I-58J1401D01*
G37*
G36*
G01X1885299Y154911D02*
G03X1885233Y155526I-285J280D01*
G02X1887000Y155717I767J1174D01*
G03X1887066Y155102I285J-280D01*
G02X1887203Y152857I-767J-1173D01*
G03X1887148Y152303I258J-305D01*
G02X1885146Y152502I-1098J-872D01*
G03X1885201Y153056I-258J305D01*
G02X1885299Y154911I1098J872D01*
G37*
G36*
G01X68098Y149962D02*
X63098D01*
G02Y152984I0J1511D01*
G01X68099D01*
G02X69610Y151483I0J-1512D01*
G01Y151388D01*
X69600Y151304D01*
G02X68098Y149962I-1502J169D01*
G37*
G36*
G01X1265136Y151576D02*
G03X1265691Y151567I282J284D01*
G02X1265656Y149548I955J-1026D01*
G03X1265101Y149557I-282J-284D01*
G02X1263135Y149613I-955J1027D01*
G03X1262557I-289J-277D01*
G02Y151555I-1011J971D01*
G03X1263135I289J277D01*
G02X1265136Y151576I1011J-971D01*
G37*
G36*
G01X1574971Y151089D02*
G03Y150511I277J-289D01*
G02X1573029I-971J-1011D01*
G03Y151089I-277J289D01*
G02X1574971I971J1011D01*
G37*
G36*
G01X1945607Y150725D02*
G03X1945609Y150166I287J-278D01*
G02X1943602Y150159I-1000J-982D01*
G03X1943600Y150718I-287J278D01*
G02X1945607Y150725I1000J982D01*
G37*
G36*
G01X1295155Y148431D02*
G03X1294732Y148064I-24J-400D01*
G02X1291935Y148249I-1397J113D01*
G03X1291580Y148668I-400J21D01*
G02X1291742Y151463I156J1393D01*
G03X1292143Y151839I2J400D01*
G02X1292145Y151862I1398J-110D01*
G03X1291752Y152292I-399J30D01*
G02X1293170Y153588I20J1402D01*
G03X1293563Y153158I399J-30D01*
G02X1293594Y153157I-30J-1402D01*
G03X1293797Y153396I7J200D01*
G02X1295303Y152274I1375J274D01*
G03X1294942Y151849I38J-398D01*
G02Y151657I-1399J-96D01*
G03X1295318Y151230I399J-28D01*
G02X1295155Y148431I-78J-1400D01*
G37*
G36*
G01X1496967Y149755D02*
G03X1497034Y149203I319J-241D01*
G02X1495031Y148960I-884J-1088D01*
G03X1494964Y149512I-319J241D01*
G02X1496967Y149755I884J1088D01*
G37*
G36*
G01X1964194Y149150D02*
G03X1964545Y148710I398J-43D01*
G02X1962988Y147468I-163J-1392D01*
G03X1962637Y147908I-398J43D01*
G02X1964194Y149150I163J1392D01*
G37*
G36*
G01X25591Y150376D02*
G03X26858Y150779I-2J2199D01*
G02X26874Y146141I1488J-2314D01*
G03X25620Y146554I-1283J-1786D01*
G01X25590D01*
G03X24323Y146151I2J-2199D01*
G02X24307Y150789I-1488J2314D01*
G03X25561Y150376I1283J1786D01*
G01X25591D01*
G37*
G36*
G01X9056D02*
G03X10323Y150779I-2J2199D01*
G02X10339Y146141I1488J-2314D01*
G03X9085Y146554I-1283J-1786D01*
G01X9054D01*
G03X7787Y146151I2J-2199D01*
G02X7771Y150789I-1488J2314D01*
G03X9025Y150376I1283J1786D01*
G01X9056D01*
G37*
G36*
G01X-7480D02*
G03X-6213Y150779I-2J2199D01*
G02X-6197Y146141I1488J-2314D01*
G03X-7451Y146554I-1283J-1786D01*
G01X-7481D01*
G03X-8748Y146151I2J-2199D01*
G02X-8764Y150789I-1488J2314D01*
G03X-7510Y150376I1283J1786D01*
G01X-7480D01*
G37*
G36*
G01X1278933Y147438D02*
G03X1278927Y146832I258J-306D01*
G02X1277097Y146852I-927J-1052D01*
G03X1277103Y147458I-258J306D01*
G02X1278933Y147438I927J1052D01*
G37*
G36*
G01X1490661Y145218D02*
G03X1490195Y144863I-68J-394D01*
G02X1489039Y146382I-1395J138D01*
G03X1489505Y146737I68J394D01*
G02X1490661Y145218I1395J-138D01*
G37*
G36*
G01X1533237Y146370D02*
G03X1533446Y145819I358J-180D01*
G02X1531671Y145148I-523J-1301D01*
G03X1531462Y145699I-358J180D01*
G02X1533237Y146370I523J1301D01*
G37*
G36*
G01X1849616Y143180D02*
G03X1849627Y142581I270J-295D01*
G02X1847506Y142540I-1037J-1221D01*
G03X1847495Y143139I-270J295D01*
G02X1849616Y143180I1037J1221D01*
G37*
G36*
G01X1267743Y140626D02*
G03X1267208Y140322I-141J-375D01*
G02X1266321Y141880I-1380J246D01*
G03X1266856Y142184I141J375D01*
G02X1267743Y140626I1380J-246D01*
G37*
G36*
G01X62342Y144760D02*
Y139665D01*
X62333Y139581D01*
G02X59320Y139750I-1502J169D01*
G01Y144750D01*
G02X62342Y144760I1511J0D01*
G37*
G36*
G01X48412D02*
Y139665D01*
X48402Y139581D01*
G02X45388Y139750I-1502J169D01*
G01Y144750D01*
G02X48412Y144760I1512J0D01*
G37*
G36*
G01X3938Y142502D02*
G03X5205Y142905I-2J2199D01*
G02X5221Y138267I1488J-2314D01*
G03X3967Y138680I-1283J-1786D01*
G01X3936D01*
G03X2669Y138277I2J-2199D01*
G02X2653Y142915I-1488J2314D01*
G03X3907Y142502I1283J1786D01*
G01X3938D01*
G37*
G36*
G01X-12598D02*
G03X-11331Y142905I-2J2199D01*
G02X-11315Y138267I1488J-2314D01*
G03X-12569Y138680I-1283J-1786D01*
G01X-12599D01*
G03X-13866Y138277I2J-2199D01*
G02X-13882Y142915I-1488J2314D01*
G03X-12628Y142502I1283J1786D01*
G01X-12598D01*
G37*
G36*
G01X1452354Y140426D02*
G03X1452435Y139869I322J-238D01*
G02X1450464Y139585I-845J-1119D01*
G03X1450383Y140142I-322J238D01*
G02X1450207Y142221I845J1118D01*
G03X1450200Y142776I-292J274D01*
G02X1450259Y144802I998J985D01*
G03X1450267Y145389I-268J297D01*
G02X1452172Y145364I966J1016D01*
G03X1452164Y144777I268J-297D01*
G02X1452219Y142801I-966J-1016D01*
G03X1452226Y142246I292J-274D01*
G02X1452354Y140426I-998J-985D01*
G37*
G36*
G01X1856050Y137539D02*
G03X1855450I-300J-265D01*
G02Y139661I-1200J1061D01*
G03X1856050I300J265D01*
G02Y137539I1200J-1061D01*
G37*
G36*
G01X1846743Y136086D02*
G03X1847327Y135919I364J167D01*
G02X1846826Y134164I773J-1170D01*
G03X1846242Y134331I-364J-167D01*
G02X1846743Y136086I-773J1170D01*
G37*
G36*
G01X67198Y137760D02*
Y132665D01*
X67189Y132581D01*
G02X64176Y132750I-1502J169D01*
G01Y137750D01*
G02X67198Y137760I1511J0D01*
G37*
G36*
G01X53080D02*
Y132665D01*
X53071Y132581D01*
G02X50058Y132750I-1502J169D01*
G01Y137751D01*
G02X53080Y137760I1511J-1D01*
G37*
G36*
G01X1920235Y133456D02*
G03X1920306Y132858I297J-268D01*
G02X1918474Y132641I-792J-1157D01*
G03X1918403Y133239I-297J268D01*
G02X1920235Y133456I792J1157D01*
G37*
G36*
G01X25591Y134628D02*
G03X26858Y135031I-2J2199D01*
G02X26874Y130393I1488J-2314D01*
G03X25620Y130806I-1283J-1786D01*
G01X25590D01*
G03X24323Y130403I2J-2199D01*
G02X24307Y135041I-1488J2314D01*
G03X25561Y134628I1283J1786D01*
G01X25591D01*
G37*
G36*
G01X1855539Y132335D02*
G03X1855351Y131782I165J-364D01*
G02X1853538Y132399I-1236J-661D01*
G03X1853726Y132952I-165J364D01*
G02X1855539Y132335I1236J661D01*
G37*
G36*
G01X118581Y133842D02*
G03X119128Y133859I264J300D01*
G02X121151Y131918I989J-994D01*
G03X121155Y131373I295J-270D01*
G02X119191Y129374I-1017J-965D01*
G03X118646Y129369I-270J-295D01*
G02X116626Y131310I-964J1018D01*
G03X116620Y131843I-301J263D01*
G02X118581Y133842I1032J949D01*
G37*
G36*
G01X1580308Y130140D02*
G03X1580312Y129585I290J-275D01*
G02X1578292Y129568I-1002J-981D01*
G03X1578288Y130123I-290J275D01*
G02X1580308Y130140I1002J981D01*
G37*
G36*
G01X1469569Y130197D02*
G03X1469606Y129592I279J-287D01*
G02X1467776Y129481I-851J-1114D01*
G03X1467739Y130086I-279J287D01*
G02X1469569Y130197I851J1114D01*
G37*
G36*
G01X1920681Y127497D02*
G03Y126924I279J-287D01*
G02X1918723I-979J-1004D01*
G03Y127497I-279J286D01*
G02X1920681I979J1004D01*
G37*
G36*
G01X62342Y130760D02*
Y125665D01*
X62333Y125581D01*
G02X59320Y125750I-1502J169D01*
G01Y130750D01*
G02X62342Y130760I1511J0D01*
G37*
G36*
G01X48412D02*
Y125665D01*
X48402Y125581D01*
G02X45388Y125750I-1502J169D01*
G01Y130750D01*
G02X48412Y130760I1512J0D01*
G37*
G36*
G01X-12598Y126754D02*
G03X-11331Y127157I-2J2199D01*
G02X-11315Y122519I1488J-2314D01*
G03X-12569Y122932I-1283J-1786D01*
G01X-12599D01*
G03X-13866Y122529I2J-2199D01*
G02X-13882Y127167I-1488J2314D01*
G03X-12628Y126754I1283J1786D01*
G01X-12598D01*
G37*
G36*
G01X1270489Y121529D02*
G03X1269911I-289J-277D01*
G02Y123471I-1011J971D01*
G03X1270489I289J277D01*
G02Y121529I1011J-971D01*
G37*
G36*
G01X1543504Y120435D02*
G03X1543326Y119880I172J-361D01*
G02X1541496Y120465I-1226J-680D01*
G03X1541674Y121020I-172J361D01*
G02X1543504Y120435I1226J680D01*
G37*
G36*
G01X1760020Y118137D02*
G03X1759380I-320J-240D01*
G02Y120063I-1280J963D01*
G03X1760020I320J240D01*
G02Y118137I1280J-963D01*
G37*
G36*
G01X53080Y123760D02*
Y118665D01*
X53071Y118581D01*
G02X50058Y118750I-1502J169D01*
G01Y123751D01*
G02X53080Y123760I1511J-1D01*
G37*
G36*
G01X63894Y123731D02*
G02X66916Y123740I1511J-1D01*
G01Y118730D01*
X66917D01*
X66916Y118645D01*
X66907Y118561D01*
G02X63894Y118730I-1502J169D01*
G01Y123731D01*
G37*
G36*
G01X1474064Y119985D02*
G03X1474087Y119386I276J-289D01*
G02X1472232Y119314I-887J-1086D01*
G03X1472209Y119913I-276J289D01*
G02X1471986Y121856I887J1086D01*
G03X1471854Y122456I-316J245D01*
G02X1473610Y122843I646J1244D01*
G03X1473742Y122243I316J-245D01*
G02X1474064Y119985I-646J-1244D01*
G37*
G36*
G01X1528024Y120779D02*
Y115684D01*
X1528015Y115600D01*
G02X1525002Y115769I-1502J169D01*
G01Y120769D01*
G02X1528024Y120779I1511J0D01*
G37*
G36*
G01X25591Y118880D02*
G03X26858Y119283I-2J2199D01*
G02X26874Y114645I1488J-2314D01*
G03X25620Y115058I-1283J-1786D01*
G01X25590D01*
G03X24323Y114655I2J-2199D01*
G02X24307Y119293I-1488J2314D01*
G03X25561Y118880I1283J1786D01*
G01X25591D01*
G37*
G36*
G01X9054Y115058D02*
G03X7787Y114655I2J-2199D01*
G02X7771Y119293I-1488J2314D01*
G03X9025Y118880I1283J1786D01*
G01X9056D01*
G03X10323Y119283I-2J2199D01*
G02X10339Y114645I1488J-2314D01*
G03X9085Y115058I-1283J-1786D01*
G01X9054D01*
G37*
G36*
G01X1907363Y116972D02*
G03X1907375Y116373I271J-294D01*
G02X1905518Y116337I-908J-1068D01*
G03X1905506Y116936I-271J294D01*
G02X1907363Y116972I908J1068D01*
G37*
G36*
G01X1303475Y113289D02*
G03Y112711I277J-289D01*
G02X1301533I-971J-1011D01*
G03Y113289I-277J289D01*
G02X1301458Y115234I971J1011D01*
G03Y115766I-298J266D01*
G02X1301467Y117644I1046J934D01*
G03X1301472Y118177I-295J269D01*
G02X1303563Y118158I1054J925D01*
G03X1303558Y117625I295J-269D01*
G02X1303550Y115766I-1054J-925D01*
G03Y115234I298J-266D01*
G02X1303475Y113289I-1046J-934D01*
G37*
G36*
G01X62212Y116760D02*
Y111665D01*
X62202Y111581D01*
G02X59188Y111750I-1502J169D01*
G01Y116750D01*
G02X62212Y116760I1512J0D01*
G37*
G36*
G01X48412D02*
Y111665D01*
X48402Y111581D01*
G02X45388Y111750I-1502J169D01*
G01Y116750D01*
G02X48412Y116760I1512J0D01*
G37*
G36*
G01X1599621Y109666D02*
G03X1599111Y109654I-248J-314D01*
G02X1599059Y111811I-921J1057D01*
G03X1599569Y111823I248J314D01*
G02X1599621Y109666I921J-1057D01*
G37*
G36*
G01X1189051Y109479D02*
G03X1189057Y108922I290J-275D01*
G02X1186901Y108900I-1067J-1057D01*
G03X1186895Y109457I-290J275D01*
G02X1189051Y109479I1067J1057D01*
G37*
G36*
G01X1152240D02*
G03X1152246Y108922I290J-275D01*
G02X1150090Y108900I-1067J-1057D01*
G03X1150084Y109457I-290J275D01*
G02X1152240Y109479I1067J1057D01*
G37*
G36*
G01X934720D02*
G03X934726Y108922I290J-275D01*
G02X932570Y108900I-1067J-1057D01*
G03X932564Y109457I-290J275D01*
G02X934720Y109479I1067J1057D01*
G37*
G36*
G01X897909D02*
G03X897915Y108922I290J-275D01*
G02X895759Y108900I-1067J-1057D01*
G03X895753Y109457I-290J275D01*
G02X897909Y109479I1067J1057D01*
G37*
G36*
G01X539443D02*
G03X539449Y108922I290J-275D01*
G02X537293Y108900I-1067J-1057D01*
G03X537287Y109457I-290J275D01*
G02X539443Y109479I1067J1057D01*
G37*
G36*
G01X502632D02*
G03X502638Y108922I290J-275D01*
G02X500482Y108900I-1067J-1057D01*
G03X500476Y109457I-290J275D01*
G02X502632Y109479I1067J1057D01*
G37*
G36*
G01X285112D02*
G03X285118Y108922I290J-275D01*
G02X282962Y108900I-1067J-1057D01*
G03X282956Y109457I-290J275D01*
G02X285112Y109479I1067J1057D01*
G37*
G36*
G01X248301D02*
G03X248307Y108922I290J-275D01*
G02X246151Y108900I-1067J-1057D01*
G03X246145Y109457I-290J275D01*
G02X248301Y109479I1067J1057D01*
G37*
G36*
G01X20473Y111006D02*
G03X21740Y111409I-2J2199D01*
G02X21756Y106771I1488J-2314D01*
G03X20502Y107184I-1283J-1786D01*
G01X20471D01*
G03X19204Y106781I2J-2199D01*
G02X19188Y111419I-1488J2314D01*
G03X20442Y111006I1283J1786D01*
G01X20473D01*
G37*
G36*
G01X3936Y107184D02*
G03X2669Y106781I2J-2199D01*
G02X2653Y111419I-1488J2314D01*
G03X3907Y111006I1283J1786D01*
G01X3938D01*
G03X5205Y111409I-2J2199D01*
G02X5221Y106771I1488J-2314D01*
G03X3967Y107184I-1283J-1786D01*
G01X3936D01*
G37*
G36*
G01X-12598Y111006D02*
G03X-11331Y111409I-2J2199D01*
G02X-11315Y106771I1488J-2314D01*
G03X-12569Y107184I-1283J-1786D01*
G01X-12599D01*
G03X-13866Y106781I2J-2199D01*
G02X-13882Y111419I-1488J2314D01*
G03X-12628Y111006I1283J1786D01*
G01X-12598D01*
G37*
G36*
G01X1194172Y109223D02*
G03X1194166Y108674I288J-278D01*
G02X1191980Y108696I-1103J-1019D01*
G03X1191986Y109245I-288J278D01*
G02X1194172Y109223I1103J1019D01*
G37*
G36*
G01X1157361D02*
G03X1157355Y108674I288J-278D01*
G02X1155169Y108696I-1103J-1019D01*
G03X1155175Y109245I-288J278D01*
G02X1157361Y109223I1103J1019D01*
G37*
G36*
G01X939841D02*
G03X939835Y108674I288J-278D01*
G02X937649Y108696I-1103J-1019D01*
G03X937655Y109245I-288J278D01*
G02X939841Y109223I1103J1019D01*
G37*
G36*
G01X903030D02*
G03X903024Y108674I288J-278D01*
G02X900838Y108696I-1103J-1019D01*
G03X900844Y109245I-288J278D01*
G02X903030Y109223I1103J1019D01*
G37*
G36*
G01X544564D02*
G03X544558Y108674I288J-278D01*
G02X542372Y108696I-1103J-1019D01*
G03X542378Y109245I-288J278D01*
G02X544564Y109223I1103J1019D01*
G37*
G36*
G01X507753D02*
G03X507747Y108674I288J-278D01*
G02X505561Y108696I-1103J-1019D01*
G03X505567Y109245I-288J278D01*
G02X507753Y109223I1103J1019D01*
G37*
G36*
G01X290233D02*
G03X290227Y108674I288J-278D01*
G02X288041Y108696I-1103J-1019D01*
G03X288047Y109245I-288J278D01*
G02X290233Y109223I1103J1019D01*
G37*
G36*
G01X253422D02*
G03X253416Y108674I288J-278D01*
G02X251230Y108696I-1103J-1019D01*
G03X251236Y109245I-288J278D01*
G02X253422Y109223I1103J1019D01*
G37*
G36*
G01X1853181Y106802D02*
G03X1852743Y106393I-38J-398D01*
G02X1851477Y107753I-1402J-35D01*
G03X1851915Y108162I38J398D01*
G02X1853181Y106802I1402J35D01*
G37*
G36*
G01X66896Y109760D02*
Y104665D01*
X66886Y104581D01*
G02X63872Y104750I-1502J169D01*
G01Y109751D01*
G02X66896Y109760I1512J-1D01*
G37*
G36*
G01X52892D02*
Y104665D01*
X52883Y104581D01*
G02X49870Y104750I-1502J169D01*
G01Y109750D01*
G02X52892Y109760I1511J0D01*
G37*
G36*
G01X1512424Y108332D02*
G02X1515446Y108342I1511J0D01*
G01Y104447D01*
X1515437Y104363D01*
G02X1512424Y104532I-1502J169D01*
G01Y108332D01*
G37*
G36*
G01X1811259Y105468D02*
G03X1811814Y105445I289J276D01*
G02X1811729Y103427I929J-1050D01*
G03X1811174Y103450I-289J-276D01*
G02X1811259Y105468I-929J1050D01*
G37*
G36*
G01X1525004Y103876D02*
X1524995Y104048D01*
X1524994D01*
X1525295Y109060D01*
X1525327Y109232D01*
G02X1528314Y109136I1486J-275D01*
G01X1528335Y108960D01*
X1528378D01*
X1528498Y108816D01*
X1528246Y107442D01*
X1528032Y103868D01*
X1528031Y103867D01*
X1528027Y103788D01*
X1528015Y103789D01*
G02X1525004Y103876I-1502J168D01*
G37*
G36*
G01X1490430Y104578D02*
G03X1490268Y104024I185J-355D01*
G02X1488403Y104567I-1215J-699D01*
G03X1488565Y105121I-185J355D01*
G02X1490430Y104578I1215J699D01*
G37*
G36*
G01X700017Y103801D02*
G03X699840Y103255I176J-359D01*
G02X697587Y101631I-1240J-655D01*
G03X697032Y101653I-289J-277D01*
G02X694970Y101870I-932J1047D01*
G03X694415Y101959I-323J-236D01*
G02X692290Y103599I-815J1141D01*
G03X691892Y104140I-374J142D01*
G02X692897Y106425I-82J1400D01*
G03X693485Y106390I310J253D01*
G02X695554Y106258I974J-1008D01*
G03X696081Y106170I312J249D01*
G02X697803Y105998I751J-1184D01*
G03X698373Y106014I277J288D01*
G02X700454Y105984I1027J-954D01*
G03X701021Y105949I301J264D01*
G02X703095Y105716I932J-1047D01*
G03X703642Y105615I326J232D01*
G02X703277Y103634I777J-1167D01*
G03X702730Y103735I-326J-232D01*
G02X700899Y103978I-777J1167D01*
G03X700332Y104013I-301J-264D01*
G02X700017Y103801I-933J1046D01*
G37*
G36*
G01X743520Y101574D02*
G03X742965Y101396I-194J-350D01*
G02X742380Y103226I-1265J604D01*
G03X742935Y103404I194J350D01*
G02X744736Y104095I1265J-604D01*
G03X745269Y104340I153J370D01*
G02X746064Y102605I1331J-440D01*
G03X745531Y102360I-153J-370D01*
G02X743520Y101574I-1331J440D01*
G37*
G36*
G01X25591Y103132D02*
G03X26858Y103535I-2J2199D01*
G02X26874Y98897I1488J-2314D01*
G03X25620Y99310I-1283J-1786D01*
G01X25590D01*
G03X24323Y98907I2J-2199D01*
G02X24307Y103545I-1488J2314D01*
G03X25561Y103132I1283J1786D01*
G01X25591D01*
G37*
G36*
G01X9054Y99310D02*
G03X7787Y98907I2J-2199D01*
G02X7771Y103545I-1488J2314D01*
G03X9025Y103132I1283J1786D01*
G01X9056D01*
G03X10323Y103535I-2J2199D01*
G02X10339Y98897I1488J-2314D01*
G03X9085Y99310I-1283J-1786D01*
G01X9054D01*
G37*
G36*
G01X-7480Y103132D02*
G03X-6213Y103535I-2J2199D01*
G02X-6197Y98897I1488J-2314D01*
G03X-7451Y99310I-1283J-1786D01*
G01X-7481D01*
G03X-8748Y98907I2J-2199D01*
G02X-8764Y103545I-1488J2314D01*
G03X-7510Y103132I1283J1786D01*
G01X-7480D01*
G37*
G36*
G01X1500216Y99529D02*
G02X1497194Y99501I-1511J-7D01*
G01X1497149Y102725D01*
G02X1500161Y102924I1511J21D01*
G01X1500169Y102860D01*
X1500171Y102795D01*
G02X1500172Y102767I-1510J-68D01*
G01Y102746D01*
X1500216Y99544D01*
G02Y99529I-1511J-8D01*
G37*
G36*
G01X757771Y100989D02*
G03Y100411I277J-289D01*
G02X755829I-971J-1011D01*
G03Y100989I-277J289D01*
G02X757771I971J1011D01*
G37*
G36*
G01X1375685Y100772D02*
G03Y100460I125J-156D01*
G02X1373798Y100339I-877J-1094D01*
G03Y100893I-288J277D01*
G02Y102839I1010J973D01*
G03Y103393I-288J277D01*
G02Y105339I1010J973D01*
G03Y105893I-288J277D01*
G02X1375781Y107876I1010J973D01*
G03X1376335I277J288D01*
G02X1378318Y105893I973J-1010D01*
G03Y105339I288J-277D01*
G02Y103393I-1010J-973D01*
G03Y102839I288J-277D01*
G02X1376335Y100856I-1010J-973D01*
G03X1375781I-277J-288D01*
G02X1375685Y100772I-970J1012D01*
G37*
G36*
G01X1687931Y99885D02*
G03X1688484Y99838I301J264D01*
G02X1688313Y97827I884J-1088D01*
G03X1687760Y97874I-301J-264D01*
G02X1687931Y99885I-884J1088D01*
G37*
G36*
G01X1659414Y100014D02*
G03X1659913Y99815I359J176D01*
G02X1659140Y97886I487J-1315D01*
G03X1658641Y98085I-359J-176D01*
G02X1659414Y100014I-487J1315D01*
G37*
G36*
G01X62312Y102760D02*
Y97665D01*
X62303Y97581D01*
G02X59290Y97750I-1502J169D01*
G01Y102751D01*
G02X62312Y102760I1511J-1D01*
G37*
G36*
G01X48412D02*
Y97665D01*
X48402Y97581D01*
G02X45388Y97750I-1502J169D01*
G01Y102751D01*
G02X48412Y102760I1512J-1D01*
G37*
G36*
G01X1542883Y98810D02*
G03X1542905Y98277I309J-254D01*
G02X1540817Y98190I-1005J-977D01*
G03X1540795Y98723I-309J254D01*
G02X1542883Y98810I1005J977D01*
G37*
G36*
G01X763520Y94433D02*
G03X762998Y94166I-137J-376D01*
G02X762130Y95867I-1348J384D01*
G03X762652Y96134I137J376D01*
G02X763520Y94433I1348J-384D01*
G37*
G36*
G01X1919170Y95082D02*
G03X1919149Y94521I274J-291D01*
G02X1917153Y94597I-1035J-945D01*
G03X1917174Y95158I-274J291D01*
G02X1917196Y97071I1036J945D01*
G03X1917137Y97674I-289J276D01*
G02X1919039Y97816I865J1228D01*
G03X1919070Y97210I276J-290D01*
G02X1919170Y95082I-860J-1107D01*
G37*
G36*
G01X1525232Y98265D02*
G02X1528256Y98275I1512J0D01*
G01Y93180D01*
X1528246Y93096D01*
G02X1525232Y93265I-1502J169D01*
G01Y98265D01*
G37*
G36*
G01X1405579Y90903D02*
G03X1404913I-333J-222D01*
G02X1403448Y93050I-1167J777D01*
G03X1403759Y93494I-85J391D01*
G02X1406205Y94601I1390J185D01*
G03X1406829Y94628I301J263D01*
G02X1408382Y92463I1131J-828D01*
G03X1408113Y91993I121J-381D01*
G02X1405579Y90903I-1367J-313D01*
G37*
G36*
G01X35367Y93038D02*
G03X35733Y92550I390J-89D01*
G02X34283Y91462I-83J-1400D01*
G03X33917Y91950I-390J89D01*
G02X35367Y93038I83J1400D01*
G37*
G36*
G01X1908550Y92826D02*
G03X1908558Y92268I291J-275D01*
G02X1906263Y92233I-1130J-1135D01*
G03X1906255Y92791I-291J275D01*
G02X1906213Y92833I1112J1153D01*
G03X1905913Y92824I-146J-136D01*
G02X1903524Y94956I-1234J1022D01*
G03X1903537Y95497I-288J278D01*
G02X1905797Y97757I1205J1055D01*
G03X1906338Y97770I263J301D01*
G02X1908609Y95511I1110J-1155D01*
G03X1908597Y94974I290J-275D01*
G02X1908550Y92826I-1212J-1048D01*
G37*
G36*
G01X68725Y89388D02*
X63724D01*
G02X63725Y92412I1J1512D01*
G01X68725D01*
G02X70236Y90910I-1J-1512D01*
G01Y90815D01*
X70227Y90731D01*
G02X68725Y89388I-1502J168D01*
G37*
G36*
G01X52892Y95760D02*
Y90665D01*
X52883Y90581D01*
G02X49870Y90750I-1502J169D01*
G01Y95750D01*
G02X52892Y95760I1511J0D01*
G37*
G36*
G01X1676372Y91718D02*
G03X1676946Y91514I374J142D01*
G02X1676339Y89802I703J-1213D01*
G03X1675765Y90006I-374J-142D01*
G02X1676372Y91718I-703J1213D01*
G37*
G36*
G01X733655Y89330D02*
G03X734242Y89312I302J263D01*
G02X734185Y87407I999J-983D01*
G03X733598Y87425I-302J-263D01*
G02X731603Y87422I-999J983D01*
G03X731034I-284J-282D01*
G02Y89394I-996J986D01*
G03X731603I285J282D01*
G02X733655Y89330I996J-986D01*
G37*
G36*
G01X1542878Y89123D02*
G03X1542807Y88580I253J-309D01*
G02X1540780Y88844I-1137J-820D01*
G03X1540851Y89387I-253J309D01*
G02X1540978Y91180I1137J820D01*
G03Y91734I-288J277D01*
G02X1543287Y93234I1010J973D01*
G03X1543774Y93002I371J151D01*
G02X1543857Y90296I406J-1342D01*
G03X1543370Y89973I-92J-389D01*
G02X1542878Y89123I-1383J233D01*
G37*
G36*
G01X1230970Y89087D02*
G03Y88541I292J-273D01*
G02X1228778I-1096J-1027D01*
G03Y89087I-292J273D01*
G02X1230970I1096J1027D01*
G37*
G36*
G01X1194159D02*
G03Y88541I292J-273D01*
G02X1191967I-1096J-1027D01*
G03Y89087I-292J273D01*
G02X1194159I1096J1027D01*
G37*
G36*
G01X1157348D02*
G03Y88541I292J-273D01*
G02X1155156I-1096J-1027D01*
G03Y89087I-292J273D01*
G02X1157348I1096J1027D01*
G37*
G36*
G01X1120536D02*
G03Y88541I292J-273D01*
G02X1118344I-1096J-1027D01*
G03Y89087I-292J273D01*
G02X1120536I1096J1027D01*
G37*
G36*
G01X939828D02*
G03Y88541I292J-273D01*
G02X937636I-1096J-1027D01*
G03Y89087I-292J273D01*
G02X939828I1096J1027D01*
G37*
G36*
G01X903017D02*
G03Y88541I292J-273D01*
G02X900825I-1096J-1027D01*
G03Y89087I-292J273D01*
G02X903017I1096J1027D01*
G37*
G36*
G01X866206D02*
G03Y88541I292J-273D01*
G02X864014I-1096J-1027D01*
G03Y89087I-292J273D01*
G02X866206I1096J1027D01*
G37*
G36*
G01X829395D02*
G03Y88541I292J-273D01*
G02X827203I-1096J-1027D01*
G03Y89087I-292J273D01*
G02X829395I1096J1027D01*
G37*
G36*
G01X792584D02*
G03Y88541I292J-273D01*
G02X790392I-1096J-1027D01*
G03Y89087I-292J273D01*
G02X792584I1096J1027D01*
G37*
G36*
G01X581362D02*
G03Y88541I292J-273D01*
G02X579170I-1096J-1027D01*
G03Y89087I-292J273D01*
G02X581362I1096J1027D01*
G37*
G36*
G01X544551D02*
G03Y88541I292J-273D01*
G02X542359I-1096J-1027D01*
G03Y89087I-292J273D01*
G02X544551I1096J1027D01*
G37*
G36*
G01X507740D02*
G03Y88541I292J-273D01*
G02X505548I-1096J-1027D01*
G03Y89087I-292J273D01*
G02X507740I1096J1027D01*
G37*
G36*
G01X470928D02*
G03Y88541I292J-273D01*
G02X468736I-1096J-1027D01*
G03Y89087I-292J273D01*
G02X470928I1096J1027D01*
G37*
G36*
G01X290220D02*
G03Y88541I292J-273D01*
G02X288028I-1096J-1027D01*
G03Y89087I-292J273D01*
G02X290220I1096J1027D01*
G37*
G36*
G01X253409D02*
G03Y88541I292J-273D01*
G02X251217I-1096J-1027D01*
G03Y89087I-292J273D01*
G02X253409I1096J1027D01*
G37*
G36*
G01X216598D02*
G03Y88541I292J-273D01*
G02X214406I-1096J-1027D01*
G03Y89087I-292J273D01*
G02X216598I1096J1027D01*
G37*
G36*
G01X179787D02*
G03Y88541I292J-273D01*
G02X177595I-1096J-1027D01*
G03Y89087I-292J273D01*
G02X179787I1096J1027D01*
G37*
G36*
G01X142976D02*
G03Y88541I292J-273D01*
G02X140784I-1096J-1027D01*
G03Y89087I-292J273D01*
G02X142976I1096J1027D01*
G37*
G36*
G01X1225870Y88873D02*
G03Y88327I292J-273D01*
G02X1223678I-1096J-1027D01*
G03Y88873I-292J273D01*
G02X1225870I1096J1027D01*
G37*
G36*
G01X1189059D02*
G03Y88327I292J-273D01*
G02X1186867I-1096J-1027D01*
G03Y88873I-292J273D01*
G02X1189059I1096J1027D01*
G37*
G36*
G01X1152248D02*
G03Y88327I292J-273D01*
G02X1150056I-1096J-1027D01*
G03Y88873I-292J273D01*
G02X1152248I1096J1027D01*
G37*
G36*
G01X1115436D02*
G03Y88327I292J-273D01*
G02X1113244I-1096J-1027D01*
G03Y88873I-292J273D01*
G02X1115436I1096J1027D01*
G37*
G36*
G01X934728D02*
G03Y88327I292J-273D01*
G02X932536I-1096J-1027D01*
G03Y88873I-292J273D01*
G02X934728I1096J1027D01*
G37*
G36*
G01X897917D02*
G03Y88327I292J-273D01*
G02X895725I-1096J-1027D01*
G03Y88873I-292J273D01*
G02X897917I1096J1027D01*
G37*
G36*
G01X861106D02*
G03Y88327I292J-273D01*
G02X858914I-1096J-1027D01*
G03Y88873I-292J273D01*
G02X861106I1096J1027D01*
G37*
G36*
G01X824295D02*
G03Y88327I292J-273D01*
G02X822103I-1096J-1027D01*
G03Y88873I-292J273D01*
G02X824295I1096J1027D01*
G37*
G36*
G01X787484D02*
G03Y88327I292J-273D01*
G02X785292I-1096J-1027D01*
G03Y88873I-292J273D01*
G02X787484I1096J1027D01*
G37*
G36*
G01X576262D02*
G03Y88327I292J-273D01*
G02X574070I-1096J-1027D01*
G03Y88873I-292J273D01*
G02X576262I1096J1027D01*
G37*
G36*
G01X539451D02*
G03Y88327I292J-273D01*
G02X537259I-1096J-1027D01*
G03Y88873I-292J273D01*
G02X539451I1096J1027D01*
G37*
G36*
G01X502640D02*
G03Y88327I292J-273D01*
G02X500448I-1096J-1027D01*
G03Y88873I-292J273D01*
G02X502640I1096J1027D01*
G37*
G36*
G01X465828D02*
G03Y88327I292J-273D01*
G02X463636I-1096J-1027D01*
G03Y88873I-292J273D01*
G02X465828I1096J1027D01*
G37*
G36*
G01X285120D02*
G03Y88327I292J-273D01*
G02X282928I-1096J-1027D01*
G03Y88873I-292J273D01*
G02X285120I1096J1027D01*
G37*
G36*
G01X248309D02*
G03Y88327I292J-273D01*
G02X246117I-1096J-1027D01*
G03Y88873I-292J273D01*
G02X248309I1096J1027D01*
G37*
G36*
G01X211498D02*
G03Y88327I292J-273D01*
G02X209306I-1096J-1027D01*
G03Y88873I-292J273D01*
G02X211498I1096J1027D01*
G37*
G36*
G01X174687D02*
G03Y88327I292J-273D01*
G02X172495I-1096J-1027D01*
G03Y88873I-292J273D01*
G02X174687I1096J1027D01*
G37*
G36*
G01X137876D02*
G03Y88327I292J-273D01*
G02X135684I-1096J-1027D01*
G03Y88873I-292J273D01*
G02X137876I1096J1027D01*
G37*
G36*
G01X1810887Y85685D02*
G03X1810347I-270J-295D01*
G02X1808049Y87908I-1080J1183D01*
G03Y88428I-304J260D01*
G02X1808084Y90548I1218J1040D01*
G03Y91088I-295J270D01*
G02Y93248I1183J1080D01*
G03Y93788I-295J270D01*
G02X1810347Y96051I1183J1080D01*
G03X1810887I270J295D01*
G02X1813047I1080J-1183D01*
G03X1813587I270J295D01*
G02X1815850Y93788I1080J-1183D01*
G03Y93248I295J-270D01*
G02Y91088I-1183J-1080D01*
G03Y90548I295J-270D01*
G02X1815885Y88428I-1183J-1080D01*
G03Y87908I304J-260D01*
G02X1813587Y85685I-1218J-1040D01*
G03X1813047I-270J-295D01*
G02X1810887I-1080J1183D01*
G37*
G36*
G01X1501386Y90491D02*
Y86596D01*
X1501377Y86512D01*
G02X1498364Y86681I-1502J169D01*
G01Y90481D01*
G02X1501386Y90491I1511J0D01*
G37*
G36*
G01X1598489Y83529D02*
G03X1597911I-289J-277D01*
G02Y85471I-1011J971D01*
G03X1598489I289J277D01*
G02X1600473Y85510I1011J-971D01*
G03X1601027I277J288D01*
G02Y83490I973J-1010D01*
G03X1600473I-277J-288D01*
G02X1598489Y83529I-973J1010D01*
G37*
G36*
G01X1953132Y85697D02*
G03X1953664Y85419I388J95D01*
G02X1952807Y83777I505J-1308D01*
G03X1952275Y84055I-388J-95D01*
G02X1950797Y84353I-505J1308D01*
G03X1950243I-277J-288D01*
G02X1948259Y84392I-973J1010D01*
G03X1947681I-289J-277D01*
G02X1945660Y86336I-1010J972D01*
G03Y86890I-288J277D01*
G02X1945623Y88795I1010J972D01*
G03X1945601Y89350I-299J266D01*
G02X1945560Y91336I969J1013D01*
G03Y91890I-288J277D01*
G02X1947581Y93834I1011J972D01*
G03X1948159I289J277D01*
G02X1948419Y94047I1012J-970D01*
G03X1948517Y94635I-214J338D01*
G02X1950583Y96523I1092J879D01*
G03X1951137I277J288D01*
G02X1953293Y96265I973J-1010D01*
G03X1953904Y96187I338J214D01*
G02X1955834Y96173I958J-1024D01*
G03X1956388I277J288D01*
G02X1958096Y93969I972J-1010D01*
G03X1957992Y93381I210J-340D01*
G02X1955918Y91503I-1100J-869D01*
G03X1955364I-277J-288D01*
G02X1953216Y91747I-973J1010D01*
G03X1952613Y91825I-335J-218D01*
G02X1952547Y91769I-940J1041D01*
G03Y91457I125J-156D01*
G02X1952717Y89431I-877J-1094D01*
G03X1952739Y88876I299J-266D01*
G02X1952780Y86890I-969J-1013D01*
G03Y86336I288J-277D01*
G02X1953132Y85697I-1010J-973D01*
G37*
G36*
G01X753559Y85177D02*
G03X753577Y84578I274J-292D01*
G02X751721Y84523I-897J-1078D01*
G03X751703Y85122I-274J292D01*
G02X753559Y85177I897J1078D01*
G37*
G36*
G01X1491579Y84665D02*
G03X1491783Y84181I380J-125D01*
G02X1489789Y83197I-619J-1258D01*
G03X1489529Y83653I-392J78D01*
G02X1491579Y84665I528J1512D01*
G37*
G36*
G01X1664527Y80590D02*
G03X1663973I-277J-288D01*
G02Y82610I-973J1010D01*
G03X1664527I277J288D01*
G02X1666473I973J-1010D01*
G03X1667027I277J288D01*
G02X1668973I973J-1010D01*
G03X1669527I277J288D01*
G02X1671473I973J-1010D01*
G03X1672027I277J288D01*
G02X1673973I973J-1010D01*
G03X1674527I277J288D01*
G02X1676473I973J-1010D01*
G03X1677027I277J288D01*
G02Y80590I973J-1010D01*
G03X1676473I-277J-288D01*
G02X1674527I-973J1010D01*
G03X1673973I-277J-288D01*
G02X1672027I-973J1010D01*
G03X1671473I-277J-288D01*
G02X1669527I-973J1010D01*
G03X1668973I-277J-288D01*
G02X1667027I-973J1010D01*
G03X1666473I-277J-288D01*
G02X1664527I-973J1010D01*
G37*
G36*
G01X1540631Y78303D02*
G03X1540043Y78212I-253J-310D01*
G02X1539759Y80064I-1173J768D01*
G03X1540347Y80155I253J310D01*
G02X1540631Y78303I1173J-768D01*
G37*
G36*
G01X1695009Y79103D02*
G03X1695533Y79134I244J317D01*
G02Y76848I1122J-1143D01*
G03X1695009Y76879I-280J-286D01*
G02X1693182Y76981I-854J1112D01*
G03X1692628I-277J-288D01*
G02X1690682I-973J1010D01*
G03X1690128I-277J-288D01*
G02Y79001I-973J1010D01*
G03X1690682I277J288D01*
G02X1692628I973J-1010D01*
G03X1693182I277J288D01*
G02X1695009Y79103I973J-1010D01*
G37*
G36*
G01X1822075Y76146D02*
G03X1821535I-270J-295D01*
G02X1819255Y78390I-1079J1184D01*
G03X1819261Y78912I-300J264D01*
G02X1821568Y81126I1226J1032D01*
G03X1822108I270J295D01*
G02X1824388Y78882I1079J-1184D01*
G03X1824382Y78360I300J-264D01*
G02X1822075Y76146I-1226J-1032D01*
G37*
G36*
G01X1394060Y75160D02*
G03X1393524I-268J-297D01*
G02X1391612Y77211I-940J1040D01*
G03Y77787I-277J288D01*
G02X1393523Y79839I972J1011D01*
G03X1394059Y79840I267J297D01*
G02X1395934Y79846I941J-1040D01*
G03X1396466I266J298D01*
G02X1398371Y77789I934J-1045D01*
G03Y77211I277J-289D01*
G02X1396466Y75154I-971J-1012D01*
G03X1395934I-266J-298D01*
G02X1394060Y75160I-934J1046D01*
G37*
G36*
G01X1581396Y74870D02*
G03X1580818I-289J-277D01*
G02Y76812I-1011J971D01*
G03X1581396I289J277D01*
G02Y74870I1011J-971D01*
G37*
G36*
G01X1571535Y76354D02*
G03X1572104Y76339I292J273D01*
G02X1572052Y74370I972J-1011D01*
G03X1571483Y74385I-292J-273D01*
G02X1571535Y76354I-972J1011D01*
G37*
G36*
G01X732634Y74469D02*
G03X732024Y74447I-296J-270D01*
G02X731960Y76258I-1101J868D01*
G03X732570Y76280I296J270D01*
G02X732634Y74469I1101J-868D01*
G37*
G36*
G01X1622583Y74541D02*
G03X1622036Y74329I-175J-359D01*
G02X1621350Y76106I-1303J518D01*
G03X1621897Y76318I175J359D01*
G02X1622583Y74541I1303J-518D01*
G37*
G36*
G01X1675015Y75899D02*
G03X1675598Y75776I347J200D01*
G02X1675213Y73947I830J-1130D01*
G03X1674630Y74070I-347J-200D01*
G02X1675015Y75899I-830J1130D01*
G37*
G36*
G01X1680934Y75447D02*
G03X1681488Y75412I295J270D01*
G02X1681362Y73397I908J-1068D01*
G03X1680808Y73432I-295J-270D01*
G02X1680934Y75447I-908J1068D01*
G37*
G36*
G01X62027Y72990D02*
G03X61473I-277J-288D01*
G02X59490Y74973I-973J1010D01*
G03Y75527I-288J277D01*
G02Y77473I1010J973D01*
G03Y78027I-288J277D01*
G02Y79973I1010J973D01*
G03Y80527I-288J277D01*
G02X61473Y82510I1010J973D01*
G03X62027I277J288D01*
G02X64010Y80527I973J-1010D01*
G03Y79973I288J-277D01*
G02Y78027I-1010J-973D01*
G03Y77473I288J-277D01*
G02Y75527I-1010J-973D01*
G03Y74973I288J-277D01*
G02X62027Y72990I-1010J-973D01*
G37*
G36*
G01X1454277Y74673D02*
G03X1454869Y74662I301J263D01*
G02X1454833Y72777I1020J-962D01*
G03X1454241Y72788I-301J-263D01*
G02X1454277Y74673I-1020J962D01*
G37*
G36*
G01X1563646Y75326D02*
G03X1563707Y74752I306J-258D01*
G02X1561779Y74547I-857J-1110D01*
G03X1561718Y75121I-306J258D01*
G02X1563646Y75326I857J1110D01*
G37*
G36*
G01X1895824Y72653D02*
G03X1895156Y72632I-327J-230D01*
G02X1893701Y74743I-1195J733D01*
G03X1894010Y75250I-74J393D01*
G02X1896722Y75344I1344J400D01*
G03X1897081Y74858I390J-87D01*
G02X1895824Y72653I-111J-1398D01*
G37*
G36*
G01X76473Y71510D02*
G03X77027I277J288D01*
G02X77776Y71884I972J-1010D01*
G03X78109Y72328I-64J395D01*
G02X79724Y71116I1391J172D01*
G03X79391Y70672I64J-395D01*
G02X77027Y69490I-1391J-172D01*
G03X76473I-277J-288D01*
G02X74527I-973J1010D01*
G03X73973I-277J-288D01*
G02X72027I-973J1010D01*
G03X71473I-277J-288D01*
G02X69527I-973J1010D01*
G03X68973I-277J-288D01*
G02X67027I-973J1010D01*
G03X66473I-277J-288D01*
G02X64527I-973J1010D01*
G03X63973I-277J-288D01*
G02X62027I-973J1010D01*
G03X61473I-277J-288D01*
G02Y71510I-973J1010D01*
G03X62027I277J288D01*
G02X63973I973J-1010D01*
G03X64527I277J288D01*
G02X66473I973J-1010D01*
G03X67027I277J288D01*
G02X68973I973J-1010D01*
G03X69527I277J288D01*
G02X71473I973J-1010D01*
G03X72027I277J288D01*
G02X73973I973J-1010D01*
G03X74527I277J288D01*
G02X76473I973J-1010D01*
G37*
G36*
G01X1825167Y71302D02*
G03X1825191Y70703I276J-289D01*
G02X1823012Y68364I-1011J-1243D01*
G03X1822431Y68366I-291J-274D01*
G02X1820139Y70604I-1161J1104D01*
G03X1820099Y71206I-282J284D01*
G02X1822273Y73537I970J1275D01*
G03X1822871Y73533I301J264D01*
G02X1825167Y71302I1189J-1073D01*
G37*
G36*
G01X1795700Y70821D02*
G03X1796100Y70402I400J-19D01*
G01X1796101D01*
G02X1794500Y68877I-1J-1602D01*
G03X1794100Y69296I-400J19D01*
G01X1794099D01*
G02X1795700Y70821I1J1602D01*
G37*
G36*
G01X1225862Y70164D02*
G03X1225868Y69607I290J-275D01*
G02X1223712Y69585I-1067J-1057D01*
G03X1223706Y70142I-290J275D01*
G02X1225862Y70164I1067J1057D01*
G37*
G36*
G01X1189051D02*
G03X1189057Y69607I290J-275D01*
G02X1186901Y69585I-1067J-1057D01*
G03X1186895Y70142I-290J275D01*
G02X1189051Y70164I1067J1057D01*
G37*
G36*
G01X1152240D02*
G03X1152246Y69607I290J-275D01*
G02X1150090Y69585I-1067J-1057D01*
G03X1150084Y70142I-290J275D01*
G02X1152240Y70164I1067J1057D01*
G37*
G36*
G01X1115428D02*
G03X1115434Y69607I290J-275D01*
G02X1113278Y69585I-1067J-1057D01*
G03X1113272Y70142I-290J275D01*
G02X1115428Y70164I1067J1057D01*
G37*
G36*
G01X934720D02*
G03X934726Y69607I290J-275D01*
G02X932570Y69585I-1067J-1057D01*
G03X932564Y70142I-290J275D01*
G02X934720Y70164I1067J1057D01*
G37*
G36*
G01X897909D02*
G03X897915Y69607I290J-275D01*
G02X895759Y69585I-1067J-1057D01*
G03X895753Y70142I-290J275D01*
G02X897909Y70164I1067J1057D01*
G37*
G36*
G01X861098D02*
G03X861104Y69607I290J-275D01*
G02X858948Y69585I-1067J-1057D01*
G03X858942Y70142I-290J275D01*
G02X861098Y70164I1067J1057D01*
G37*
G36*
G01X824287D02*
G03X824293Y69607I290J-275D01*
G02X822137Y69585I-1067J-1057D01*
G03X822131Y70142I-290J275D01*
G02X824287Y70164I1067J1057D01*
G37*
G36*
G01X787476D02*
G03X787482Y69607I290J-275D01*
G02X785326Y69585I-1067J-1057D01*
G03X785320Y70142I-290J275D01*
G02X787476Y70164I1067J1057D01*
G37*
G36*
G01X576254D02*
G03X576260Y69607I290J-275D01*
G02X574104Y69585I-1067J-1057D01*
G03X574098Y70142I-290J275D01*
G02X576254Y70164I1067J1057D01*
G37*
G36*
G01X539443D02*
G03X539449Y69607I290J-275D01*
G02X537293Y69585I-1067J-1057D01*
G03X537287Y70142I-290J275D01*
G02X539443Y70164I1067J1057D01*
G37*
G36*
G01X502632D02*
G03X502638Y69607I290J-275D01*
G02X500482Y69585I-1067J-1057D01*
G03X500476Y70142I-290J275D01*
G02X502632Y70164I1067J1057D01*
G37*
G36*
G01X465820D02*
G03X465826Y69607I290J-275D01*
G02X463670Y69585I-1067J-1057D01*
G03X463664Y70142I-290J275D01*
G02X465820Y70164I1067J1057D01*
G37*
G36*
G01X285112D02*
G03X285118Y69607I290J-275D01*
G02X282962Y69585I-1067J-1057D01*
G03X282956Y70142I-290J275D01*
G02X285112Y70164I1067J1057D01*
G37*
G36*
G01X248301D02*
G03X248307Y69607I290J-275D01*
G02X246151Y69585I-1067J-1057D01*
G03X246145Y70142I-290J275D01*
G02X248301Y70164I1067J1057D01*
G37*
G36*
G01X211490D02*
G03X211496Y69607I290J-275D01*
G02X209340Y69585I-1067J-1057D01*
G03X209334Y70142I-290J275D01*
G02X211490Y70164I1067J1057D01*
G37*
G36*
G01X174679D02*
G03X174685Y69607I290J-275D01*
G02X172529Y69585I-1067J-1057D01*
G03X172523Y70142I-290J275D01*
G02X174679Y70164I1067J1057D01*
G37*
G36*
G01X137868D02*
G03X137874Y69607I290J-275D01*
G02X135718Y69585I-1067J-1057D01*
G03X135712Y70142I-290J275D01*
G02X137868Y70164I1067J1057D01*
G37*
G36*
G01X1230967Y69919D02*
G03Y69370I291J-274D01*
G02X1228781I-1093J-1030D01*
G03Y69919I-291J274D01*
G02X1230967I1093J1030D01*
G37*
G36*
G01X1194156D02*
G03Y69370I291J-274D01*
G02X1191970I-1093J-1030D01*
G03Y69919I-291J274D01*
G02X1194156I1093J1030D01*
G37*
G36*
G01X1157345D02*
G03Y69370I291J-274D01*
G02X1155159I-1093J-1030D01*
G03Y69919I-291J274D01*
G02X1157345I1093J1030D01*
G37*
G36*
G01X1120533D02*
G03Y69370I291J-274D01*
G02X1118347I-1093J-1030D01*
G03Y69919I-291J274D01*
G02X1120533I1093J1030D01*
G37*
G36*
G01X939825D02*
G03Y69370I291J-274D01*
G02X937639I-1093J-1030D01*
G03Y69919I-291J274D01*
G02X939825I1093J1030D01*
G37*
G36*
G01X903014D02*
G03Y69370I291J-274D01*
G02X900828I-1093J-1030D01*
G03Y69919I-291J274D01*
G02X903014I1093J1030D01*
G37*
G36*
G01X866203D02*
G03Y69370I291J-274D01*
G02X864017I-1093J-1030D01*
G03Y69919I-291J274D01*
G02X866203I1093J1030D01*
G37*
G36*
G01X829392D02*
G03Y69370I291J-274D01*
G02X827206I-1093J-1030D01*
G03Y69919I-291J274D01*
G02X829392I1093J1030D01*
G37*
G36*
G01X792581D02*
G03Y69370I291J-274D01*
G02X790395I-1093J-1030D01*
G03Y69919I-291J274D01*
G02X792581I1093J1030D01*
G37*
G36*
G01X581359D02*
G03Y69370I291J-274D01*
G02X579173I-1093J-1030D01*
G03Y69919I-291J274D01*
G02X581359I1093J1030D01*
G37*
G36*
G01X544548D02*
G03Y69370I291J-274D01*
G02X542362I-1093J-1030D01*
G03Y69919I-291J274D01*
G02X544548I1093J1030D01*
G37*
G36*
G01X507737D02*
G03Y69370I291J-274D01*
G02X505551I-1093J-1030D01*
G03Y69919I-291J274D01*
G02X507737I1093J1030D01*
G37*
G36*
G01X470925D02*
G03Y69370I291J-274D01*
G02X468739I-1093J-1030D01*
G03Y69919I-291J274D01*
G02X470925I1093J1030D01*
G37*
G36*
G01X290217D02*
G03Y69370I291J-274D01*
G02X288031I-1093J-1030D01*
G03Y69919I-291J274D01*
G02X290217I1093J1030D01*
G37*
G36*
G01X253406D02*
G03Y69370I291J-274D01*
G02X251220I-1093J-1030D01*
G03Y69919I-291J274D01*
G02X253406I1093J1030D01*
G37*
G36*
G01X216595D02*
G03Y69370I291J-274D01*
G02X214409I-1093J-1030D01*
G03Y69919I-291J274D01*
G02X216595I1093J1030D01*
G37*
G36*
G01X179784D02*
G03Y69370I291J-274D01*
G02X177598I-1093J-1030D01*
G03Y69919I-291J274D01*
G02X179784I1093J1030D01*
G37*
G36*
G01X142973D02*
G03Y69370I291J-274D01*
G02X140787I-1093J-1030D01*
G03Y69919I-291J274D01*
G02X142973I1093J1030D01*
G37*
G36*
G01X1845615Y66161D02*
G03X1845085I-265J-300D01*
G02X1842527Y67931I-1060J1201D01*
G03X1842226Y68466I-374J142D01*
G02X1841455Y68841I290J1576D01*
G03X1840925I-265J-300D01*
G02X1838834Y68816I-1060J1201D01*
G03X1838293Y68793I-258J-306D01*
G02X1835740Y69186I-1132J1133D01*
G03X1835120Y69301I-355J-185D01*
G02X1832973Y69324I-1061J1200D01*
G03X1832454Y69343I-271J-295D01*
G02X1830277Y71680I-994J1256D01*
G03Y72220I-295J270D01*
G02X1832643I1183J1080D01*
G03Y71680I295J-270D01*
G02X1832657Y71664I-1198J-1063D01*
G03X1832946Y71653I150J133D01*
G02X1835579Y71007I1113J-1152D01*
G03X1835923Y70943I190J63D01*
G02X1835930Y70951I1209J-1051D01*
G03X1835924Y71471I-307J256D01*
G02X1835592Y72979I1205J1056D01*
G03X1835310Y73479I-384J113D01*
G02X1835250Y76562I404J1550D01*
G03X1835522Y77042I-116J383D01*
G02X1838205Y78566I1555J387D01*
G03X1838786Y78585I282J284D01*
G02X1841073Y78698I1199J-1063D01*
G03X1841632Y78713I272J293D01*
G02X1844328Y77177I1151J-1114D01*
G03X1844581Y76695I386J-105D01*
G02X1845132Y76364I-533J-1511D01*
G03X1845655Y76348I271J294D01*
G02X1847024Y73544I1012J-1242D01*
G03X1846724Y73062I89J-390D01*
G02X1846366Y71632I-1559J-370D01*
G03Y71102I300J-265D01*
G02X1846663Y69473I-1201J-1061D01*
G03X1846964Y68938I374J-142D01*
G02X1847735Y68563I-290J-1576D01*
G03X1848265I265J300D01*
G02Y66161I1060J-1201D01*
G03X1847735I-265J-300D01*
G02X1845615I-1060J1201D01*
G37*
G36*
G01X1733Y66210D02*
G03X1351Y66698I-390J88D01*
G02X2749Y67790I31J1402D01*
G03X3131Y67302I390J-88D01*
G02X1733Y66210I-31J-1402D01*
G37*
G36*
G01X1328429Y66950D02*
G03Y66350I265J-300D01*
G02X1326571I-929J-1050D01*
G03Y66950I-265J300D01*
G02X1326598Y69073I929J1050D01*
G03X1326591Y69692I-257J307D01*
G02X1328369Y69713I876J1094D01*
G03X1328376Y69094I257J-307D01*
G02X1328429Y66950I-876J-1094D01*
G37*
G36*
G01X1649871Y64260D02*
G03X1649293Y64256I-287J-279D01*
G02X1649281Y66198I-1017J965D01*
G03X1649859Y66202I287J279D01*
G02X1649871Y64260I1017J-965D01*
G37*
G36*
G01X734722Y65252D02*
G03X734742Y64719I308J-255D01*
G02X732775Y62723I-1010J-972D01*
G03X732242Y62735I-273J-292D01*
G02X730252Y64695I-910J1067D01*
G03X730232Y65228I-308J255D01*
G02X730180Y67115I1010J972D01*
G03X730171Y67648I-303J261D01*
G02X732157Y69624I1029J952D01*
G03X732690Y69612I273J292D01*
G02X734662Y67631I909J-1067D01*
G03X734671Y67098I303J-261D01*
G02X734722Y65252I-1029J-952D01*
G37*
G36*
G01X1785725Y65065D02*
G03X1786169Y64732I395J64D01*
G02X1784957Y63117I172J-1391D01*
G03X1784513Y63450I-395J-64D01*
G02X1785725Y65065I-172J1391D01*
G37*
G36*
G01X1610284Y62579D02*
G03X1609752Y62364I-162J-365D01*
G02X1607065Y63094I-1300J526D01*
G03X1606698Y63551I-396J58D01*
G02X1608184Y64745I99J1398D01*
G03X1608551Y64288I396J-58D01*
G02X1609021Y64172I-96J-1399D01*
G03X1609553Y64387I162J365D01*
G02X1610284Y62579I1300J-526D01*
G37*
G36*
G01X1734177Y57140D02*
G03X1733623I-277J-288D01*
G02X1731640Y59123I-973J1010D01*
G03Y59677I-288J277D01*
G02X1733660I1010J973D01*
G03Y59123I288J-277D01*
G02X1733744Y59027I-1012J-970D01*
G03X1734056I156J125D01*
G02X1734177Y57140I1094J-877D01*
G37*
G36*
G01X15614Y55240D02*
G03X15036I-289J-277D01*
G02Y57182I-1011J971D01*
G03X15614I289J277D01*
G02Y55240I1011J-971D01*
G37*
G36*
G01X60527Y54990D02*
G03X59973I-277J-288D01*
G02X57990Y56973I-973J1010D01*
G03Y57527I-288J277D01*
G02Y59473I1010J973D01*
G03Y60027I-288J277D01*
G02X59973Y62010I1010J973D01*
G03X60527I277J288D01*
G02X62510Y60027I973J-1010D01*
G03Y59473I288J-277D01*
G02Y57527I-1010J-973D01*
G03Y56973I288J-277D01*
G02X60527Y54990I-1010J-973D01*
G37*
G36*
G01X1816718Y55668D02*
G03X1817330Y55663I308J255D01*
G02X1817315Y53859I1066J-911D01*
G03X1816703Y53864I-308J-255D01*
G02X1816718Y55668I-1066J911D01*
G37*
G36*
G01X1825893Y54749D02*
G03X1826068Y54496I193J-54D01*
G02X1824348Y53154I-138J-1596D01*
G03X1824033Y53610I-395J64D01*
G02X1823249Y56344I317J1570D01*
G03X1823261Y56913I-275J290D01*
G02X1823034Y58850I1149J1116D01*
G03X1822918Y59383I-344J204D01*
G02X1825206Y59880I912J1317D01*
G03X1825322Y59347I344J-204D01*
G02X1825980Y58351I-912J-1318D01*
G03X1826477Y58045I392J80D01*
G02X1826212Y55053I423J-1545D01*
G03X1825929Y54907I-86J-180D01*
G02X1825893Y54749I-1578J276D01*
G37*
G36*
G01X1668527Y50490D02*
G03X1667973I-277J-288D01*
G02Y52510I-973J1010D01*
G03X1668527I277J288D01*
G02Y50490I973J-1010D01*
G37*
G36*
G01X1230970Y51287D02*
G03Y50741I292J-273D01*
G02X1228778I-1096J-1027D01*
G03Y51287I-292J273D01*
G02X1230970I1096J1027D01*
G37*
G36*
G01X1194159D02*
G03Y50741I292J-273D01*
G02X1191967I-1096J-1027D01*
G03Y51287I-292J273D01*
G02X1194159I1096J1027D01*
G37*
G36*
G01X1157347D02*
G03Y50741I292J-273D01*
G02X1155155I-1096J-1027D01*
G03Y51287I-292J273D01*
G02X1157347I1096J1027D01*
G37*
G36*
G01X1120536D02*
G03Y50741I292J-273D01*
G02X1118344I-1096J-1027D01*
G03Y51287I-292J273D01*
G02X1120536I1096J1027D01*
G37*
G36*
G01X939828D02*
G03Y50741I292J-273D01*
G02X937636I-1096J-1027D01*
G03Y51287I-292J273D01*
G02X939828I1096J1027D01*
G37*
G36*
G01X903017D02*
G03Y50741I292J-273D01*
G02X900825I-1096J-1027D01*
G03Y51287I-292J273D01*
G02X903017I1096J1027D01*
G37*
G36*
G01X866206D02*
G03Y50741I292J-273D01*
G02X864014I-1096J-1027D01*
G03Y51287I-292J273D01*
G02X866206I1096J1027D01*
G37*
G36*
G01X829395D02*
G03Y50741I292J-273D01*
G02X827203I-1096J-1027D01*
G03Y51287I-292J273D01*
G02X829395I1096J1027D01*
G37*
G36*
G01X792584D02*
G03Y50741I292J-273D01*
G02X790392I-1096J-1027D01*
G03Y51287I-292J273D01*
G02X792584I1096J1027D01*
G37*
G36*
G01X581362D02*
G03Y50741I292J-273D01*
G02X579170I-1096J-1027D01*
G03Y51287I-292J273D01*
G02X581362I1096J1027D01*
G37*
G36*
G01X544551D02*
G03Y50741I292J-273D01*
G02X542359I-1096J-1027D01*
G03Y51287I-292J273D01*
G02X544551I1096J1027D01*
G37*
G36*
G01X507739D02*
G03Y50741I292J-273D01*
G02X505547I-1096J-1027D01*
G03Y51287I-292J273D01*
G02X507739I1096J1027D01*
G37*
G36*
G01X470928D02*
G03Y50741I292J-273D01*
G02X468736I-1096J-1027D01*
G03Y51287I-292J273D01*
G02X470928I1096J1027D01*
G37*
G36*
G01X290220D02*
G03Y50741I292J-273D01*
G02X288028I-1096J-1027D01*
G03Y51287I-292J273D01*
G02X290220I1096J1027D01*
G37*
G36*
G01X253409D02*
G03Y50741I292J-273D01*
G02X251217I-1096J-1027D01*
G03Y51287I-292J273D01*
G02X253409I1096J1027D01*
G37*
G36*
G01X216598D02*
G03Y50741I292J-273D01*
G02X214406I-1096J-1027D01*
G03Y51287I-292J273D01*
G02X216598I1096J1027D01*
G37*
G36*
G01X179787D02*
G03Y50741I292J-273D01*
G02X177595I-1096J-1027D01*
G03Y51287I-292J273D01*
G02X179787I1096J1027D01*
G37*
G36*
G01X142976D02*
G03Y50741I292J-273D01*
G02X140784I-1096J-1027D01*
G03Y51287I-292J273D01*
G02X142976I1096J1027D01*
G37*
G36*
G01X1225870Y51073D02*
G03Y50527I292J-273D01*
G02X1223678I-1096J-1027D01*
G03Y51073I-292J273D01*
G02X1225870I1096J1027D01*
G37*
G36*
G01X1189059D02*
G03Y50527I292J-273D01*
G02X1186867I-1096J-1027D01*
G03Y51073I-292J273D01*
G02X1189059I1096J1027D01*
G37*
G36*
G01X1152247D02*
G03Y50527I292J-273D01*
G02X1150055I-1096J-1027D01*
G03Y51073I-292J273D01*
G02X1152247I1096J1027D01*
G37*
G36*
G01X1115436D02*
G03Y50527I292J-273D01*
G02X1113244I-1096J-1027D01*
G03Y51073I-292J273D01*
G02X1115436I1096J1027D01*
G37*
G36*
G01X934728D02*
G03Y50527I292J-273D01*
G02X932536I-1096J-1027D01*
G03Y51073I-292J273D01*
G02X934728I1096J1027D01*
G37*
G36*
G01X897917D02*
G03Y50527I292J-273D01*
G02X895725I-1096J-1027D01*
G03Y51073I-292J273D01*
G02X897917I1096J1027D01*
G37*
G36*
G01X861106D02*
G03Y50527I292J-273D01*
G02X858914I-1096J-1027D01*
G03Y51073I-292J273D01*
G02X861106I1096J1027D01*
G37*
G36*
G01X824295D02*
G03Y50527I292J-273D01*
G02X822103I-1096J-1027D01*
G03Y51073I-292J273D01*
G02X824295I1096J1027D01*
G37*
G36*
G01X787484D02*
G03Y50527I292J-273D01*
G02X785292I-1096J-1027D01*
G03Y51073I-292J273D01*
G02X787484I1096J1027D01*
G37*
G36*
G01X576262D02*
G03Y50527I292J-273D01*
G02X574070I-1096J-1027D01*
G03Y51073I-292J273D01*
G02X576262I1096J1027D01*
G37*
G36*
G01X539451D02*
G03Y50527I292J-273D01*
G02X537259I-1096J-1027D01*
G03Y51073I-292J273D01*
G02X539451I1096J1027D01*
G37*
G36*
G01X502639D02*
G03Y50527I292J-273D01*
G02X500447I-1096J-1027D01*
G03Y51073I-292J273D01*
G02X502639I1096J1027D01*
G37*
G36*
G01X465828D02*
G03Y50527I292J-273D01*
G02X463636I-1096J-1027D01*
G03Y51073I-292J273D01*
G02X465828I1096J1027D01*
G37*
G36*
G01X285120D02*
G03Y50527I292J-273D01*
G02X282928I-1096J-1027D01*
G03Y51073I-292J273D01*
G02X285120I1096J1027D01*
G37*
G36*
G01X248309D02*
G03Y50527I292J-273D01*
G02X246117I-1096J-1027D01*
G03Y51073I-292J273D01*
G02X248309I1096J1027D01*
G37*
G36*
G01X211498D02*
G03Y50527I292J-273D01*
G02X209306I-1096J-1027D01*
G03Y51073I-292J273D01*
G02X211498I1096J1027D01*
G37*
G36*
G01X174687D02*
G03Y50527I292J-273D01*
G02X172495I-1096J-1027D01*
G03Y51073I-292J273D01*
G02X174687I1096J1027D01*
G37*
G36*
G01X137876D02*
G03Y50527I292J-273D01*
G02X135684I-1096J-1027D01*
G03Y51073I-292J273D01*
G02X137876I1096J1027D01*
G37*
G36*
G01X1744121Y46096D02*
G03X1743567I-277J-288D01*
G02Y48116I-973J1010D01*
G03X1744121I277J288D01*
G02Y46096I973J-1010D01*
G37*
G36*
G01X1363531Y44948D02*
G03X1363481Y44361I244J-316D01*
G02X1361591Y44523I-1033J-948D01*
G03X1361641Y45110I-244J316D01*
G02X1363531Y44948I1033J948D01*
G37*
G36*
G01X1309627Y40490D02*
G03X1309073I-277J-288D01*
G02Y42510I-973J1010D01*
G03X1309627I277J288D01*
G02Y40490I973J-1010D01*
G37*
G36*
G01X1324989Y40468D02*
G03X1324411I-289J-277D01*
G02X1322354Y42373I-1012J971D01*
G03Y42905I-298J266D01*
G02X1324392Y44829I1047J933D01*
G03X1324982Y44855I283J283D01*
G02X1327038Y42954I1076J-898D01*
G03X1327025Y42395I280J-286D01*
G02X1324989Y40468I-1025J-956D01*
G37*
G36*
G01X1721758Y38368D02*
X1717958D01*
G02Y41392I0J1512D01*
G01X1721759D01*
G02X1723270Y39890I-1J-1512D01*
G01Y39795D01*
X1723260Y39711D01*
G02X1721758Y38368I-1502J169D01*
G37*
G36*
G01X1703073Y38168D02*
X1699273D01*
G02Y41190I0J1511D01*
G01X1703074D01*
G02X1704584Y39689I-1J-1511D01*
G01Y39594D01*
X1704575Y39510D01*
G02X1703073Y38168I-1502J169D01*
G37*
G36*
G01X1740556Y37975D02*
Y37965D01*
X1736654Y38080D01*
X1736483Y38104D01*
G02X1736742Y41111I217J1496D01*
G01Y41121D01*
X1740642Y41006D01*
X1740650Y40998D01*
X1740723Y40992D01*
G02X1742110Y39496I-125J-1506D01*
G01Y39401D01*
X1742100Y39317D01*
G02X1740556Y37975I-1502J169D01*
G37*
G36*
G01X1731183Y37954D02*
X1727383D01*
G02Y40976I0J1511D01*
G01X1731183D01*
G02X1732694Y39475I0J-1511D01*
G01Y39380D01*
X1732685Y39296D01*
G02X1731183Y37954I-1502J169D01*
G37*
G36*
G01X1694098Y37950D02*
X1689098D01*
G02Y40974I0J1512D01*
G01X1694098D01*
G02X1695610Y39472I0J-1512D01*
G01Y39377D01*
X1695600Y39293D01*
G02X1694098Y37950I-1502J169D01*
G37*
G36*
G01X1684648D02*
X1679648D01*
G02Y40974I0J1512D01*
G01X1684649D01*
G02X1686160Y39472I-1J-1512D01*
G01Y39377D01*
X1686150Y39293D01*
G02X1684648Y37950I-1502J169D01*
G37*
G36*
G01X1675198D02*
X1670198D01*
G02Y40974I0J1512D01*
G01X1675199D01*
G02X1676710Y39472I-1J-1512D01*
G01Y39377D01*
X1676700Y39293D01*
G02X1675198Y37950I-1502J169D01*
G37*
G36*
G01X1646848D02*
X1641848D01*
G02Y40974I0J1512D01*
G01X1646849D01*
G02X1648360Y39472I-1J-1512D01*
G01Y39377D01*
X1648350Y39293D01*
G02X1646848Y37950I-1502J169D01*
G37*
G36*
G01X1712308Y37838D02*
X1708508D01*
G02Y40862I0J1512D01*
G01X1712309D01*
G02X1713820Y39360I-1J-1512D01*
G01Y39265D01*
X1713810Y39181D01*
G02X1712308Y37838I-1502J168D01*
G37*
G36*
G01X1368689Y36829D02*
G03X1368111I-289J-277D01*
G02Y38771I-1011J971D01*
G03X1368689I289J277D01*
G02Y36829I1011J-971D01*
G37*
G36*
G01X1660748Y40974D02*
X1665749D01*
G02X1667260Y39472I-1J-1512D01*
G01Y39377D01*
X1667250Y39293D01*
G02X1665748Y37950I-1502J169D01*
G01X1662563D01*
G03X1662204Y37375I1J-400D01*
G02X1659887Y37682I-1260J-614D01*
G03X1659829Y38262I-302J263D01*
G02X1660748Y40974I919J1200D01*
G37*
G36*
G01X1651297D02*
X1656299D01*
G02X1657810Y39472I-1J-1512D01*
G01Y39377D01*
X1657800Y39293D01*
G02X1656298Y37950I-1502J169D01*
G01X1652864D01*
G03X1652506Y37373I0J-400D01*
G02X1650282Y37764I-1256J-623D01*
G03X1650276Y38348I-276J289D01*
G02X1651297Y40974I1022J1114D01*
G37*
G36*
G01X1847503Y35441D02*
G03X1848058Y35439I279J287D01*
G02X1848051Y33420I969J-1013D01*
G03X1847496Y33422I-279J-287D01*
G02X1847503Y35441I-969J1013D01*
G37*
G36*
G01X655725Y30405D02*
G03X655151Y30327I-250J-312D01*
G02X652986Y30199I-1135J823D01*
G03X652415Y30215I-293J-272D01*
G02X650428Y30257I-973J1010D01*
G03X649856Y30264I-289J-276D01*
G02X649881Y32226I-989J994D01*
G03X650453Y32219I289J276D01*
G02X652472Y32176I989J-994D01*
G03X653043Y32160I293J272D01*
G02X654891Y32245I972J-1010D01*
G03X655465Y32323I250J312D01*
G02X655725Y30405I1135J-823D01*
G37*
G36*
G01X1311586Y30712D02*
G03X1311131Y30400I-64J-395D01*
G02X1309983Y32075I-1371J291D01*
G03X1310438Y32387I64J395D01*
G02X1313179Y32393I1371J-292D01*
G03X1313653Y32086I391J84D01*
G02X1314428Y32029I289J-1372D01*
G03X1314952Y32295I139J375D01*
G02X1317220Y32969I1348J-384D01*
G03X1317752Y32976I262J302D01*
G02X1319816Y32791I948J-1033D01*
G03X1320427Y32760I319J242D01*
G02X1320336Y30955I1025J-956D01*
G03X1319725Y30986I-319J-242D01*
G02X1317780Y30885I-1025J957D01*
G03X1317248Y30878I-262J-302D01*
G02X1315814Y30596I-948J1033D01*
G03X1315290Y30330I-139J-375D01*
G02X1312572Y30417I-1348J384D01*
G03X1312098Y30724I-391J-84D01*
G02X1311586Y30712I-288J1372D01*
G37*
G36*
G01X1225862Y32364D02*
G03X1225868Y31807I290J-275D01*
G02X1223712Y31785I-1067J-1057D01*
G03X1223706Y32342I-290J275D01*
G02X1225862Y32364I1067J1057D01*
G37*
G36*
G01X1189051D02*
G03X1189057Y31807I290J-275D01*
G02X1186901Y31785I-1067J-1057D01*
G03X1186895Y32342I-290J275D01*
G02X1189051Y32364I1067J1057D01*
G37*
G36*
G01X1152239D02*
G03X1152245Y31807I290J-275D01*
G02X1150089Y31785I-1067J-1057D01*
G03X1150083Y32342I-290J275D01*
G02X1152239Y32364I1067J1057D01*
G37*
G36*
G01X1115428D02*
G03X1115434Y31807I290J-275D01*
G02X1113278Y31785I-1067J-1057D01*
G03X1113272Y32342I-290J275D01*
G02X1115428Y32364I1067J1057D01*
G37*
G36*
G01X934720D02*
G03X934726Y31807I290J-275D01*
G02X932570Y31785I-1067J-1057D01*
G03X932564Y32342I-290J275D01*
G02X934720Y32364I1067J1057D01*
G37*
G36*
G01X897909D02*
G03X897915Y31807I290J-275D01*
G02X895759Y31785I-1067J-1057D01*
G03X895753Y32342I-290J275D01*
G02X897909Y32364I1067J1057D01*
G37*
G36*
G01X861098D02*
G03X861104Y31807I290J-275D01*
G02X858948Y31785I-1067J-1057D01*
G03X858942Y32342I-290J275D01*
G02X861098Y32364I1067J1057D01*
G37*
G36*
G01X824287D02*
G03X824293Y31807I290J-275D01*
G02X822137Y31785I-1067J-1057D01*
G03X822131Y32342I-290J275D01*
G02X824287Y32364I1067J1057D01*
G37*
G36*
G01X787476D02*
G03X787482Y31807I290J-275D01*
G02X785326Y31785I-1067J-1057D01*
G03X785320Y32342I-290J275D01*
G02X787476Y32364I1067J1057D01*
G37*
G36*
G01X576254D02*
G03X576260Y31807I290J-275D01*
G02X574104Y31785I-1067J-1057D01*
G03X574098Y32342I-290J275D01*
G02X576254Y32364I1067J1057D01*
G37*
G36*
G01X539443D02*
G03X539449Y31807I290J-275D01*
G02X537293Y31785I-1067J-1057D01*
G03X537287Y32342I-290J275D01*
G02X539443Y32364I1067J1057D01*
G37*
G36*
G01X502631D02*
G03X502637Y31807I290J-275D01*
G02X500481Y31785I-1067J-1057D01*
G03X500475Y32342I-290J275D01*
G02X502631Y32364I1067J1057D01*
G37*
G36*
G01X465820D02*
G03X465826Y31807I290J-275D01*
G02X463670Y31785I-1067J-1057D01*
G03X463664Y32342I-290J275D01*
G02X465820Y32364I1067J1057D01*
G37*
G36*
G01X285112D02*
G03X285118Y31807I290J-275D01*
G02X282962Y31785I-1067J-1057D01*
G03X282956Y32342I-290J275D01*
G02X285112Y32364I1067J1057D01*
G37*
G36*
G01X248301D02*
G03X248307Y31807I290J-275D01*
G02X246151Y31785I-1067J-1057D01*
G03X246145Y32342I-290J275D01*
G02X248301Y32364I1067J1057D01*
G37*
G36*
G01X211490D02*
G03X211496Y31807I290J-275D01*
G02X209340Y31785I-1067J-1057D01*
G03X209334Y32342I-290J275D01*
G02X211490Y32364I1067J1057D01*
G37*
G36*
G01X174679D02*
G03X174685Y31807I290J-275D01*
G02X172529Y31785I-1067J-1057D01*
G03X172523Y32342I-290J275D01*
G02X174679Y32364I1067J1057D01*
G37*
G36*
G01X137868D02*
G03X137874Y31807I290J-275D01*
G02X135718Y31785I-1067J-1057D01*
G03X135712Y32342I-290J275D01*
G02X137868Y32364I1067J1057D01*
G37*
G36*
G01X1230967Y32119D02*
G03Y31570I291J-275D01*
G02X1228781I-1093J-1030D01*
G03Y32119I-291J274D01*
G02X1230967I1093J1030D01*
G37*
G36*
G01X1194156D02*
G03Y31570I291J-275D01*
G02X1191970I-1093J-1030D01*
G03Y32119I-291J274D01*
G02X1194156I1093J1030D01*
G37*
G36*
G01X1157344D02*
G03Y31570I291J-275D01*
G02X1155158I-1093J-1030D01*
G03Y32119I-291J274D01*
G02X1157344I1093J1030D01*
G37*
G36*
G01X1120533D02*
G03Y31570I291J-275D01*
G02X1118347I-1093J-1030D01*
G03Y32119I-291J274D01*
G02X1120533I1093J1030D01*
G37*
G36*
G01X939825D02*
G03Y31570I291J-275D01*
G02X937639I-1093J-1030D01*
G03Y32119I-291J274D01*
G02X939825I1093J1030D01*
G37*
G36*
G01X903014D02*
G03Y31570I291J-275D01*
G02X900828I-1093J-1030D01*
G03Y32119I-291J274D01*
G02X903014I1093J1030D01*
G37*
G36*
G01X866203D02*
G03Y31570I291J-275D01*
G02X864017I-1093J-1030D01*
G03Y32119I-291J274D01*
G02X866203I1093J1030D01*
G37*
G36*
G01X829392D02*
G03Y31570I291J-275D01*
G02X827206I-1093J-1030D01*
G03Y32119I-291J274D01*
G02X829392I1093J1030D01*
G37*
G36*
G01X792581D02*
G03Y31570I291J-275D01*
G02X790395I-1093J-1030D01*
G03Y32119I-291J274D01*
G02X792581I1093J1030D01*
G37*
G36*
G01X581359D02*
G03Y31570I291J-275D01*
G02X579173I-1093J-1030D01*
G03Y32119I-291J274D01*
G02X581359I1093J1030D01*
G37*
G36*
G01X544548D02*
G03Y31570I291J-275D01*
G02X542362I-1093J-1030D01*
G03Y32119I-291J274D01*
G02X544548I1093J1030D01*
G37*
G36*
G01X507736D02*
G03Y31570I291J-275D01*
G02X505550I-1093J-1030D01*
G03Y32119I-291J274D01*
G02X507736I1093J1030D01*
G37*
G36*
G01X470925D02*
G03Y31570I291J-275D01*
G02X468739I-1093J-1030D01*
G03Y32119I-291J274D01*
G02X470925I1093J1030D01*
G37*
G36*
G01X290217D02*
G03Y31570I291J-275D01*
G02X288031I-1093J-1030D01*
G03Y32119I-291J274D01*
G02X290217I1093J1030D01*
G37*
G36*
G01X253406D02*
G03Y31570I291J-275D01*
G02X251220I-1093J-1030D01*
G03Y32119I-291J274D01*
G02X253406I1093J1030D01*
G37*
G36*
G01X216595D02*
G03Y31570I291J-275D01*
G02X214409I-1093J-1030D01*
G03Y32119I-291J274D01*
G02X216595I1093J1030D01*
G37*
G36*
G01X179784D02*
G03Y31570I291J-275D01*
G02X177598I-1093J-1030D01*
G03Y32119I-291J274D01*
G02X179784I1093J1030D01*
G37*
G36*
G01X142973D02*
G03Y31570I291J-275D01*
G02X140787I-1093J-1030D01*
G03Y32119I-291J274D01*
G02X142973I1093J1030D01*
G37*
G36*
G01X1758406Y34262D02*
Y30367D01*
X1758397Y30283D01*
G02X1755384Y30452I-1502J169D01*
G01Y34252D01*
G02X1758406Y34262I1511J0D01*
G37*
G36*
G01X683076Y27208D02*
G03X682476I-300J-265D01*
G02Y29066I-1050J929D01*
G03X683076I300J265D01*
G02Y27208I1050J-929D01*
G37*
G36*
G01X1523780Y27567D02*
G03X1523280Y27252I-106J-386D01*
G02X1522274Y28851I-1380J248D01*
G03X1522774Y29166I106J386D01*
G02X1523780Y27567I1380J-248D01*
G37*
G36*
G01X1509078Y30563D02*
G03X1508559Y30154I-120J-381D01*
G02X1507596Y32459I-3893J-273D01*
G03X1508253Y32540I301J264D01*
G02X1509078Y30563I1247J-640D01*
G37*
G36*
G01X1808288Y27703D02*
G03X1808887Y27629I332J224D01*
G02X1808661Y25800I935J-1044D01*
G03X1808062Y25874I-332J-224D01*
G02X1808288Y27703I-935J1044D01*
G37*
G36*
G01X1380536Y27426D02*
G03X1381078Y27181I381J121D01*
G02X1380306Y25472I564J-1284D01*
G03X1379764Y25717I-381J-121D01*
G02X1380536Y27426I-564J1284D01*
G37*
G36*
G01X14801Y25749D02*
G03X15397Y25723I310J253D01*
G02X15315Y23856I1003J-979D01*
G03X14719Y23882I-310J-253D01*
G02X14801Y25749I-1003J979D01*
G37*
G36*
G01X1767069Y22498D02*
X1763360D01*
G02Y25522I0J1512D01*
G01X1767069D01*
G02X1768580Y24020I-1J-1512D01*
G01Y23925D01*
X1768571Y23841D01*
G02X1767069Y22498I-1502J169D01*
G37*
G36*
G01X1550861Y22846D02*
G03X1550307I-277J-288D01*
G02Y24866I-973J1010D01*
G03X1550861I277J288D01*
G02X1552845Y24827I973J-1010D01*
G03X1553423I289J277D01*
G02Y22885I1011J-971D01*
G03X1552845I-289J-277D01*
G02X1550861Y22846I-1011J971D01*
G37*
G36*
G01X1748152Y21686D02*
X1743152D01*
G02Y24708I0J1511D01*
G01X1748153D01*
G02X1749664Y23207I0J-1512D01*
G01Y23112D01*
X1749654Y23028D01*
G02X1748152Y21686I-1502J169D01*
G37*
G36*
G01X655327Y21790D02*
G03X654773I-277J-288D01*
G02Y23810I-973J1010D01*
G03X655327I277J288D01*
G02Y21790I973J-1010D01*
G37*
G36*
G01X1738168Y20800D02*
X1733168D01*
G02Y23824I0J1512D01*
G01X1738169D01*
G02X1739680Y22322I-1J-1512D01*
G01Y22227D01*
X1739670Y22143D01*
G02X1738168Y20800I-1502J169D01*
G37*
G36*
G01X1532430Y23307D02*
G02Y24629I3693J661D01*
G02Y23307I3693J-661D01*
G37*
G36*
G01X1824343Y22637D02*
G03X1824913Y22612I297J267D01*
G02X1824827Y20650I957J-1025D01*
G03X1824257Y20675I-297J-267D01*
G02X1824343Y22637I-957J1025D01*
G37*
G36*
G01X691427Y19790D02*
G03X690873I-277J-288D01*
G02Y21810I-973J1010D01*
G03X691427I277J288D01*
G02Y19790I973J-1010D01*
G37*
G36*
G01X1760709Y18534D02*
X1757009Y18496D01*
G02X1756976Y21518I-16J1511D01*
G01X1760677Y21556D01*
G02X1762198Y20189I16J-1511D01*
G01X1762204Y20130D01*
X1762205Y20071D01*
G02Y20019I-1512J-26D01*
G01X1762204Y20017D01*
Y20007D01*
G02X1760709Y18534I-1511J38D01*
G37*
G36*
G01X1375911Y14137D02*
G03X1375375Y14134I-266J-299D01*
G02X1373408Y14211I-944J1036D01*
G03X1372860Y14245I-292J-273D01*
G02X1370835Y16459I-959J1156D01*
G03Y16741I-142J141D01*
G02X1370857Y18881I1065J1059D01*
G03X1370863Y19163I-139J144D01*
G02X1370888Y21263I1087J1037D01*
G03X1370887Y21547I-141J142D01*
G02X1373003Y21554I1054J1070D01*
G03X1373004Y21270I141J-142D01*
G02X1372993Y19119I-1054J-1070D01*
G03X1372987Y18837I139J-144D01*
G02X1372965Y16741I-1087J-1037D01*
G03Y16459I142J-141D01*
G02X1373053Y16363I-1062J-1062D01*
G03X1373598Y16297I307J256D01*
G02X1375362Y16218I833J-1127D01*
G03X1375898Y16221I266J299D01*
G02X1375911Y14137I944J-1036D01*
G37*
G36*
G01X1577048Y10994D02*
X1573048D01*
G02Y14018I0J1512D01*
G01X1577049D01*
G02X1578560Y12516I-1J-1512D01*
G01Y12421D01*
X1578550Y12337D01*
G02X1577048Y10994I-1502J169D01*
G37*
G36*
G01X1567498D02*
X1563498D01*
G02Y14018I0J1512D01*
G01X1567499D01*
G02X1569010Y12516I-1J-1512D01*
G01Y12421D01*
X1569000Y12337D01*
G02X1567498Y10994I-1502J169D01*
G37*
G36*
G01X1548698D02*
X1544698D01*
G02Y14018I0J1512D01*
G01X1548699D01*
G02X1550210Y12516I-1J-1512D01*
G01Y12421D01*
X1550200Y12337D01*
G02X1548698Y10994I-1502J169D01*
G37*
G36*
G01X1554148Y13818D02*
X1558148D01*
G02X1559660Y12316I0J-1512D01*
G01Y12221D01*
X1559650Y12137D01*
G02X1558148Y10794I-1502J169D01*
G01X1554148D01*
G02Y13818I0J1512D01*
G37*
G36*
G01X1230970Y13487D02*
G03Y12941I292J-273D01*
G02X1228778I-1096J-1027D01*
G03Y13487I-292J273D01*
G02X1230970I1096J1027D01*
G37*
G36*
G01X1194159D02*
G03Y12941I292J-273D01*
G02X1191967I-1096J-1027D01*
G03Y13487I-292J273D01*
G02X1194159I1096J1027D01*
G37*
G36*
G01X1157348D02*
G03Y12941I292J-273D01*
G02X1155156I-1096J-1027D01*
G03Y13487I-292J273D01*
G02X1157348I1096J1027D01*
G37*
G36*
G01X1120536D02*
G03Y12941I292J-273D01*
G02X1118344I-1096J-1027D01*
G03Y13487I-292J273D01*
G02X1120536I1096J1027D01*
G37*
G36*
G01X939828D02*
G03Y12941I292J-273D01*
G02X937636I-1096J-1027D01*
G03Y13487I-292J273D01*
G02X939828I1096J1027D01*
G37*
G36*
G01X903017D02*
G03Y12941I292J-273D01*
G02X900825I-1096J-1027D01*
G03Y13487I-292J273D01*
G02X903017I1096J1027D01*
G37*
G36*
G01X866206D02*
G03Y12941I292J-273D01*
G02X864014I-1096J-1027D01*
G03Y13487I-292J273D01*
G02X866206I1096J1027D01*
G37*
G36*
G01X829395D02*
G03Y12941I292J-273D01*
G02X827203I-1096J-1027D01*
G03Y13487I-292J273D01*
G02X829395I1096J1027D01*
G37*
G36*
G01X792584D02*
G03Y12941I292J-273D01*
G02X790392I-1096J-1027D01*
G03Y13487I-292J273D01*
G02X792584I1096J1027D01*
G37*
G36*
G01X581362D02*
G03Y12941I292J-273D01*
G02X579170I-1096J-1027D01*
G03Y13487I-292J273D01*
G02X581362I1096J1027D01*
G37*
G36*
G01X544551D02*
G03Y12941I292J-273D01*
G02X542359I-1096J-1027D01*
G03Y13487I-292J273D01*
G02X544551I1096J1027D01*
G37*
G36*
G01X507740D02*
G03Y12941I292J-273D01*
G02X505548I-1096J-1027D01*
G03Y13487I-292J273D01*
G02X507740I1096J1027D01*
G37*
G36*
G01X470928D02*
G03Y12941I292J-273D01*
G02X468736I-1096J-1027D01*
G03Y13487I-292J273D01*
G02X470928I1096J1027D01*
G37*
G36*
G01X290220D02*
G03Y12941I292J-273D01*
G02X288028I-1096J-1027D01*
G03Y13487I-292J273D01*
G02X290220I1096J1027D01*
G37*
G36*
G01X253409D02*
G03Y12941I292J-273D01*
G02X251217I-1096J-1027D01*
G03Y13487I-292J273D01*
G02X253409I1096J1027D01*
G37*
G36*
G01X216598D02*
G03Y12941I292J-273D01*
G02X214406I-1096J-1027D01*
G03Y13487I-292J273D01*
G02X216598I1096J1027D01*
G37*
G36*
G01X179787D02*
G03Y12941I292J-273D01*
G02X177595I-1096J-1027D01*
G03Y13487I-292J273D01*
G02X179787I1096J1027D01*
G37*
G36*
G01X142976D02*
G03Y12941I292J-273D01*
G02X140784I-1096J-1027D01*
G03Y13487I-292J273D01*
G02X142976I1096J1027D01*
G37*
G36*
G01X1225870Y13273D02*
G03Y12727I292J-273D01*
G02X1223678I-1096J-1027D01*
G03Y13273I-292J273D01*
G02X1225870I1096J1027D01*
G37*
G36*
G01X1189059D02*
G03Y12727I292J-273D01*
G02X1186867I-1096J-1027D01*
G03Y13273I-292J273D01*
G02X1189059I1096J1027D01*
G37*
G36*
G01X1152248D02*
G03Y12727I292J-273D01*
G02X1150056I-1096J-1027D01*
G03Y13273I-292J273D01*
G02X1152248I1096J1027D01*
G37*
G36*
G01X1115436D02*
G03Y12727I292J-273D01*
G02X1113244I-1096J-1027D01*
G03Y13273I-292J273D01*
G02X1115436I1096J1027D01*
G37*
G36*
G01X934728D02*
G03Y12727I292J-273D01*
G02X932536I-1096J-1027D01*
G03Y13273I-292J273D01*
G02X934728I1096J1027D01*
G37*
G36*
G01X897917D02*
G03Y12727I292J-273D01*
G02X895725I-1096J-1027D01*
G03Y13273I-292J273D01*
G02X897917I1096J1027D01*
G37*
G36*
G01X861106D02*
G03Y12727I292J-273D01*
G02X858914I-1096J-1027D01*
G03Y13273I-292J273D01*
G02X861106I1096J1027D01*
G37*
G36*
G01X824295D02*
G03Y12727I292J-273D01*
G02X822103I-1096J-1027D01*
G03Y13273I-292J273D01*
G02X824295I1096J1027D01*
G37*
G36*
G01X787484D02*
G03Y12727I292J-273D01*
G02X785292I-1096J-1027D01*
G03Y13273I-292J273D01*
G02X787484I1096J1027D01*
G37*
G36*
G01X576262D02*
G03Y12727I292J-273D01*
G02X574070I-1096J-1027D01*
G03Y13273I-292J273D01*
G02X576262I1096J1027D01*
G37*
G36*
G01X539451D02*
G03Y12727I292J-273D01*
G02X537259I-1096J-1027D01*
G03Y13273I-292J273D01*
G02X539451I1096J1027D01*
G37*
G36*
G01X502640D02*
G03Y12727I292J-273D01*
G02X500448I-1096J-1027D01*
G03Y13273I-292J273D01*
G02X502640I1096J1027D01*
G37*
G36*
G01X465828D02*
G03Y12727I292J-273D01*
G02X463636I-1096J-1027D01*
G03Y13273I-292J273D01*
G02X465828I1096J1027D01*
G37*
G36*
G01X285120D02*
G03Y12727I292J-273D01*
G02X282928I-1096J-1027D01*
G03Y13273I-292J273D01*
G02X285120I1096J1027D01*
G37*
G36*
G01X248309D02*
G03Y12727I292J-273D01*
G02X246117I-1096J-1027D01*
G03Y13273I-292J273D01*
G02X248309I1096J1027D01*
G37*
G36*
G01X211498D02*
G03Y12727I292J-273D01*
G02X209306I-1096J-1027D01*
G03Y13273I-292J273D01*
G02X211498I1096J1027D01*
G37*
G36*
G01X174687D02*
G03Y12727I292J-273D01*
G02X172495I-1096J-1027D01*
G03Y13273I-292J273D01*
G02X174687I1096J1027D01*
G37*
G36*
G01X137876D02*
G03Y12727I292J-273D01*
G02X135684I-1096J-1027D01*
G03Y13273I-292J273D01*
G02X137876I1096J1027D01*
G37*
G36*
G01X1484135Y10052D02*
X1479135D01*
G02Y13074I0J1511D01*
G01X1484136D01*
G02X1485646Y11573I-1J-1511D01*
G01Y11478D01*
X1485637Y11394D01*
G02X1484135Y10052I-1502J169D01*
G37*
G36*
G01X1465237D02*
X1460237D01*
G02Y13074I0J1511D01*
G01X1465238D01*
G02X1466748Y11573I-1J-1511D01*
G01Y11478D01*
X1466739Y11394D01*
G02X1465237Y10052I-1502J169D01*
G37*
G36*
G01X1441340Y13074D02*
X1446341D01*
G02X1447852Y11573I0J-1512D01*
G01Y11478D01*
X1447842Y11394D01*
G02X1446340Y10052I-1502J169D01*
G01X1441340D01*
G02Y13074I1J1511D01*
G37*
G36*
G01X1427442Y10052D02*
X1422442D01*
G02Y13074I0J1511D01*
G01X1427443D01*
G02X1428954Y11573I0J-1512D01*
G01Y11478D01*
X1428944Y11394D01*
G02X1427442Y10052I-1502J169D01*
G37*
G36*
G01X1728678Y9870D02*
X1723678D01*
G02Y12892I0J1511D01*
G01X1728679D01*
G02X1730190Y11391I0J-1512D01*
G01Y11296D01*
X1730180Y11212D01*
G02X1728678Y9870I-1502J169D01*
G37*
G36*
G01X1681428D02*
X1676428D01*
G02Y12892I0J1511D01*
G01X1681429D01*
G02X1682940Y11391I0J-1512D01*
G01Y11296D01*
X1682930Y11212D01*
G02X1681428Y9870I-1502J169D01*
G37*
G36*
G01X1605898Y9844D02*
X1600898D01*
G02Y12866I0J1511D01*
G01X1605899D01*
G02X1607410Y11365I0J-1512D01*
G01Y11270D01*
X1607400Y11186D01*
G02X1605898Y9844I-1502J169D01*
G37*
G36*
G01X1586998D02*
X1581998D01*
G02Y12866I0J1511D01*
G01X1586999D01*
G02X1588510Y11365I0J-1512D01*
G01Y11270D01*
X1588500Y11186D01*
G02X1586998Y9844I-1502J169D01*
G37*
G36*
G01X1700200Y9806D02*
X1695200D01*
G02Y12828I0J1511D01*
G01X1700201D01*
G02X1701712Y11327I0J-1512D01*
G01Y11232D01*
X1701702Y11148D01*
G02X1700200Y9806I-1502J170D01*
G37*
G36*
G01X1709771Y9750D02*
X1704771D01*
G02Y12772I0J1511D01*
G01X1709772D01*
G02X1711282Y11271I-1J-1511D01*
G01Y11176D01*
X1711273Y11092D01*
G02X1709771Y9750I-1502J169D01*
G37*
G36*
G01X1719297Y9668D02*
X1714297D01*
G02Y12692I0J1512D01*
G01X1719298D01*
G02X1720808Y11190I-1J-1512D01*
G01Y11095D01*
X1720799Y11011D01*
G02X1719297Y9668I-1502J169D01*
G37*
G36*
G01X1643865Y9594D02*
X1638865D01*
G02Y12616I0J1511D01*
G01X1643866D01*
G02X1645376Y11115I-1J-1511D01*
G01Y11020D01*
X1645367Y10936D01*
G02X1643865Y9594I-1502J169D01*
G37*
G36*
G01X1690948Y9214D02*
X1685948D01*
G02Y12236I0J1511D01*
G01X1690949D01*
G02X1692460Y10735I0J-1512D01*
G01Y10640D01*
X1692450Y10556D01*
G02X1690948Y9214I-1502J169D01*
G37*
G36*
G01X1302990Y9175D02*
G03X1302368I-311J-252D01*
G02X1300259Y11020I-1089J883D01*
G03X1300242Y11587I-291J275D01*
G02X1300225Y13618I958J1024D01*
G03Y14192I-278J287D01*
G02X1302289Y16083I976J1007D01*
G03X1302911I311J252D01*
G02X1305089I1089J-883D01*
G03X1305711I311J252D01*
G02X1307775Y14192I1088J-884D01*
G03Y13618I278J-287D01*
G02X1307820Y11648I-975J-1008D01*
G03X1307837Y11081I291J-275D01*
G02X1305790Y9175I-957J-1024D01*
G03X1305168I-311J-252D01*
G02X1302990I-1089J883D01*
G37*
G36*
G01X1663884Y10164D02*
Y10069D01*
X1663875Y9985D01*
G02X1662342Y8643I-1502J169D01*
G01X1657338Y8747D01*
G02X1657400Y11769I31J1511D01*
G01X1662403Y11665D01*
G02X1663884Y10164I-30J-1511D01*
G37*
G36*
G01X1401627Y8990D02*
G03X1401073I-277J-288D01*
G02Y11010I-973J1010D01*
G03X1401627I277J288D01*
G02X1403573I973J-1010D01*
G03X1404127I277J288D01*
G02Y8990I973J-1010D01*
G03X1403573I-277J-288D01*
G02X1401627I-973J1010D01*
G37*
G36*
G01X665011Y9117D02*
G03X664389I-311J-252D01*
G02Y10883I-1089J883D01*
G03X665011I311J252D01*
G02Y9117I1089J-883D01*
G37*
G36*
G01X82642Y10684D02*
G03X82629Y10122I278J-288D01*
G02X80364Y8516I-1019J-963D01*
G03X79806Y8677I-355J-184D01*
G02X78085Y10857I-710J1209D01*
G03X78089Y11406I-289J277D01*
G02X78229Y13446I1027J954D01*
G03X78285Y14009I-253J309D01*
G02X80652Y15467I1087J886D01*
G03X81238Y15297I365J164D01*
G02X82894Y13038I775J-1168D01*
G03X82817Y12497I251J-312D01*
G02X82642Y10684I-1148J-804D01*
G37*
G36*
G01X1259473Y10130D02*
G03X1260036Y10118I288J278D01*
G02X1259991Y8127I964J-1018D01*
G03X1259428Y8139I-288J-278D01*
G02X1259473Y10130I-964J1018D01*
G37*
G36*
G01X1754065Y10273D02*
G03X1754640Y10183I330J226D01*
G02X1754343Y8284I860J-1107D01*
G03X1753768Y8374I-330J-226D01*
G02X1754065Y10273I-860J1107D01*
G37*
G36*
G01X1591848Y12918D02*
X1595849D01*
G02X1597360Y11416I-1J-1512D01*
G01Y11321D01*
X1597350Y11237D01*
G02X1595848Y9894I-1502J169D01*
G01X1593957D01*
G03X1593623Y9274I0J-400D01*
G02X1591378Y9402I-1170J-772D01*
G03X1591234Y10025I-306J257D01*
G02X1591848Y12918I614J1381D01*
G37*
G36*
G01X1436025Y6244D02*
X1431025D01*
G02Y9268I0J1512D01*
G01X1436026D01*
G02X1437536Y7766I-1J-1512D01*
G01Y7671D01*
X1437527Y7587D01*
G02X1436025Y6244I-1502J169D01*
G37*
G36*
G01X1493770Y5398D02*
X1488770D01*
G02Y8420I0J1511D01*
G01X1493771D01*
G02X1495282Y6919I0J-1512D01*
G01Y6824D01*
X1495272Y6740D01*
G02X1493770Y5398I-1502J169D01*
G37*
G36*
G01X1634148Y5314D02*
X1629148D01*
G02Y8336I0J1511D01*
G01X1634149D01*
G02X1635660Y6835I0J-1512D01*
G01Y6740D01*
X1635650Y6656D01*
G02X1634148Y5314I-1502J169D01*
G37*
G36*
G01X1653748Y4814D02*
X1648748D01*
G02Y7836I0J1511D01*
G01X1653749D01*
G02X1655260Y6335I0J-1512D01*
G01Y6240D01*
X1655250Y6156D01*
G02X1653748Y4814I-1502J169D01*
G37*
G36*
G01X1671979Y4724D02*
X1666979D01*
G02Y7748I0J1512D01*
G01X1671979D01*
G02X1673490Y6246I-1J-1512D01*
G01Y6151D01*
X1673481Y6067D01*
G02X1671979Y4724I-1502J168D01*
G37*
G36*
G01X1368378Y4805D02*
G03X1367800I-289J-277D01*
G02Y6747I-1011J971D01*
G03X1368378I289J277D01*
G02Y4805I1011J-971D01*
G37*
G36*
G01X1474388Y4078D02*
X1469388D01*
G02Y7100I0J1511D01*
G01X1474389D01*
G02X1475900Y5599I0J-1512D01*
G01Y5504D01*
X1475890Y5420D01*
G02X1474388Y4078I-1502J169D01*
G37*
G36*
G01X1454991D02*
X1449991D01*
G02Y7100I0J1511D01*
G01X1454992D01*
G02X1456502Y5599I-1J-1511D01*
G01Y5504D01*
X1456493Y5420D01*
G02X1454991Y4078I-1502J169D01*
G37*
G36*
G01X1614833Y3914D02*
X1609833D01*
G02Y6936I0J1511D01*
G01X1614834D01*
G02X1616344Y5435I-1J-1511D01*
G01Y5340D01*
X1616335Y5256D01*
G02X1614833Y3914I-1502J169D01*
G37*
G36*
G01X665442Y3406D02*
G03X664944Y3216I-143J-374D01*
G02X664199Y5171I-1245J645D01*
G03X664697Y5361I143J374D01*
G02X665442Y3406I1245J-645D01*
G37*
G36*
G01X115022Y5064D02*
G03X115000Y4483I263J-301D01*
G02X113078Y4556I-1000J-983D01*
G03X113100Y5137I-263J301D01*
G02X115022Y5064I1000J983D01*
G37*
G36*
G01X1381205Y4584D02*
G03X1381223Y3999I282J-284D01*
G02X1379314Y3941I-923J-1055D01*
G03X1379296Y4526I-282J284D01*
G02X1381205Y4584I923J1055D01*
G37*
G36*
G01X1328965Y4380D02*
G03X1329273Y3898I389J-91D01*
G02X1327952Y1579I-286J-1373D01*
G03X1327378Y1596I-295J-270D01*
G02X1325311Y1717I-978J1004D01*
G03X1324689I-311J-252D01*
G02X1322511I-1089J883D01*
G03X1321889I-311J-252D01*
G02X1319672Y1768I-1089J883D01*
G03X1319028I-322J-238D01*
G02X1316783Y1753I-1128J832D01*
G03X1316140Y1745I-319J-242D01*
G02X1313907Y1694I-1136J822D01*
G03X1313306Y1724I-314J-248D01*
G02X1311211Y1817I-1006J976D01*
G03X1310589I-311J-252D01*
G02X1308411I-1089J883D01*
G03X1307789I-311J-252D01*
G02X1305611I-1089J883D01*
G03X1304989I-311J-252D01*
G02X1302811I-1089J883D01*
G03X1302189I-311J-252D01*
G02X1300664Y4033I-1089J883D01*
G03X1300931Y4499I-124J380D01*
G02X1303389Y5683I1369J301D01*
G03X1304011I311J252D01*
G02X1306189I1089J-883D01*
G03X1306811I311J252D01*
G02X1308989I1089J-883D01*
G03X1309611I311J252D01*
G02X1311789I1089J-883D01*
G03X1312411I311J252D01*
G02X1314621Y5642I1089J-883D01*
G03X1315242Y5620I319J241D01*
G02X1317428Y5532I1058J-920D01*
G03X1318072I322J238D01*
G02X1320289Y5583I1128J-832D01*
G03X1320911I311J252D01*
G02X1323089I1089J-883D01*
G03X1323711I311J252D01*
G02X1325889I1089J-883D01*
G03X1326511I311J252D01*
G02X1328965Y4380I1089J-883D01*
G37*
G36*
G01X1825803Y2785D02*
G03X1825972Y2243I354J-187D01*
G02X1824085Y1656I-648J-1243D01*
G03X1823916Y2198I-354J187D01*
G02X1825803Y2785I648J1243D01*
G37*
G36*
G01X752985Y1288D02*
G03X753584Y1266I309J254D01*
G02X753515Y-588I1016J-966D01*
G03X752916Y-566I-309J-254D01*
G02X752985Y1288I-1016J966D01*
G37*
G36*
G01X1600129Y-1610D02*
G03X1599575I-277J-288D01*
G02Y410I-973J1010D01*
G03X1600129I277J288D01*
G02Y-1610I973J-1010D01*
G37*
G36*
G01X63074Y-533D02*
G03X63194Y-1141I308J-255D01*
G02X61456Y-1484I-659J-1238D01*
G03X61336Y-876I-308J255D01*
G02X63074Y-533I659J1238D01*
G37*
G36*
G01X1381410Y-3782D02*
G03X1381885Y-4168I400J7D01*
G02X1380749Y-5568I266J-1377D01*
G03X1380274Y-5182I-400J-7D01*
G02X1381410Y-3782I-266J1377D01*
G37*
G36*
G01X718771Y-5838D02*
G03X718316Y-6193I-57J-396D01*
G02X717125Y-4661I-1395J145D01*
G03X717580Y-4306I57J396D01*
G02X718771Y-5838I1395J-145D01*
G37*
G36*
G01X1225862Y-5436D02*
G03X1225868Y-5993I290J-275D01*
G02X1223712Y-6015I-1067J-1057D01*
G03X1223706Y-5458I-290J275D01*
G02X1225862Y-5436I1067J1057D01*
G37*
G36*
G01X1189051D02*
G03X1189057Y-5993I290J-275D01*
G02X1186901Y-6015I-1067J-1057D01*
G03X1186895Y-5458I-290J275D01*
G02X1189051Y-5436I1067J1057D01*
G37*
G36*
G01X1152240D02*
G03X1152246Y-5993I290J-275D01*
G02X1150090Y-6015I-1067J-1057D01*
G03X1150084Y-5458I-290J275D01*
G02X1152240Y-5436I1067J1057D01*
G37*
G36*
G01X1115428D02*
G03X1115434Y-5993I290J-275D01*
G02X1113278Y-6015I-1067J-1057D01*
G03X1113272Y-5458I-290J275D01*
G02X1115428Y-5436I1067J1057D01*
G37*
G36*
G01X934720D02*
G03X934726Y-5993I290J-275D01*
G02X932570Y-6015I-1067J-1057D01*
G03X932564Y-5458I-290J275D01*
G02X934720Y-5436I1067J1057D01*
G37*
G36*
G01X897909D02*
G03X897915Y-5993I290J-275D01*
G02X895759Y-6015I-1067J-1057D01*
G03X895753Y-5458I-290J275D01*
G02X897909Y-5436I1067J1057D01*
G37*
G36*
G01X861098D02*
G03X861104Y-5993I290J-275D01*
G02X858948Y-6015I-1067J-1057D01*
G03X858942Y-5458I-290J275D01*
G02X861098Y-5436I1067J1057D01*
G37*
G36*
G01X824287D02*
G03X824293Y-5993I290J-275D01*
G02X822137Y-6015I-1067J-1057D01*
G03X822131Y-5458I-290J275D01*
G02X824287Y-5436I1067J1057D01*
G37*
G36*
G01X787476D02*
G03X787482Y-5993I290J-275D01*
G02X785326Y-6015I-1067J-1057D01*
G03X785320Y-5458I-290J275D01*
G02X787476Y-5436I1067J1057D01*
G37*
G36*
G01X576254D02*
G03X576260Y-5993I290J-275D01*
G02X574104Y-6015I-1067J-1057D01*
G03X574098Y-5458I-290J275D01*
G02X576254Y-5436I1067J1057D01*
G37*
G36*
G01X539443D02*
G03X539449Y-5993I290J-275D01*
G02X537293Y-6015I-1067J-1057D01*
G03X537287Y-5458I-290J275D01*
G02X539443Y-5436I1067J1057D01*
G37*
G36*
G01X502632D02*
G03X502638Y-5993I290J-275D01*
G02X500482Y-6015I-1067J-1057D01*
G03X500476Y-5458I-290J275D01*
G02X502632Y-5436I1067J1057D01*
G37*
G36*
G01X465820D02*
G03X465826Y-5993I290J-275D01*
G02X463670Y-6015I-1067J-1057D01*
G03X463664Y-5458I-290J275D01*
G02X465820Y-5436I1067J1057D01*
G37*
G36*
G01X285112D02*
G03X285118Y-5993I290J-275D01*
G02X282962Y-6015I-1067J-1057D01*
G03X282956Y-5458I-290J275D01*
G02X285112Y-5436I1067J1057D01*
G37*
G36*
G01X248301D02*
G03X248307Y-5993I290J-275D01*
G02X246151Y-6015I-1067J-1057D01*
G03X246145Y-5458I-290J275D01*
G02X248301Y-5436I1067J1057D01*
G37*
G36*
G01X211490D02*
G03X211496Y-5993I290J-275D01*
G02X209340Y-6015I-1067J-1057D01*
G03X209334Y-5458I-290J275D01*
G02X211490Y-5436I1067J1057D01*
G37*
G36*
G01X174679D02*
G03X174685Y-5993I290J-275D01*
G02X172529Y-6015I-1067J-1057D01*
G03X172523Y-5458I-290J275D01*
G02X174679Y-5436I1067J1057D01*
G37*
G36*
G01X137868D02*
G03X137874Y-5993I290J-275D01*
G02X135718Y-6015I-1067J-1057D01*
G03X135712Y-5458I-290J275D01*
G02X137868Y-5436I1067J1057D01*
G37*
G36*
G01X1230967Y-5681D02*
G03Y-6230I291J-274D01*
G02X1228781I-1093J-1030D01*
G03Y-5681I-291J274D01*
G02X1230967I1093J1030D01*
G37*
G36*
G01X1194156D02*
G03Y-6230I291J-274D01*
G02X1191970I-1093J-1030D01*
G03Y-5681I-291J274D01*
G02X1194156I1093J1030D01*
G37*
G36*
G01X1157345D02*
G03Y-6230I291J-274D01*
G02X1155159I-1093J-1030D01*
G03Y-5681I-291J274D01*
G02X1157345I1093J1030D01*
G37*
G36*
G01X1120533D02*
G03Y-6230I291J-274D01*
G02X1118347I-1093J-1030D01*
G03Y-5681I-291J274D01*
G02X1120533I1093J1030D01*
G37*
G36*
G01X939825D02*
G03Y-6230I291J-274D01*
G02X937639I-1093J-1030D01*
G03Y-5681I-291J274D01*
G02X939825I1093J1030D01*
G37*
G36*
G01X903014D02*
G03Y-6230I291J-274D01*
G02X900828I-1093J-1030D01*
G03Y-5681I-291J274D01*
G02X903014I1093J1030D01*
G37*
G36*
G01X866203D02*
G03Y-6230I291J-274D01*
G02X864017I-1093J-1030D01*
G03Y-5681I-291J274D01*
G02X866203I1093J1030D01*
G37*
G36*
G01X829392D02*
G03Y-6230I291J-274D01*
G02X827206I-1093J-1030D01*
G03Y-5681I-291J274D01*
G02X829392I1093J1030D01*
G37*
G36*
G01X792581D02*
G03Y-6230I291J-274D01*
G02X790395I-1093J-1030D01*
G03Y-5681I-291J274D01*
G02X792581I1093J1030D01*
G37*
G36*
G01X581359D02*
G03Y-6230I291J-274D01*
G02X579173I-1093J-1030D01*
G03Y-5681I-291J274D01*
G02X581359I1093J1030D01*
G37*
G36*
G01X544548D02*
G03Y-6230I291J-274D01*
G02X542362I-1093J-1030D01*
G03Y-5681I-291J274D01*
G02X544548I1093J1030D01*
G37*
G36*
G01X507737D02*
G03Y-6230I291J-274D01*
G02X505551I-1093J-1030D01*
G03Y-5681I-291J274D01*
G02X507737I1093J1030D01*
G37*
G36*
G01X470925D02*
G03Y-6230I291J-274D01*
G02X468739I-1093J-1030D01*
G03Y-5681I-291J274D01*
G02X470925I1093J1030D01*
G37*
G36*
G01X290217D02*
G03Y-6230I291J-274D01*
G02X288031I-1093J-1030D01*
G03Y-5681I-291J274D01*
G02X290217I1093J1030D01*
G37*
G36*
G01X253406D02*
G03Y-6230I291J-274D01*
G02X251220I-1093J-1030D01*
G03Y-5681I-291J274D01*
G02X253406I1093J1030D01*
G37*
G36*
G01X216595D02*
G03Y-6230I291J-274D01*
G02X214409I-1093J-1030D01*
G03Y-5681I-291J274D01*
G02X216595I1093J1030D01*
G37*
G36*
G01X179784D02*
G03Y-6230I291J-274D01*
G02X177598I-1093J-1030D01*
G03Y-5681I-291J274D01*
G02X179784I1093J1030D01*
G37*
G36*
G01X142973D02*
G03Y-6230I291J-274D01*
G02X140787I-1093J-1030D01*
G03Y-5681I-291J274D01*
G02X142973I1093J1030D01*
G37*
G36*
G01X647971Y-10511D02*
G03Y-11089I277J-289D01*
G02X646029I-971J-1011D01*
G03Y-10511I-277J289D01*
G02X646208Y-8343I971J1011D01*
G03X646297Y-7766I-226J330D01*
G02X648192Y-8057I1103J866D01*
G03X648103Y-8634I226J-330D01*
G02X647971Y-10511I-1103J-866D01*
G37*
G36*
G01X64936Y-12238D02*
G03X65464Y-12420I357J180D01*
G02X64808Y-14317I597J-1268D01*
G03X64280Y-14135I-357J-180D01*
G02X64936Y-12238I-597J1268D01*
G37*
G36*
G01X730372Y-16258D02*
G03X729818Y-16331I-240J-320D01*
G02X727466Y-16100I-1102J866D01*
G03X726936Y-15921I-356J-181D01*
G02X725354Y-15668I-609J1263D01*
G03X724800I-277J-288D01*
G02Y-13648I-973J1010D01*
G03X725354I277J288D01*
G02X726891Y-13374I973J-1010D01*
G03X727448Y-12954I161J366D01*
G02X729716Y-13856I1389J191D01*
G03X729689Y-14455I250J-311D01*
G02X729693Y-14460I-1084J-871D01*
G03X730004Y-14418I139J144D01*
G02X730372Y-16258I1206J-716D01*
G37*
G36*
G01X1585527Y-17110D02*
G03X1584973I-277J-288D01*
G02Y-15090I-973J1010D01*
G03X1585527I277J288D01*
G02Y-17110I973J-1010D01*
G37*
G36*
G01X41289Y-16225D02*
G03X41102Y-15669I-351J191D01*
G02X42908Y-15061I575J1279D01*
G03X43095Y-15617I351J-191D01*
G02X41289Y-16225I-575J-1279D01*
G37*
G36*
G01X1375736Y-17802D02*
G03X1375155Y-17824I-280J-285D01*
G02X1373099Y-17881I-1054J924D01*
G03X1372569Y-17844I-286J-280D01*
G02X1370533Y-15654I-916J1190D01*
G03X1370522Y-15110I-299J266D01*
G02X1370449Y-13110I1083J1041D01*
G03X1370447Y-12598I-308J255D01*
G02X1370460Y-10653I1151J965D01*
G03X1370467Y-10139I-303J261D01*
G02X1372770Y-10171I1165J948D01*
G03X1372763Y-10685I303J-261D01*
G02X1372754Y-12592I-1165J-948D01*
G03X1372756Y-13104I308J-255D01*
G02X1372725Y-15069I-1151J-965D01*
G03X1372736Y-15613I299J-266D01*
G02X1372788Y-15670I-1083J-1041D01*
G03X1373314Y-15739I302J262D01*
G02X1375083Y-15900I786J-1161D01*
G03X1375664Y-15878I280J285D01*
G02X1375736Y-17802I1055J-924D01*
G37*
G36*
G01X1316783Y-17747D02*
G03X1316140Y-17755I-319J-242D01*
G02X1313907Y-17806I-1136J822D01*
G03X1313306Y-17776I-314J-248D01*
G02X1311211Y-17683I-1006J976D01*
G03X1310589I-311J-252D01*
G02X1308411I-1089J883D01*
G03X1307789I-311J-252D01*
G02X1306264Y-15467I-1089J883D01*
G03X1306531Y-15001I-124J380D01*
G02X1308989Y-13817I1369J301D01*
G03X1309611I311J252D01*
G02X1311789I1089J-883D01*
G03X1312411I311J252D01*
G02X1314621Y-13858I1089J-883D01*
G03X1315242Y-13880I319J241D01*
G02X1317428Y-13968I1058J-920D01*
G03X1318072I322J238D01*
G02X1320289Y-13917I1128J-832D01*
G03X1320911I311J252D01*
G02X1321879Y-13403I1089J-883D01*
G03X1322234Y-12915I-35J398D01*
G02X1324577Y-11595I1366J315D01*
G03X1325110Y-11617I279J287D01*
G02X1327089Y-11817I890J-1083D01*
G03X1327711I311J252D01*
G02X1329236Y-14033I1089J-883D01*
G03X1328969Y-14499I124J-380D01*
G02X1328036Y-16133I-1369J-302D01*
G03X1327769Y-16599I124J-380D01*
G02X1325311Y-17783I-1369J-301D01*
G03X1324689I-311J-252D01*
G02X1322511I-1089J883D01*
G03X1321889I-311J-252D01*
G02X1319672Y-17732I-1089J883D01*
G03X1319028I-322J-238D01*
G02X1316783Y-17747I-1128J832D01*
G37*
G36*
G01X18562Y-92D02*
X18560Y-189D01*
G02Y199I-18560J194D01*
G01X18561Y105D01*
X18562Y10D01*
Y-92D01*
G37*
G36*
G01X1606531Y-18356D02*
G03X1605977I-277J-288D01*
G02Y-16336I-973J1010D01*
G03X1606531I277J288D01*
G02X1608477I973J-1010D01*
G03X1609031I277J288D01*
G02Y-18356I973J-1010D01*
G03X1608477I-277J-288D01*
G02X1606531I-973J1010D01*
G37*
G36*
G01X1596531D02*
G03X1595977I-277J-288D01*
G02Y-16336I-973J1010D01*
G03X1596531I277J288D01*
G02X1598477I973J-1010D01*
G03X1599031I277J288D01*
G02Y-18356I973J-1010D01*
G03X1598477I-277J-288D01*
G02X1596531I-973J1010D01*
G37*
G36*
G01X661185Y-16750D02*
G03X661784Y-16839I338J214D01*
G02X661515Y-18650I916J-1062D01*
G03X660916Y-18561I-338J-214D01*
G02X661185Y-16750I-916J1062D01*
G37*
G36*
G01X1300366Y-16666D02*
G03X1300430Y-17281I284J-281D01*
G02X1298511Y-17399I-881J-1338D01*
G03X1298500Y-16780I-259J305D01*
G02X1300366Y-16666I869J1100D01*
G37*
G36*
G01X21111Y-18129D02*
G03X21683Y-18241I339J213D01*
G02X21312Y-20127I816J-1140D01*
G03X20740Y-20015I-339J-213D01*
G02X21111Y-18129I-816J1140D01*
G37*
G36*
G01X709720Y-17986D02*
G03X710115Y-18437I397J-51D01*
G02X708717Y-19659I-8J-1402D01*
G03X708322Y-19208I-397J51D01*
G02X709720Y-17986I8J1402D01*
G37*
G36*
G01X1902168Y-18425D02*
G02X1901892Y-20014I992J-991D01*
G03X1901248Y-19902I-361J-171D01*
G02X1901524Y-18313I-992J991D01*
G03X1902168Y-18425I361J171D01*
G37*
G36*
G01X714334Y-17027D02*
G02X712514Y-17832I-510J-1306D01*
G03X712286Y-17317I-373J143D01*
G02X711398Y-16115I510J1306D01*
G03X710836Y-15780I-399J-30D01*
G02X709291Y-13490I-573J1280D01*
G03X709305Y-12928I-277J288D01*
G02X711299Y-12978I1022J960D01*
G03X711285Y-13540I277J-288D01*
G02X711661Y-14396I-1022J-960D01*
G03X712223Y-14731I399J30D01*
G02X714106Y-16512I573J-1280D01*
G03X714334Y-17027I373J-143D01*
G37*
G36*
G01X1674935Y-17561D02*
G02X1674904Y-16078I-1435J712D01*
G03X1675602Y-16084I351J193D01*
G02X1675632Y-17526I1217J-696D01*
G03X1674935Y-17561I-339J-213D01*
G37*
G36*
G01X1280343Y-15495D02*
G02X1280321Y-14060I-1443J696D01*
G03X1281025Y-14068I354J186D01*
G02X1283184Y-13700I1227J-679D01*
G03X1283763Y-13650I266J299D01*
G02X1283927Y-15571I1096J-874D01*
G03X1283348Y-15621I-266J-299D01*
G02X1281047Y-15464I-1096J874D01*
G03X1280343Y-15495I-344J-205D01*
G37*
G36*
G01X1498611Y-11287D02*
G02X1497445Y-12317I189J-1389D01*
G03X1496979Y-11822I-387J103D01*
G02X1498178Y-10763I-319J1570D01*
G03X1498611Y-11287I379J-127D01*
G37*
G36*
G01X342790Y215115D02*
G03X342352Y215513I-400J0D01*
G02Y218305I-134J1396D01*
G03X342790Y218703I38J398D01*
G01Y222915D01*
G03X342352Y223313I-400J0D01*
G02Y226105I-134J1396D01*
G03X342790Y226503I38J398D01*
G01Y226816D01*
G03X342352Y227214I-400J0D01*
G02Y230006I-134J1396D01*
G03X342790Y230404I38J398D01*
G01Y230715D01*
G03X342352Y231113I-400J0D01*
G02Y233905I-134J1396D01*
G03X342790Y234303I38J398D01*
G01Y234615D01*
G03X342352Y235013I-400J0D01*
G02Y237805I-134J1396D01*
G03X342790Y238203I38J398D01*
G01Y238515D01*
G03X342352Y238913I-400J0D01*
G02Y241705I-134J1396D01*
G03X342790Y242103I38J398D01*
G01Y242415D01*
G03X342352Y242813I-400J0D01*
G02Y245605I-134J1396D01*
G03X342790Y246003I38J398D01*
G01Y246315D01*
G03X342352Y246713I-400J0D01*
G02X342845Y249363I-134J1396D01*
G01X342974Y249298D01*
X343394Y249718D01*
G02X344197Y250116I991J-991D01*
G02X346788Y250802I1401J-56D01*
G01X347722D01*
G02X347731Y250801I-149J-1386D01*
G03X347888Y251127I1J200D01*
G02X350068I1090J882D01*
G03X350225Y250801I156J-126D01*
G02X350234Y250802I158J-1385D01*
G01X351167D01*
G02X353547I1190J-742D01*
G01X354481D01*
G02X354490Y250801I-149J-1386D01*
G03X354647Y251127I1J200D01*
G02X356827I1090J882D01*
G03X356984Y250801I156J-126D01*
G02X356993Y250802I158J-1385D01*
G01X357927D01*
G02X360307I1190J-742D01*
G01X361241D01*
G02X361250Y250801I-149J-1386D01*
G03X361407Y251127I1J200D01*
G02X363587I1090J882D01*
G03X363742Y250802I156J-125D01*
G01X363852D01*
X363952Y250702D01*
X364630D01*
G02X367124I1247J-642D01*
G01X367906D01*
G02X368196Y250671I-3J-1402D01*
G01X368216Y250666D01*
X370587D01*
X371834Y249420D01*
X373160D01*
Y251337D01*
X378178Y256354D01*
G03X377977Y257028I-283J283D01*
G02X379639Y258690I290J1372D01*
G03X380313Y258489I391J82D01*
G01X389395Y267572D01*
X417885D01*
X417887Y267570D01*
X427263D01*
X428927Y265905D01*
G02X429296Y263478I854J-1112D01*
G03X428769Y263196I-138J-375D01*
G01X427371Y261798D01*
X424202D01*
Y258075D01*
X422532Y256405D01*
G02X420685Y254331I-1068J-908D01*
G01X420549Y254422D01*
X419473Y253347D01*
X419462Y253286D01*
G02X418344Y252168I-1378J260D01*
G01X418283Y252157D01*
X412272Y246146D01*
Y201064D01*
X417386Y195951D01*
Y142789D01*
X449294Y110881D01*
Y90572D01*
X448541Y90271D01*
G03Y89529I151J-371D01*
G01X449294Y89228D01*
Y85952D01*
X448480Y85675D01*
G03Y84917I130J-379D01*
G01X449294Y84640D01*
Y74245D01*
X448473Y73969D01*
X448472D01*
G03X448339Y73284I127J-380D01*
G02X448379Y71191I-911J-1064D01*
G03X448340Y70644I272J-294D01*
G03X448403Y70581I313J250D01*
G02X448390Y68413I-895J-1079D01*
G03X448226Y68071I236J-324D01*
G03X448493Y67712I400J19D01*
G01X449294Y67429D01*
Y55519D01*
X448779Y55233D01*
G03Y54533I194J-350D01*
G01X449294Y54247D01*
Y51623D01*
X448393Y51388D01*
X448392D01*
G03Y50612I100J-388D01*
G01X448393D01*
X449294Y50377D01*
Y47602D01*
X448410Y47361D01*
G03Y46589I107J-386D01*
G01X449294Y46348D01*
Y36351D01*
X448334Y36153D01*
X448333D01*
G03X448097Y35515I81J-392D01*
G03X448244Y35398I316J246D01*
G02X448644Y33136I-590J-1271D01*
G01Y33135D01*
X447594Y32085D01*
Y27415D01*
X449294Y25715D01*
Y19585D01*
X447394Y17685D01*
Y16776D01*
X447292D01*
G03X447130Y16460I0J-200D01*
G02X447394Y15642I-1138J-819D01*
G01Y12849D01*
G03X447889Y12461I400J0D01*
G02X448829Y9834I338J-1361D01*
G03X448718Y9190I172J-361D01*
G01X449294Y8615D01*
Y-5223D01*
X445873Y-8643D01*
X445999Y-8784D01*
G02X443878Y-10905I-1119J-1002D01*
G01X443737Y-10779D01*
X440685Y-13832D01*
X402025D01*
X399131Y-10938D01*
X398991Y-11055D01*
G02X396629Y-9356I-962J1154D01*
G03X396257Y-8812I-373J144D01*
G01X395547D01*
X394919Y-9439D01*
X394292Y-9312D01*
X394280Y-9310D01*
G03X393824Y-9541I-89J-390D01*
G01X393821Y-9549D01*
X393506Y-10242D01*
X392148D01*
G02X391513Y-10089I2J1402D01*
G03X391252Y-10163I-90J-179D01*
G02X385103Y-10132I-3065J1891D01*
G03X384843Y-10056I-171J-103D01*
G02X384221Y-10202I-623J1256D01*
G01X376042D01*
G03X375678Y-10767I0J-400D01*
G02X373049Y-10976I-1277J-579D01*
G03X372724Y-10475I-386J106D01*
G02X372513Y-10425I217J1385D01*
G02X370817Y-11131I-1255J625D01*
G02X369597Y-11844I-1221J688D01*
G01X366350D01*
G02X365152Y-11169I1J1402D01*
G02X363140Y-10261I-587J1383D01*
G02X362643I-249J1379D01*
G02X360631Y-11169I-1425J475D01*
G02X359433Y-11844I-1199J727D01*
G01X353002D01*
G02X351853Y-11243I1J1401D01*
G02X350505I-674J1342D01*
G02X349356Y-11844I-1150J800D01*
G01X346271D01*
G02X345073Y-11169I1J1402D01*
G02X343899I-587J1383D01*
G02X342701Y-11844I-1199J727D01*
G01X332885D01*
G02X331687Y-11169I1J1402D01*
G02X330513I-587J1383D01*
G02X329315Y-11844I-1199J727D01*
G01X326230D01*
G02X325081Y-11243I1J1401D01*
G02X323733I-674J1342D01*
G02X322584Y-11844I-1150J800D01*
G01X308836D01*
X308306Y-11315D01*
X306872Y-9883D01*
Y-8978D01*
G02X307144Y-8149I1402J-1D01*
G02Y-6211I1013J969D01*
G02X306872Y-5382I1130J830D01*
G01Y-2466D01*
X307773Y-2231D01*
X307775D01*
G03X308064Y-1940I-100J388D01*
G03X307866Y-1491I-389J97D01*
G01X307340Y-1207D01*
Y8664D01*
X307865Y8948D01*
G03Y9652I-190J352D01*
G01X307340Y9936D01*
Y12535D01*
X308129Y12824D01*
X308130D01*
G03X308021Y13599I-138J376D01*
G03X307808Y13556I-30J-399D01*
G01X307028Y13148D01*
X305490Y14685D01*
Y15491D01*
G02X306304Y16763I1402J-1D01*
G02Y17351I1371J294D01*
G02X305490Y18623I588J1273D01*
G01Y26915D01*
X306300Y27724D01*
X306286Y27823D01*
G02X307163Y29319I1389J191D01*
G01X307290Y29369D01*
Y31477D01*
X308191Y31712D01*
X308192D01*
G03Y32488I-100J388D01*
G01X308191D01*
X307290Y32723D01*
Y35322D01*
X307851Y35597D01*
G03Y36317I-176J360D01*
G01X307290Y36592D01*
Y50062D01*
X308065Y50345D01*
X308077Y50349D01*
G03X308084Y51106I-127J380D01*
G01X308083Y51107D01*
X307828Y51198D01*
X306740Y52285D01*
Y53812D01*
G02X307020Y56096I935J1045D01*
G02X307076Y56997I1352J368D01*
G01X307090Y57033D01*
Y66678D01*
G02X307778Y69196I838J1124D01*
G02X308242Y70087I1393J-159D01*
G03X308062Y70794I-250J313D01*
G01X308055Y70795D01*
X307090Y70981D01*
Y73110D01*
X307767Y73440D01*
G03X307849Y74107I-175J360D01*
G01X307490Y74407D01*
Y86730D01*
X308277Y87009D01*
X308289Y87013D01*
G03X308297Y87772I-123J381D01*
G01X308296Y87773D01*
X307490Y88055D01*
Y90513D01*
X307469Y90555D01*
G02X307322Y91300I1250J634D01*
G02X306740Y93702I353J1357D01*
G01Y99615D01*
X308012Y100886D01*
Y105796D01*
X337882Y135667D01*
Y201357D01*
X338051Y201525D01*
G03X338006Y202130I-283J283D01*
G02X339447Y204521I832J1128D01*
G03X339710Y204606I87J180D01*
G02X339950Y204927I1231J-670D01*
G03Y205493I-283J283D01*
G02X339711Y205812I991J991D01*
G03X339449Y205896I-175J-96D01*
G02X339073Y208540I-611J1262D01*
G03X339540Y208934I67J394D01*
G01Y210573D01*
X341107Y212139D01*
X341024Y212274D01*
G02X342352Y214405I1194J735D01*
G03X342790Y214803I38J398D01*
G01Y215115D01*
G37*
G36*
G01X992398D02*
G03X991960Y215513I-400J0D01*
G02Y218305I-134J1396D01*
G03X992398Y218703I38J398D01*
G01Y222915D01*
G03X991960Y223313I-400J0D01*
G02Y226105I-134J1396D01*
G03X992398Y226503I38J398D01*
G01Y226816D01*
G03X991960Y227214I-400J0D01*
G02Y230006I-134J1396D01*
G03X992398Y230404I38J398D01*
G01Y230715D01*
G03X991960Y231113I-400J0D01*
G02Y233905I-134J1396D01*
G03X992398Y234303I38J398D01*
G01Y234615D01*
G03X991960Y235013I-400J0D01*
G02Y237805I-134J1396D01*
G03X992398Y238203I38J398D01*
G01Y238515D01*
G03X991960Y238913I-400J0D01*
G02Y241705I-134J1396D01*
G03X992398Y242103I38J398D01*
G01Y242415D01*
G03X991960Y242813I-400J0D01*
G02Y245605I-134J1396D01*
G03X992398Y246003I38J398D01*
G01Y246315D01*
G03X991960Y246713I-400J0D01*
G02X992453Y249363I-134J1396D01*
G01X992582Y249298D01*
X993002Y249718D01*
G02X993805Y250116I991J-991D01*
G02X996396Y250802I1401J-56D01*
G01X997329D01*
G02X997339Y250801I-134J-1389D01*
G03X997496Y251127I1J200D01*
G02X999676I1090J882D01*
G03X999833Y250801I156J-126D01*
G02X999843Y250802I144J-1388D01*
G01X1000775D01*
G02X1003155I1190J-742D01*
G01X1004088D01*
G02X1004098Y250801I-134J-1389D01*
G03X1004255Y251127I1J200D01*
G02X1006435I1090J882D01*
G03X1006592Y250801I156J-126D01*
G02X1006602Y250802I144J-1388D01*
G01X1007535D01*
G02X1009915I1190J-742D01*
G01X1010848D01*
G02X1010858Y250801I-134J-1389D01*
G03X1011015Y251127I1J200D01*
G02X1013195I1090J882D01*
G03X1013350Y250802I156J-125D01*
G01X1013460D01*
X1013560Y250702D01*
X1014238D01*
G02X1016732I1247J-642D01*
G01X1019002D01*
X1020366Y249338D01*
X1020664D01*
X1020672Y249330D01*
X1022487D01*
X1022832Y249675D01*
Y251469D01*
X1027730Y256367D01*
G03X1027542Y257038I-283J283D01*
G02X1029237Y258733I333J1362D01*
G03X1029908Y258545I388J95D01*
G01X1038825Y267462D01*
X1077280D01*
X1078802Y265939D01*
X1078943Y266061D01*
G02X1078838Y264039I916J-1061D01*
G03X1078264Y264048I-291J-274D01*
G01X1071751Y257535D01*
G03X1071820Y256914I283J-283D01*
G02X1069886Y254980I-748J-1186D01*
G03X1069265Y255049I-338J-214D01*
G01X1068915Y254699D01*
X1068972Y254573D01*
G02X1067119Y252720I-1280J-573D01*
G01X1066993Y252777D01*
X1061880Y247664D01*
Y201064D01*
X1066994Y195951D01*
Y142789D01*
X1098902Y110881D01*
Y90572D01*
X1098149Y90271D01*
G03Y89529I151J-371D01*
G01X1098902Y89228D01*
Y85952D01*
X1098088Y85675D01*
G03Y84917I130J-379D01*
G01X1098902Y84640D01*
Y74245D01*
X1098081Y73969D01*
X1098080D01*
G03X1097947Y73284I127J-380D01*
G02X1097987Y71191I-911J-1064D01*
G03X1098005Y70587I272J-294D01*
G02X1097987Y68404I-888J-1084D01*
G03X1098101Y67712I248J-315D01*
G01X1098902Y67429D01*
Y55519D01*
X1098387Y55233D01*
G03Y54533I194J-350D01*
G01X1098902Y54247D01*
Y51617D01*
X1097999Y51388D01*
G03Y50612I101J-388D01*
G01X1098902Y50383D01*
Y47602D01*
X1098018Y47361D01*
G03Y46589I107J-386D01*
G01X1098902Y46348D01*
Y36351D01*
X1097942Y36153D01*
G03X1097853Y35398I80J-392D01*
G02X1098252Y33136I-591J-1271D01*
G01Y33135D01*
X1097202Y32085D01*
Y27415D01*
X1098902Y25715D01*
Y19585D01*
X1097002Y17685D01*
Y16776D01*
X1096900D01*
G03X1096738Y16460I0J-200D01*
G02X1097002Y15642I-1138J-819D01*
G01Y12849D01*
G03X1097497Y12461I400J0D01*
G02X1098437Y9834I338J-1361D01*
G03X1098326Y9190I172J-361D01*
G01X1098902Y8615D01*
Y-3883D01*
X1097377Y-5407D01*
G02X1096206Y-5806I-991J991D01*
G03X1095758Y-6254I-51J-397D01*
G02X1095359Y-7425I-1390J-180D01*
G01X1095006Y-7778D01*
G03X1095121Y-8424I283J-283D01*
G02X1093083Y-9255I-633J-1362D01*
G01X1093128Y-9135D01*
X1092535Y-8542D01*
X1089499D01*
G03X1089141Y-9119I0J-400D01*
G02X1086609Y-8864I-1346J-667D01*
G03X1086451Y-8542I-158J122D01*
G01X1086095D01*
X1085425Y-9212D01*
X1083225D01*
X1082345Y-8332D01*
X1081913D01*
Y-8632D01*
X1081994Y-8692D01*
G02X1080210I-892J-1209D01*
G01X1080291Y-8632D01*
Y-8332D01*
X1079835D01*
X1078985Y-9182D01*
X1076675D01*
X1076035Y-8542D01*
X1075753D01*
G03X1075595Y-8864I0J-200D01*
G02X1072907Y-9751I-1186J-922D01*
G03X1072285Y-9409I-400J10D01*
G01X1071442Y-8565D01*
X1071338Y-8584D01*
G02X1069767Y-7869I-276J1476D01*
G02X1068287Y-7602I-530J1297D01*
G01X1065794D01*
X1065741Y-7720D01*
G02X1062997I-1372J612D01*
G01X1062944Y-7602D01*
X1059101D01*
X1059048Y-7720D01*
G02X1056304I-1372J612D01*
G01X1056251Y-7602D01*
X1052301D01*
X1052247Y-7715D01*
G02X1049719I-1264J607D01*
G01X1049665Y-7602D01*
X1046365D01*
X1044526Y-9441D01*
X1043887Y-9309D01*
X1043883D01*
G03X1043435Y-9535I-84J-391D01*
G01Y-9537D01*
X1043112Y-10242D01*
X1041756D01*
G02X1041122Y-10090I1J1402D01*
G03X1040862Y-10163I-90J-179D01*
G02X1034712Y-10131I-3065J1891D01*
G03X1034452Y-10055I-171J-103D01*
G02X1033829Y-10202I-625J1255D01*
G01X1032128D01*
X1031092Y-9165D01*
Y-8035D01*
X1030408Y-7351D01*
G03X1029795Y-7408I-283J-283D01*
G02X1028530Y-8013I-1156J793D01*
G03X1028100Y-8375I-32J-399D01*
G01X1027469Y-9006D01*
G03X1027630Y-9670I283J-283D01*
G02X1025836Y-10691I-428J-1335D01*
G03X1025446Y-10202I-390J89D01*
G01X1023398D01*
G02X1021239Y-9597I-853J1113D01*
G03X1020497Y-9898I-373J-145D01*
G02X1019206Y-11844I-1292J-544D01*
G01X1015958D01*
G02X1014760Y-11169I1J1402D01*
G02X1012748Y-10261I-587J1383D01*
G02X1012251I-249J1379D01*
G02X1010239Y-11169I-1425J475D01*
G02X1009041Y-11844I-1199J727D01*
G01X1002610D01*
G02X1001461Y-11243I1J1401D01*
G02X1000113I-674J1342D01*
G02X998964Y-11844I-1150J800D01*
G01X995879D01*
G02X994681Y-11169I1J1402D01*
G02X993507I-587J1383D01*
G02X992309Y-11844I-1199J727D01*
G01X982493D01*
G02X981295Y-11169I1J1402D01*
G02X980121I-587J1383D01*
G02X978923Y-11844I-1199J727D01*
G01X975838D01*
G02X974689Y-11243I1J1401D01*
G02X973341I-674J1342D01*
G02X972192Y-11844I-1150J800D01*
G01X958444D01*
X957914Y-11315D01*
X956480Y-9883D01*
Y-8978D01*
G02X956752Y-8149I1402J-1D01*
G02Y-6211I1013J969D01*
G02X956480Y-5382I1130J830D01*
G01Y-2460D01*
X957384Y-2231D01*
G03X957474Y-1491I-101J388D01*
G01X956948Y-1207D01*
Y8664D01*
X957473Y8948D01*
G03Y9652I-190J352D01*
G01X956948Y9936D01*
Y12535D01*
X957737Y12824D01*
X957738D01*
G03X957417Y13556I-137J376D01*
G01X956636Y13148D01*
X955098Y14685D01*
Y15490D01*
G02X955912Y16762I1402J-1D01*
G02Y17352I1371J295D01*
G02X955098Y18624I588J1273D01*
G01Y26915D01*
X955908Y27724D01*
X955894Y27823D01*
G02X956771Y29319I1389J191D01*
G01X956898Y29369D01*
Y31483D01*
X957801Y31712D01*
G03Y32488I-101J388D01*
G01X956898Y32717D01*
Y35322D01*
X957459Y35597D01*
G03Y36317I-176J360D01*
G01X956898Y36592D01*
Y50063D01*
X957691Y50352D01*
X957693D01*
G03X957692Y51106I-135J377D01*
G01X957691Y51107D01*
X957436Y51198D01*
X956348Y52285D01*
Y53812D01*
G02X956627Y56096I935J1045D01*
G02X956683Y56997I1353J368D01*
G01X956698Y57033D01*
Y66678D01*
G02X957386Y69196I838J1124D01*
G02X957862Y70097I1392J-159D01*
G03X957675Y70793I-262J303D01*
G01X956698Y70979D01*
Y73110D01*
X957375Y73440D01*
G03X957457Y74107I-175J360D01*
G01X957098Y74407D01*
Y86733D01*
X957904Y87016D01*
X957905D01*
G03Y87772I-131J378D01*
G01X957904D01*
X957098Y88055D01*
Y90513D01*
X957077Y90555D01*
G02X956930Y91300I1250J634D01*
G02X956348Y93702I353J1357D01*
G01Y99615D01*
X957620Y100886D01*
Y105796D01*
X987490Y135667D01*
Y201357D01*
X987659Y201525D01*
G03X987614Y202130I-283J283D01*
G02X989055Y204521I832J1128D01*
G03X989318Y204606I87J180D01*
G02X989558Y204927I1231J-670D01*
G03Y205493I-283J283D01*
G02X989319Y205812I991J991D01*
G03X989057Y205896I-175J-96D01*
G02X988681Y208540I-611J1262D01*
G03X989148Y208934I67J394D01*
G01Y210573D01*
X990715Y212139D01*
X990632Y212274D01*
G02X991960Y214405I1194J735D01*
G03X992398Y214803I38J398D01*
G01Y215115D01*
G37*
G36*
G01X90170Y-10745D02*
G02X88916Y-9191I-1393J159D01*
G03X89311Y-8609I40J398D01*
G02X90822Y-10483I5373J2786D01*
G03X90170Y-10745I-255J-308D01*
G37*
G36*
G01X735454Y-7525D02*
G02X734182Y-7734I-434J-1333D01*
G03X734066Y-7033I-239J320D01*
G02X733101Y-5790I434J1333D01*
G03X732588Y-5432I-399J-25D01*
G02X731232Y-3064I-397J1345D01*
G03X731260Y-2509I-273J292D01*
G02X733327Y-616I1056J922D01*
G03X733905I289J277D01*
G02Y-2558I1011J-971D01*
G03X733327I-289J-277D01*
G02X733275Y-2610I-1017J965D01*
G03X733247Y-3165I273J-292D01*
G02X733590Y-3997I-1056J-922D01*
G03X734103Y-4355I399J25D01*
G02X735338Y-6824I397J-1345D01*
G03X735454Y-7525I239J-320D01*
G37*
G36*
G01X1606667Y-4377D02*
G02Y-2823I-1167J777D01*
G03X1607333I333J222D01*
G02Y-4377I1167J-777D01*
G03X1606667I-333J-222D01*
G37*
G36*
G01X1837406Y-2254D02*
G02X1836404Y-3467I394J-1346D01*
G03X1835894Y-3046I-398J37D01*
G02X1836896Y-1833I-394J1346D01*
G03X1837406Y-2254I398J-37D01*
G37*
G36*
G01X624333Y-2565D02*
G02X623044Y-1599I-1333J-435D01*
G03X623437Y-1075I13J400D01*
G02X624726Y-2041I1333J435D01*
G03X624333Y-2565I-13J-400D01*
G37*
G36*
G01X1689167Y2223D02*
G02Y3777I-1167J777D01*
G03X1689833I333J222D01*
G02Y2223I1167J-777D01*
G03X1689167I-333J-222D01*
G37*
G36*
G01X1547967Y2623D02*
G02Y4177I-1167J777D01*
G03X1548633I333J222D01*
G02X1550773Y4410I1167J-777D01*
G03X1551327I277J288D01*
G02X1553273I973J-1010D01*
G03X1553827I277J288D01*
G02X1556045Y4045I973J-1010D01*
G03X1556755I355J184D01*
G02X1558973Y4410I1245J-645D01*
G03X1559527I277J288D01*
G02X1561550Y4329I973J-1010D01*
G03X1562150I300J265D01*
G02X1564289Y4283I1050J-929D01*
G03X1564911I311J252D01*
G02X1567167Y4177I1089J-883D01*
G03X1567833I333J222D01*
G02Y2623I1167J-777D01*
G03X1567167I-333J-222D01*
G02X1564911Y2517I-1167J777D01*
G03X1564289I-311J-252D01*
G02X1562150Y2471I-1089J883D01*
G03X1561550I-300J-265D01*
G02X1559527Y2390I-1050J929D01*
G03X1558973I-277J-288D01*
G02X1556755Y2755I-973J1010D01*
G03X1556045I-355J-184D01*
G02X1553827Y2390I-1245J645D01*
G03X1553273I-277J-288D01*
G02X1551327I-973J1010D01*
G03X1550773I-277J-288D01*
G02X1548633Y2623I-973J1010D01*
G03X1547967I-333J-222D01*
G37*
G36*
G01X1510373Y2490D02*
G02Y4510I-973J1010D01*
G03X1510927I277J288D01*
G02X1512873I973J-1010D01*
G03X1513427I277J288D01*
G02X1515373I973J-1010D01*
G03X1515927I277J288D01*
G02X1518145Y4145I973J-1010D01*
G03X1518855I355J184D01*
G02Y2855I1245J-645D01*
G03X1518145I-355J-184D01*
G02X1515927Y2490I-1245J645D01*
G03X1515373I-277J-288D01*
G02X1513427I-973J1010D01*
G03X1512873I-277J-288D01*
G02X1510927I-973J1010D01*
G03X1510373I-277J-288D01*
G37*
G36*
G01X1525889Y2617D02*
G02Y4383I-1089J883D01*
G03X1526511I311J252D01*
G02X1528845Y4145I1089J-883D01*
G03X1529555I355J184D01*
G02X1532045I1245J-645D01*
G03X1532755I355J184D01*
G02Y2855I1245J-645D01*
G03X1532045I-355J-184D01*
G02X1529555I-1245J645D01*
G03X1528845I-355J-184D01*
G02X1526511Y2617I-1245J645D01*
G03X1525889I-311J-252D01*
G37*
G36*
G01X1786560Y7365D02*
G02X1786549Y8852I-1194J735D01*
G03X1787227Y8857I337J215D01*
G02X1787238Y7370I1194J-735D01*
G03X1786560Y7365I-337J-215D01*
G37*
G36*
G01X649581Y7600D02*
G02X647784Y9724I-1031J950D01*
G03X647773Y10401I-218J335D01*
G02X649474Y12608I727J1199D01*
G03X650051Y12630I278J288D01*
G02X651847Y10513I1049J-931D01*
G03Y9837I213J-338D01*
G02X650147Y7622I-747J-1186D01*
G03X649581Y7600I-272J-293D01*
G37*
G36*
G01X1809523Y10358D02*
G02X1807832Y10471I-920J-1058D01*
G03X1807875Y11107I-220J334D01*
G02X1809566Y10994I920J1058D01*
G03X1809523Y10358I220J-334D01*
G37*
G36*
G01X1619797Y12266D02*
X1624799D01*
G02X1626310Y10765I0J-1512D01*
G01Y10670D01*
X1626300Y10586D01*
G02X1624798Y9244I-1502J169D01*
G01X1619796D01*
G02X1618983Y9482I1J1511D01*
G03X1618375Y9224I-216J-336D01*
G02X1617708Y10710I-1375J276D01*
G03X1618305Y10992I202J345D01*
G02X1619797Y12266I1493J-237D01*
G37*
G36*
G01X1842292Y10352D02*
G02X1842206Y8838I1134J-824D01*
G03X1841534Y8876I-348J-197D01*
G02X1839427Y8690I-1134J824D01*
G03X1838873I-277J-288D01*
G02Y10710I-973J1010D01*
G03X1839427I277J288D01*
G02X1841620Y10390I972J-1010D01*
G03X1842292Y10352I348J197D01*
G37*
G36*
G01X1323621Y8939D02*
G02X1321743Y10981I-1089J883D01*
G03X1321733Y11650I-224J331D01*
G02X1321660Y13969I750J1184D01*
G03X1321666Y14613I-234J324D01*
G02X1323597Y16617I842J1121D01*
G03X1324219I311J252D01*
G02X1326340Y16682I1089J-883D01*
G03X1326948Y16704I295J271D01*
G02X1328789Y14643I1097J-873D01*
G03X1328806Y13954I212J-339D01*
G02X1328959Y11604I-683J-1224D01*
G03X1328950Y10968I238J-321D01*
G02X1327028Y8944I-865J-1103D01*
G03X1326417Y8934I-301J-263D01*
G02X1324243Y8939I-1085J888D01*
G03X1323621I-311J-252D01*
G37*
G36*
G01X1833522Y11557D02*
G02X1831621Y9726I-622J-1257D01*
G03X1830952Y9822I-365J-164D01*
G02X1831167Y11309I-1064J913D01*
G03X1831836Y11213I365J164D01*
G02X1832233Y11533I1064J-913D01*
G03X1832220Y12243I-190J352D01*
G02X1833509Y12267I621J1257D01*
G03X1833522Y11557I190J-352D01*
G37*
G36*
G01X63880Y12677D02*
G02X62764Y11443I279J-1374D01*
G03X62287Y11875I-398J40D01*
G02X63403Y13109I-279J1374D01*
G03X63880Y12677I398J-40D01*
G37*
G36*
G01X1847352Y13735D02*
G02X1847035Y12168I970J-1012D01*
G03X1846390Y12298I-368J-158D01*
G02X1846707Y13865I-970J1012D01*
G03X1847352Y13735I368J158D01*
G37*
G36*
G01X1869503Y12151D02*
G02X1869308Y13808I-1217J697D01*
G03X1869946Y13883I291J274D01*
G02X1870141Y12226I1217J-697D01*
G03X1869503Y12151I-291J-274D01*
G37*
G36*
G01X1414946Y12458D02*
G02Y13820I-1225J681D01*
G03X1415646I350J194D01*
G02Y12458I1225J-681D01*
G03X1414946I-350J-194D01*
G37*
G36*
G01X25301Y17595D02*
G02X23782Y16791I-241J-1381D01*
G03X23487Y17350I-364J165D01*
G02X25006Y18154I241J1381D01*
G03X25301Y17595I364J-165D01*
G37*
G36*
G01X63377Y18524D02*
G02X62881Y16915I823J-1135D01*
G03X62269Y17103I-376J-135D01*
G02X62765Y18712I-823J1135D01*
G03X63377Y18524I376J135D01*
G37*
G36*
G01X35905Y18708D02*
G02X35882Y20238I-1186J747D01*
G03X36553Y20248I332J223D01*
G02X38615Y20596I1186J-747D01*
G03X39234Y20755I250J312D01*
G02X39654Y19125I1296J-535D01*
G03X39035Y18966I-250J-312D01*
G02X36576Y18718I-1296J535D01*
G03X35905Y18708I-332J-223D01*
G37*
G36*
G01X702306Y18872D02*
G02X700071Y18689I-1186J747D01*
G03X699483Y18700I-299J-266D01*
G02X699519Y20599I-1013J969D01*
G03X700107Y20588I299J266D01*
G02X702291Y20390I1013J-969D01*
G03X702964Y20397I334J220D01*
G02X702979Y18879I1186J-747D01*
G03X702306Y18872I-334J-220D01*
G37*
G36*
G01X1853676Y20417D02*
G02X1850883Y21976I-1441J700D01*
G03X1850644Y22578I-338J214D01*
G02X1850313Y25557I396J1552D01*
G03X1850492Y26087I-182J357D01*
G02X1853336Y27558I1444J693D01*
G03X1854036I350J194D01*
G02X1856876Y27481I1400J-778D01*
G03X1857596I360J175D01*
G02X1860476I1440J-701D01*
G03X1861196I360J175D01*
G02X1864207Y26465I1440J-701D01*
G03X1864483Y26004I392J-78D01*
G02X1865565Y24045I-463J-1534D01*
G03X1865850Y23551I385J-107D01*
G02X1864840Y20519I-399J-1551D01*
G03X1864338Y20342I-152J-370D01*
G02X1861536Y20340I-1402J776D01*
G03X1860836I-350J-194D01*
G02X1857996Y20417I-1400J778D01*
G03X1857276I-360J-175D01*
G02X1854396I-1440J701D01*
G03X1853676I-360J-175D01*
G37*
G36*
G01X1839505Y20731D02*
G02X1836897Y20443I-1405J769D01*
G03X1836301Y20449I-301J-264D01*
G02X1833901Y20494I-1180J1083D01*
G03X1833291I-305J-259D01*
G02Y22570I-1220J1038D01*
G03X1833901I305J259D01*
G02X1836324Y22589I1220J-1038D01*
G03X1836920Y22583I301J264D01*
G02X1839437Y22382I1180J-1083D01*
G03X1840108Y22387I334J220D01*
G02X1840174Y20781I1181J-756D01*
G03X1839505Y20731I-318J-242D01*
G37*
G36*
G01X1878167Y23773D02*
G02X1878899Y21841I3428J194D01*
G03X1878206Y21724I-315J-247D01*
G02X1877571Y23402I-1325J458D01*
G03X1878167Y23773I197J348D01*
G37*
G36*
G01X755559Y23924D02*
G02X755505Y22420I1155J-794D01*
G03X754830Y22445I-345J-202D01*
G02X754884Y23949I-1155J794D01*
G03X755559Y23924I345J202D01*
G37*
G36*
G01X713670Y24408D02*
G02X713617Y22895I1153J-798D01*
G03X712944Y22918I-344J-204D01*
G02X712997Y24431I-1153J798D01*
G03X713670Y24408I344J204D01*
G37*
G36*
G01X1871884Y25563D02*
G02X1869964Y26249I-1284J-563D01*
G03X1870029Y26921I-181J357D01*
G02X1872259Y26123I2314J2953D01*
G03X1871884Y25563I-8J-400D01*
G37*
G36*
G01X69167Y25215D02*
G02X66831Y25218I-1167J777D01*
G03X66165Y25220I-334J-221D01*
G02X63833Y25223I-1165J780D01*
G03X63167I-333J-222D01*
G02X61027Y24990I-1167J777D01*
G03X60473I-277J-288D01*
G02X58490Y26973I-973J1010D01*
G03Y27527I-288J277D01*
G02X60473Y29510I1010J973D01*
G03X61027I277J288D01*
G02X63167Y29277I973J-1010D01*
G03X63833I333J222D01*
G02X66167I1167J-777D01*
G03X66833I333J222D01*
G02X69167I1167J-777D01*
G03X69833I333J222D01*
G02X72167I1167J-777D01*
G03X72833I333J222D01*
G02X75167I1167J-777D01*
G03X75833I333J222D01*
G02X78043Y29436I1167J-777D01*
G03X78709Y29547I298J267D01*
G02X80777Y27833I1291J-547D01*
G03Y27167I222J-333D01*
G02X78835Y25220I-777J-1167D01*
G03X78169Y25218I-332J-223D01*
G02X75833Y25215I-1169J774D01*
G03X75167I-333J-222D01*
G02X72833I-1167J777D01*
G03X72167I-333J-222D01*
G02X69833I-1167J777D01*
G03X69167I-333J-222D01*
G37*
G36*
G01X1837663Y27859D02*
G02X1837514Y25561I1037J-1221D01*
G03X1836958Y25597I-297J-268D01*
G02X1834661Y25829I-1037J1221D01*
G03X1834031I-315J-247D01*
G02X1831458Y25901I-1260J989D01*
G03X1830798Y25896I-328J-229D01*
G02X1830725Y27563I-1162J784D01*
G03X1831382Y27616I310J252D01*
G02X1834031Y27807I1389J-798D01*
G03X1834661I315J247D01*
G02X1837107Y27895I1260J-989D01*
G03X1837663Y27859I297J268D01*
G37*
G36*
G01X643566Y30162D02*
G02X643831Y32385I-5773J1815D01*
G03X644497Y32113I399J26D01*
G02X644277Y30270I933J-1046D01*
G03X643566Y30162I-329J-228D01*
G37*
G36*
G01X1855356Y35523D02*
G02X1855081Y33888I977J-1005D01*
G03X1854444Y33995I-358J-180D01*
G02X1854719Y35630I-977J1005D01*
G03X1855356Y35523I358J180D01*
G37*
G36*
G01X702098Y36889D02*
G02X700469Y36532I-573J-1279D01*
G03X700331Y37160I-302J263D01*
G02X701960Y37517I573J1279D01*
G03X702098Y36889I302J-263D01*
G37*
G36*
G01X3401Y37588D02*
G02X2221Y36451I199J-1388D01*
G03X1771Y36919I-393J72D01*
G02X2951Y38056I-199J1388D01*
G03X3401Y37588I393J-72D01*
G37*
G36*
G01X1818049Y38126D02*
G02X1816526Y38042I-697J-1217D01*
G03X1816489Y38712I-236J323D01*
G02X1818012Y38796I697J1217D01*
G03X1818049Y38126I236J-323D01*
G37*
G36*
G01X1879863Y38648D02*
G02X1877978Y38508I-866J-1102D01*
G03X1877934Y39098I-291J275D01*
G02X1878027Y41370I866J1102D01*
G03Y42037I-220J334D01*
G02X1879573I773J1170D01*
G03Y41370I220J-333D01*
G02X1879819Y39238I-773J-1169D01*
G03X1879863Y38648I291J-275D01*
G37*
G36*
G01X717821Y39557D02*
G02X715736Y37718I-921J-1057D01*
G03X715097Y37752I-332J-223D01*
G02X712873Y37851I-1074J901D01*
G03X712224Y37862I-328J-228D01*
G02X710054Y39634I-1123J839D01*
G03Y40166I-298J266D01*
G02X712250Y41902I1046J933D01*
G03X712899Y41891I328J228D01*
G02X713154Y42154I1126J-836D01*
G03X713149Y42786I-247J314D01*
G02X713067Y44947I851J1114D01*
G03X712995Y45595I-266J298D01*
G02X714647Y47831I679J1227D01*
G03X715203I278J288D01*
G02X717077Y47896I973J-1009D01*
G03X717615Y47918I257J307D01*
G02X718193Y48263I987J-996D01*
G03X718471Y48718I-115J383D01*
G02X720796Y50005I1379J252D01*
G03X721342Y50011I270J295D01*
G02X723690Y48740I970J-1012D01*
G03X723976Y48280I393J-75D01*
G02X722657Y45894I-373J-1351D01*
G03X722111Y45888I-270J-295D01*
G02X720144Y45914I-970J1012D01*
G03X719580Y45919I-285J-281D01*
G02X717699Y45847I-980J1002D01*
G03X717161Y45825I-257J-307D01*
G02X717105Y45772I-991J991D01*
G03X717222Y45101I265J-299D01*
G02X717628Y42749I-522J-1301D01*
G03X717637Y42141I264J-300D01*
G02X717786Y40126I-895J-1079D01*
G03X717821Y39557I298J-267D01*
G37*
G36*
G01X1825416Y39145D02*
G02X1824999Y40803I-1286J558D01*
G03X1825614Y40958I248J314D01*
G02X1826031Y39300I1286J-558D01*
G03X1825416Y39145I-248J-314D01*
G37*
G36*
G01X1637398Y38350D02*
X1632398D01*
G02X1630896Y39694I0J1512D01*
G03X1630473Y40049I-398J-44D01*
G02X1629531Y40337I-87J1399D01*
G03X1629211Y40150I-122J-159D01*
G02X1629219Y40082I-1497J-211D01*
G01X1629226Y40019D01*
X1629227Y39956D01*
G02Y39911I-1512J-23D01*
G01X1629226Y39910D01*
Y39900D01*
G02X1627725Y38423I-1511J34D01*
G01X1622645Y38389D01*
G02X1622625Y41411I-10J1511D01*
G01X1627704Y41445D01*
G02X1628410Y41277I13J-1512D01*
G03X1628991Y41591I183J355D01*
G02X1631767Y41690I1395J-143D01*
G03X1632211Y41362I394J69D01*
G02X1632398Y41374I190J-1500D01*
G01X1637399D01*
G02X1638910Y39872I-1J-1512D01*
G01Y39777D01*
X1638900Y39693D01*
G02X1637398Y38350I-1502J169D01*
G37*
G36*
G01X1868660Y40718D02*
G02X1867396Y41163I-1041J-939D01*
G03X1867629Y41826I-64J395D01*
G02X1868893Y41381I1041J939D01*
G03X1868660Y40718I64J-395D01*
G37*
G36*
G01X685717Y41085D02*
G02X684243Y41179I-813J-1142D01*
G03X684287Y41858I-188J353D01*
G02X685761Y41764I813J1142D01*
G03X685717Y41085I188J-353D01*
G37*
G36*
G01X1350135Y39522D02*
G02X1350061Y41113I-1190J742D01*
G03X1350718Y41144I318J243D01*
G02X1350792Y39553I1190J-742D01*
G03X1350135Y39522I-318J-243D01*
G37*
G36*
G01X1856584Y40050D02*
G02X1856393Y41790I-1184J751D01*
G03X1857014Y41858I283J282D01*
G02X1859170Y42118I1184J-750D01*
G03X1859745Y42139I277J288D01*
G02X1859814Y40190I1041J-939D01*
G03X1859239Y40169I-277J-288D01*
G02X1857205Y40118I-1041J939D01*
G03X1856584Y40050I-283J-282D01*
G37*
G36*
G01X59973Y42490D02*
G02X58223Y44667I-972J1010D01*
G03Y45333I-222J333D01*
G02Y47667I777J1167D01*
G03Y48333I-222J333D01*
G02X59973Y50510I778J1167D01*
G03X60527I277J288D01*
G02X62667Y50277I973J-1010D01*
G03X63333I333J222D01*
G02X65667I1167J-777D01*
G03X66333I333J222D01*
G02X68667I1167J-777D01*
G03X69333I333J222D01*
G02X71667I1167J-777D01*
G03X72333I333J222D01*
G02X74667I1167J-777D01*
G03X75333I333J222D01*
G02X77667I1167J-777D01*
G03X78333I333J222D01*
G02X80277Y48333I1167J-777D01*
G03Y47667I222J-333D01*
G02Y45333I-777J-1167D01*
G03Y44667I222J-333D01*
G02X78333Y42723I-777J-1167D01*
G03X77667I-333J-222D01*
G02X75333I-1167J777D01*
G03X74667I-333J-222D01*
G02X72333I-1167J777D01*
G03X71667I-333J-222D01*
G02X69333I-1167J777D01*
G03X68667I-333J-222D01*
G02X66333I-1167J777D01*
G03X65667I-333J-222D01*
G02X63333I-1167J777D01*
G03X62667I-333J-222D01*
G02X60527Y42490I-1167J777D01*
G03X59973I-277J-288D01*
G37*
G36*
G01X657040Y43629D02*
G02X655290Y45806I-972J1010D01*
G03Y46472I-222J333D01*
G02X657040Y48649I778J1167D01*
G03X657594I277J288D01*
G02X659344Y46472I972J-1010D01*
G03Y45806I222J-333D01*
G02X657594Y43629I-778J-1167D01*
G03X657040I-277J-288D01*
G37*
G36*
G01X1378856Y46412D02*
G02X1377714Y45162I254J-1379D01*
G03X1377243Y45592I-398J37D01*
G02X1378385Y46842I-254J1379D01*
G03X1378856Y46412I398J-37D01*
G37*
G36*
G01X1266336Y46199D02*
G02X1266158Y47939I-1179J758D01*
G03X1266780Y48003I285J280D01*
G02X1266958Y46263I1179J-758D01*
G03X1266336Y46199I-285J-280D01*
G37*
G36*
G01X12467Y48308D02*
G02X10328Y48015I-928J-1181D01*
G03X10270Y48551I-323J236D01*
G02X10187Y48631I931J1049D01*
G03X9632Y48653I-289J-277D01*
G02X9713Y50669I-932J1047D01*
G03X10268Y50647I289J277D01*
G02X12303Y50466I932J-1047D01*
G03X12926Y50459I314J247D01*
G02X12773Y48910I1084J-889D01*
G03X12422Y48913I-176J-94D01*
G02X12378Y48840I-1222J687D01*
G03X12467Y48308I336J-217D01*
G37*
G36*
G01X-8844Y50087D02*
G02X-8845Y51712I-1143J812D01*
G03X-8193I326J232D01*
G02X-8192Y50087I1143J-812D01*
G03X-8844I-326J-232D01*
G37*
G36*
G01X114508Y56436D02*
G02X112892Y55842I-426J-1336D01*
G03X112674Y56434I-339J211D01*
G02X114290Y57028I426J1336D01*
G03X114508Y56436I339J-211D01*
G37*
G36*
G01X1393023Y54549D02*
G02X1391273Y56726I-972J1010D01*
G03Y57392I-222J333D01*
G02X1393023Y59569I778J1167D01*
G03X1393577I277J288D01*
G02X1395523I973J-1010D01*
G03X1396077I277J288D01*
G02X1397827Y57392I972J-1010D01*
G03Y56726I222J-333D01*
G02X1396077Y54549I-778J-1167D01*
G03X1395523I-277J-288D01*
G02X1393577I-973J1010D01*
G03X1393023I-277J-288D01*
G37*
G36*
G01X2629Y57596D02*
G02X1052Y57616I-803J-1149D01*
G03X1060Y58277I-221J333D01*
G02X2637Y58257I803J1149D01*
G03X2629Y57596I221J-333D01*
G37*
G36*
G01X81777Y59667D02*
G02X80223I-777J-1167D01*
G03Y60333I-222J333D01*
G02X81777I777J1167D01*
G03Y59667I222J-333D01*
G37*
G36*
G01X-7239Y59518D02*
G02X-9396Y60971I-1371J292D01*
G03X-9343Y61590I-224J331D01*
G02X-9771Y62657I973J1010D01*
G03X-10237Y63068I-400J16D01*
G02X-11672Y63728I-234J1382D01*
G03X-12369Y63708I-343J-206D01*
G02X-12408Y65082I-1241J652D01*
G03X-11711Y65102I343J206D01*
G02X-10689Y65835I1241J-652D01*
G03X-10449Y66492I-62J395D01*
G02X-9171Y66025I1060J918D01*
G03X-9411Y65368I62J-395D01*
G02X-9069Y64393I-1059J-919D01*
G03X-8603Y63982I400J-16D01*
G02X-6972Y62710I233J-1382D01*
G03X-6449Y62362I398J32D01*
G02X-6662Y59789I439J-1332D01*
G03X-7239Y59518I-186J-354D01*
G37*
G36*
G01X1875282Y59842D02*
G02X1875079Y61138I-1326J456D01*
G03X1875777Y61248I320J240D01*
G02X1875980Y59952I1326J-456D01*
G03X1875282Y59842I-320J-240D01*
G37*
G36*
G01X1393350Y64127D02*
G02X1391442Y66175I-1011J971D01*
G03X1391400Y66821I-256J308D01*
G02X1393262Y68858I749J1185D01*
G03X1393906Y68870I318J243D01*
G02X1396023Y69069I1144J-811D01*
G03X1396577I277J288D01*
G02X1398345Y66904I972J-1011D01*
G03X1398342Y66247I227J-330D01*
G02X1396528Y64127I-802J-1149D01*
G03X1395950I-289J-277D01*
G02X1393928I-1011J971D01*
G03X1393350I-289J-277D01*
G37*
G36*
G01X656573Y65090D02*
G02X654823Y67267I-972J1010D01*
G03Y67933I-222J333D01*
G02X656573Y70110I778J1167D01*
G03X657127I277J288D01*
G02X658877Y67933I972J-1010D01*
G03Y67267I222J-333D01*
G02X657127Y65090I-778J-1167D01*
G03X656573I-277J-288D01*
G37*
G36*
G01X1665360Y70935D02*
G02X1663340I-1010J-973D01*
G03Y71489I-288J277D01*
G02X1663233Y71615I1013J969D01*
G03X1662885Y71561I-159J-121D01*
G02X1661123Y70697I-1322J467D01*
G03X1660598Y70311I-125J-380D01*
G02X1659636Y71622I-1402J-20D01*
G03X1660161Y72008I125J380D01*
G02X1660178Y72245I1402J19D01*
G03X1659870Y72443I-198J31D01*
G02X1658127Y72604I-771J1171D01*
G03X1657573I-277J-288D01*
G02Y74624I-973J1010D01*
G03X1658127I277J288D01*
G02X1660500Y73684I973J-1010D01*
G03X1661047Y73332I399J20D01*
G02X1662513Y73059I516J-1304D01*
G03X1663132Y73155I271J294D01*
G02X1665360Y71489I1219J-693D01*
G03Y70935I288J-277D01*
G37*
G36*
G01X1767991Y71341D02*
G02X1767899Y69490I1259J-990D01*
G03X1767268Y69547I-338J-215D01*
G02X1767358Y71346I-1028J953D01*
G03X1767991Y71341I318J242D01*
G37*
G36*
G01X1931270Y69302D02*
G02X1928934Y71490I-1119J1146D01*
G03X1928897Y72050I-303J261D01*
G02X1928674Y72293I1062J1199D01*
G03X1928028Y72288I-321J-239D01*
G02X1927949Y74025I-1138J819D01*
G03X1928592Y74080I301J263D01*
G02X1931043Y74429I1369J-833D01*
G03X1931596Y74441I270J295D01*
G02X1933807Y74496I1134J-1131D01*
G03X1934331Y74483I269J296D01*
G02X1934965Y74802I1019J-1236D01*
G03X1935236Y75350I-96J388D01*
G02X1937806Y77151I1470J637D01*
G03X1938359Y77154I275J291D01*
G02X1940623Y77112I1111J-1154D01*
G03X1941207Y77120I288J277D01*
G02X1943433Y77256I1183J-1080D01*
G03X1943959Y77260I261J303D01*
G02X1946524Y75509I1061J-1200D01*
G03X1946790Y74987I376J-137D01*
G02X1947390Y74665I-440J-1540D01*
G03X1947910Y74666I259J304D01*
G02X1947911Y72230I1041J-1218D01*
G03X1947391Y72229I-259J-304D01*
G02X1945271Y72263I-1041J1218D01*
G03X1944711Y72243I-270J-295D01*
G02X1944641Y72174I-1159J1106D01*
G03X1944663Y71863I136J-147D01*
G02X1942630Y69402I-913J-1316D01*
G03X1942070I-280J-286D01*
G02X1939871Y69363I-1120J1145D01*
G03X1939311Y69343I-270J-295D01*
G02X1937110Y69229I-1161J1104D01*
G03X1936590I-260J-304D01*
G02X1934510I-1040J1218D01*
G03X1933990I-260J-304D01*
G02X1931830Y69302I-1040J1218D01*
G03X1931270I-280J-286D01*
G37*
G36*
G01X1613948Y71562D02*
G02X1613859Y70164I1167J-776D01*
G03X1613167Y70208I-359J-178D01*
G02X1613256Y71606I-1167J776D01*
G03X1613948Y71562I359J178D01*
G37*
G36*
G01X1585945Y70110D02*
G02X1585874Y71675I-1197J730D01*
G03X1586537Y71704I322J238D01*
G02X1586608Y70139I1197J-730D01*
G03X1585945Y70110I-322J-238D01*
G37*
G36*
G01X650973Y71290D02*
G02X649223Y73467I-972J1010D01*
G03Y74133I-222J333D01*
G02X650973Y76310I778J1167D01*
G03X651527I277J288D01*
G02X653277Y74133I972J-1010D01*
G03Y73467I222J-333D01*
G02X651527Y71290I-778J-1167D01*
G03X650973I-277J-288D01*
G37*
G36*
G01X657473D02*
G02X655723Y73467I-972J1010D01*
G03Y74133I-222J333D01*
G02X657473Y76310I778J1167D01*
G03X658027I277J288D01*
G02X659777Y74133I972J-1010D01*
G03Y73467I222J-333D01*
G02X658027Y71290I-778J-1167D01*
G03X657473I-277J-288D01*
G37*
G36*
G01X1592905Y76213D02*
G02X1590493Y74840I-1305J-513D01*
G03X1589907Y74890I-316J-245D01*
G02X1590069Y76786I-945J1036D01*
G03X1590655Y76736I316J245D01*
G02X1591385Y77085I944J-1037D01*
G03X1591695Y77627I-62J395D01*
G02X1593215Y76755I1305J513D01*
G03X1592905Y76213I62J-395D01*
G37*
G36*
G01X80403Y77220D02*
G02X78872Y77105I-678J-1227D01*
G03X78822Y77773I-243J318D01*
G02X78723Y80167I678J1227D01*
G03Y80833I-222J333D01*
G02X80277I777J1167D01*
G03Y80167I222J-333D01*
G02X80353Y77888I-777J-1167D01*
G03X80403Y77220I243J-318D01*
G37*
G36*
G01X1408457Y76508D02*
G02X1406582Y78504I-1157J792D01*
G03X1406729Y79037I-205J343D01*
G02X1406651Y79208I1234J666D01*
G03X1406277I-187J-70D01*
G02X1403617Y80088I-1313J492D01*
G03X1403239Y80598I-385J110D01*
G02X1404431Y82777I25J1402D01*
G03X1405097I333J222D01*
G02X1407431I1167J-777D01*
G03X1408097I333J222D01*
G02X1409588Y80636I1167J-777D01*
G03X1409300Y80126I93J-389D01*
G02X1408682Y78496I-1336J-426D01*
G03X1408535Y77963I205J-343D01*
G02X1408549Y77938I-1216J-697D01*
G03X1408911Y77950I178J91D01*
G02X1409100Y76530I1289J-551D01*
G03X1408457Y76508I-313J-248D01*
G37*
G36*
G01X6314Y78585D02*
G02X4763Y78637I-815J-1141D01*
G03X4786Y79303I-210J341D01*
G02X6337Y79251I815J1141D01*
G03X6314Y78585I210J-341D01*
G37*
G36*
G01X96484Y77755D02*
G02X93632Y77689I-1443J696D01*
G03X92932Y77695I-352J-191D01*
G02X92945Y79243I-1396J786D01*
G03X93645Y79237I352J191D01*
G02X96472Y79171I1396J-786D01*
G03X97190Y79177I358J179D01*
G02X97202Y77761I1443J-696D01*
G03X96484Y77755I-358J-179D01*
G37*
G36*
G01X764202Y79450D02*
G02X762559Y79422I-802J-1150D01*
G03X762548Y80070I-240J320D01*
G02X764191Y80098I802J1150D01*
G03X764202Y79450I240J-320D01*
G37*
G36*
G01X12726Y79724D02*
G02X10804Y79558I-862J-1230D01*
G03X10767Y80158I-282J284D01*
G02X10652Y80257I856J1111D01*
G03X10098I-277J-288D01*
G02X8520Y82532I-972J1010D01*
G03X8543Y83242I-172J361D01*
G02X8187Y83524I681J1226D01*
G03X7583Y83509I-296J-269D01*
G02X7538Y85343I-1083J891D01*
G03X8142Y85358I296J269D01*
G02X10198Y85477I1083J-891D01*
G03X10752I277J288D01*
G02X12330Y83202I972J-1010D01*
G03X12307Y82492I172J-361D01*
G02X12660Y80321I-682J-1225D01*
G03X12726Y79724I295J-269D01*
G37*
G36*
G01X1518409Y78143D02*
G02X1518368Y79500I-1247J641D01*
G03X1519067Y79521I344J204D01*
G02X1519077Y79539I1230J-672D01*
G03X1518914Y80079I-353J188D01*
G02X1520817Y80654I666J1234D01*
G03X1520980Y80114I353J-188D01*
G02X1519108Y78164I-666J-1234D01*
G03X1518409Y78143I-344J-204D01*
G37*
G36*
G01X-10313Y78490D02*
G02X-12501Y78378I-1139J818D01*
G03X-13089Y78389I-299J-266D01*
G02X-15075Y78348I-1013J969D01*
G03X-15629I-277J-288D01*
G02X-17612Y80331I-973J1010D01*
G03Y80885I-288J277D01*
G02X-15629Y82868I1010J973D01*
G03X-15075I277J288D01*
G02X-13053Y82788I973J-1010D01*
G03X-12465Y82777I299J266D01*
G02X-10342Y82665I1013J-969D01*
G03X-9701Y82676I316J244D01*
G02X-9678Y82707I1137J-820D01*
G03X-9733Y83251I-318J243D01*
G02X-7669Y85121I922J1057D01*
G03X-7026Y85109I326J232D01*
G02X-4846Y83347I1114J-852D01*
G03X-4835Y82814I304J-260D01*
G02X-4878Y80857I-1025J-956D01*
G03X-4894Y80302I280J-286D01*
G02X-6954Y78400I-1036J-944D01*
G03X-7538I-292J-273D01*
G02X-9672Y78501I-1024J958D01*
G03X-10313Y78490I-316J-244D01*
G37*
G36*
G01X733908Y81859D02*
G02X733868Y83450I-1174J766D01*
G03X734526Y83467I323J236D01*
G02X734566Y81876I1174J-766D01*
G03X733908Y81859I-323J-236D01*
G37*
G36*
G01X99998Y84565D02*
G02X98747Y83325I142J-1395D01*
G03X98122Y83698I-398J44D01*
G02X99631Y85193I-3439J4980D01*
G03X99998Y84565I327J-230D01*
G37*
G36*
G01X1574210Y83318D02*
G02X1574165Y84982I-1150J802D01*
G03X1574809Y85000I315J246D01*
G02X1574854Y83336I1150J-802D01*
G03X1574210Y83318I-315J-246D01*
G37*
G36*
G01X648982Y84439D02*
G02X646223Y84462I-1382J-239D01*
G03X645912Y84928I-393J74D01*
G02X645190Y87273I288J1372D01*
G03Y87827I-288J277D01*
G02X647367Y89577I1010J972D01*
G03X648033I333J222D01*
G02X648721Y90117I1166J-778D01*
G03X648943Y90668I-137J376D01*
G02X648914Y90733I1266J604D01*
G03X648270Y90866I-368J-157D01*
G02X646161Y91070I-966J1016D01*
G03X645628Y91181I-326J-231D01*
G02X646047Y93194I-724J1201D01*
G03X646580Y93083I326J231D01*
G02X648594Y92431I724J-1201D01*
G03X649238Y92298I368J157D01*
G02X651486Y91850I966J-1016D01*
G03X652063Y91672I366J162D01*
G02X651522Y89914I741J-1190D01*
G03X650945Y90092I-366J-162D01*
G02X650683Y89965I-739J1191D01*
G03X650461Y89414I137J-376D01*
G02X650210Y87827I-1261J-614D01*
G03Y87273I288J-277D01*
G02X649337Y84905I-1010J-973D01*
G03X648982Y84439I39J-398D01*
G37*
G36*
G01X1318622Y84134D02*
G02X1316250Y85529I-1322J466D01*
G03X1316227Y86084I-299J266D01*
G02X1316228Y88114I968J1015D01*
G03X1316252Y88669I-275J290D01*
G02X1318267Y88584I1049J931D01*
G03X1318243Y88029I275J-290D01*
G02X1318245Y86169I-1048J-931D01*
G03X1318268Y85614I299J-266D01*
G02X1318278Y85605I-933J-1047D01*
G03X1318615Y85717I140J143D01*
G02X1319222Y84334I1385J-217D01*
G03X1318622Y84134I-222J-333D01*
G37*
G36*
G01X768798Y85914D02*
G02X768120Y84453I702J-1214D01*
G03X767526Y84729I-394J-70D01*
G02X765913Y84877I-702J1214D01*
G03X765271Y84690I-260J-304D01*
G02X764841Y86166I-1341J410D01*
G03X765483Y86353I260J304D01*
G02X768204Y86190I1341J-410D01*
G03X768798Y85914I394J70D01*
G37*
G36*
G01X1758640Y84149D02*
G02X1758460Y85705I-1245J644D01*
G03X1759119Y85781I304J260D01*
G02X1759299Y84225I1245J-644D01*
G03X1758640Y84149I-304J-260D01*
G37*
G36*
G01X714182Y87090D02*
G02X712274Y86956I-882J-1090D01*
G03X712233Y87539I-293J272D01*
G02X714330Y89329I882J1090D01*
G03X715030Y89341I347J199D01*
G02X715053Y87983I1238J-658D01*
G03X714353Y87971I-347J-199D01*
G02X714141Y87673I-1239J657D01*
G03X714182Y87090I293J-272D01*
G37*
G36*
G01X707312Y87073D02*
G02X704606Y86976I-1340J-413D01*
G03X704134Y87458I-389J91D01*
G02X705211Y88514I-289J1372D01*
G03X705683Y88032I389J-91D01*
G02X705688Y88033I277J-1374D01*
G03X705989Y88542I-81J392D01*
G02X707613Y87582I1340J413D01*
G03X707312Y87073I81J-392D01*
G37*
G36*
G01X1676511Y87846D02*
G02X1676437Y86108I1062J-916D01*
G03X1675811Y86134I-323J-235D01*
G02X1675885Y87872I-1062J916D01*
G03X1676511Y87846I323J235D01*
G37*
G36*
G01X7750Y87098D02*
G02X7648Y88832I-1150J802D01*
G03X8275Y88869I299J265D01*
G02X10398Y89077I1150J-802D01*
G03X10952I277J288D01*
G02Y87057I973J-1010D01*
G03X10398I-277J-288D01*
G02X8377Y87135I-973J1010D01*
G03X7750Y87098I-299J-265D01*
G37*
G36*
G01X1312558Y92415D02*
G02X1310554Y92409I-999J-984D01*
G03X1310552Y92968I-287J278D01*
G02X1310472Y93057I1002J981D01*
G03X1310152Y93039I-153J-128D01*
G02X1308161Y94950I-1168J775D01*
G03X1308159Y95600I-234J324D01*
G02X1309794Y95606I813J1142D01*
G03X1309796Y94956I234J-324D01*
G02X1309929Y94848I-815J-1140D01*
G03X1310499Y94879I270J295D01*
G02X1312556Y92974I1052J-927D01*
G03X1312558Y92415I287J-278D01*
G37*
G36*
G01X1377332Y92806D02*
G02X1377230Y91313I1132J-827D01*
G03X1376554Y91358I-352J-190D01*
G02X1376656Y92853I-1142J829D01*
G03X1377332Y92806I353J189D01*
G37*
G36*
G01X1455416Y93465D02*
G02X1454081Y92667I-69J-1400D01*
G03X1453740Y93239I-361J172D01*
G02X1455075Y94037I69J1400D01*
G03X1455416Y93465I361J-172D01*
G37*
G36*
G01X692056Y93537D02*
G02X691687Y92008I944J-1037D01*
G03X691044Y92163I-374J-141D01*
G02X691413Y93692I-944J1037D01*
G03X692056Y93537I374J141D01*
G37*
G36*
G01X110302Y92129D02*
G02X110107Y93703I-1245J645D01*
G03X110762Y93784I300J265D01*
G02X110957Y92210I1245J-645D01*
G03X110302Y92129I-300J-265D01*
G37*
G36*
G01X733219Y93291D02*
G02X732024Y94187I-1309J-501D01*
G03X732431Y94729I33J399D01*
G02X733626Y93833I1309J501D01*
G03X733219Y93291I-33J-399D01*
G37*
G36*
G01X1296358Y95487D02*
G02X1294804I-777J-1167D01*
G03Y96153I-222J333D01*
G02X1296358I777J1167D01*
G03Y95487I222J-333D01*
G37*
G36*
G01X1693483Y93884D02*
G02X1693432Y95418I-1198J728D01*
G03X1694102Y95440I328J229D01*
G02X1696313Y95681I1198J-728D01*
G03X1696868Y95659I289J277D01*
G02X1696787Y93643I932J-1047D01*
G03X1696232Y93665I-289J-277D01*
G02X1694153Y93906I-932J1047D01*
G03X1693483Y93884I-328J-229D01*
G37*
G36*
G01X1363012Y95261D02*
G02X1360588Y96453I-1378J258D01*
G03Y96985I-298J266D01*
G02X1362680I1046J934D01*
G03Y96453I298J-266D01*
G02X1362959Y95976I-1047J-932D01*
G03X1363342Y96091I189J64D01*
G02X1363693Y95465I1358J350D01*
G03X1363012Y95261I-288J-278D01*
G37*
G36*
G01X1573433Y96756D02*
G02X1571776Y96784I-848J-1117D01*
G03X1571787Y97429I-231J327D01*
G02X1573444Y97401I848J1117D01*
G03X1573433Y96756I231J-327D01*
G37*
G36*
G01X1746712Y97034D02*
G02X1745151Y95238I-221J-1384D01*
G03X1744487Y95404I-382J-118D01*
G02X1743575Y97800I-987J996D01*
G03X1743989Y98277I22J399D01*
G02X1746462Y97678I1375J273D01*
G03X1746712Y97034I313J-249D01*
G37*
G36*
G01X1289548Y96543D02*
G02Y98097I-1167J777D01*
G03X1290214I333J222D01*
G02Y96543I1167J-777D01*
G03X1289548I-333J-222D01*
G37*
G36*
G01X1945567Y98870D02*
G02X1945553Y97453I1203J-720D01*
G03X1944863Y97460I-347J-199D01*
G02X1944877Y98877I-1203J720D01*
G03X1945567Y98870I347J199D01*
G37*
G36*
G01X1723995Y99775D02*
G02X1722633I-681J-1225D01*
G03Y100475I-194J350D01*
G02Y102925I681J1225D01*
G03Y103625I-194J350D01*
G02X1722089Y104169I681J1225D01*
G03X1721389I-350J-194D01*
G02X1718939I-1225J681D01*
G03X1718239I-350J-194D01*
G02Y105531I-1225J681D01*
G03X1718939I350J194D01*
G02X1719483Y106075I1225J-681D01*
G03Y106775I-194J350D01*
G02X1721389Y108681I681J1225D01*
G03X1722089I350J194D01*
G02X1723995Y106775I1225J-681D01*
G03Y106075I194J-350D01*
G02Y103625I-681J-1225D01*
G03Y102925I194J-350D01*
G02Y100475I-681J-1225D01*
G03Y99775I194J-350D01*
G37*
G36*
G01X1736595Y102925D02*
G02X1735233I-681J-1225D01*
G03Y103625I-194J350D01*
G02Y106075I681J1225D01*
G03Y106775I-194J350D01*
G02X1736595I681J1225D01*
G03Y106075I194J-350D01*
G02Y103625I-681J-1225D01*
G03Y102925I194J-350D01*
G37*
G36*
G01X1269667Y101323D02*
G02X1267570Y103149I-1167J777D01*
G03X1267592Y103726I-266J299D01*
G02X1269724Y105538I1008J975D01*
G03X1270366I321J239D01*
G02X1272465Y103692I1124J-839D01*
G03X1272467Y103115I278J-288D01*
G02X1270333Y101323I-967J-1015D01*
G03X1269667I-333J-222D01*
G37*
G36*
G01X1875618Y103538D02*
G02X1874255Y104598I-1360J-342D01*
G03X1874641Y105096I-2J400D01*
G02X1876004Y104036I1360J342D01*
G03X1875618Y103538I2J-400D01*
G37*
G36*
G01X74915Y103760D02*
G02Y106240I-2115J1240D01*
G03X75606I346J202D01*
G02X79837Y106239I2115J-1240D01*
G03X80527I345J202D01*
G02X84758Y106240I2116J-1239D01*
G03X85449I345J202D01*
G02X89679I2115J-1240D01*
G03X90370I346J202D01*
G02X94600I2115J-1240D01*
G03X95291I345J202D01*
G02X99522Y106239I2115J-1240D01*
G03X100212I345J202D01*
G02X104443Y106240I2116J-1239D01*
G03X105134I345J202D01*
G02Y103760I2115J-1240D01*
G03X104443I-345J-202D01*
G02X100212Y103761I-2115J1240D01*
G03X99522I-345J-202D01*
G02X95291Y103760I-2116J1239D01*
G03X94600I-345J-202D01*
G02X90370I-2115J1240D01*
G03X89679I-345J-202D01*
G02X85449I-2115J1240D01*
G03X84758I-345J-202D01*
G02X80527Y103761I-2115J1240D01*
G03X79837I-345J-202D01*
G02X75606Y103760I-2116J1239D01*
G03X74915I-345J-202D01*
G37*
G36*
G01X1345919Y105559D02*
G02X1344470Y105798I-919J-1059D01*
G03X1344581Y106470I-151J370D01*
G02X1346030Y106231I919J1059D01*
G03X1345919Y105559I151J-370D01*
G37*
G36*
G01X121118Y107644D02*
G02X119537Y107824I-921J-1057D01*
G03X119612Y108478I-188J353D01*
G02X121193Y108298I921J1057D01*
G03X121118Y107644I188J-353D01*
G37*
G36*
G01X1392517Y107705D02*
G02X1392488Y109327I-1158J791D01*
G03X1393140Y109339I322J237D01*
G02X1393502Y109702I1157J-792D01*
G03X1393504Y110359I-227J329D01*
G02X1395106Y110352I806J1147D01*
G03X1395104Y109695I227J-329D01*
G02X1393169Y107717I-806J-1147D01*
G03X1392517Y107705I-322J-237D01*
G37*
G36*
G01X1452447Y110885D02*
G02X1451038Y110235I-215J-1385D01*
G03X1450758Y110840I-341J210D01*
G02X1452167Y111490I215J1385D01*
G03X1452447Y110885I341J-210D01*
G37*
G36*
G01X1512424Y120143D02*
G02X1515446Y120153I1511J0D01*
G01Y116258D01*
X1515437Y116174D01*
G02X1514779Y115089I-1502J169D01*
G03X1514753Y114445I224J-332D01*
G02X1513046Y114477I-874J-1096D01*
G03X1513044Y115122I-237J322D01*
G02X1512424Y116343I892J1221D01*
G01Y120143D01*
G37*
G36*
G01X1258565Y115056D02*
G02X1257135I-715J-1206D01*
G03Y115744I-204J344D01*
G02X1258565I715J1206D01*
G03Y115056I204J-344D01*
G37*
G36*
G01X619388Y115330D02*
G02X618655Y114188I666J-1234D01*
G03X618066Y114566I-399J26D01*
G02X618799Y115708I-666J1234D01*
G03X619388Y115330I399J-26D01*
G37*
G36*
G01X1286893Y117099D02*
G02X1285339I-777J-1167D01*
G03Y117765I-222J333D01*
G02X1286893I777J1167D01*
G03Y117099I222J-333D01*
G37*
G36*
G01X1398444Y117893D02*
G02X1397340Y117114I156J-1393D01*
G03X1396936Y117687I-360J175D01*
G02X1398040Y118466I-156J1393D01*
G03X1398444Y117893I360J-175D01*
G37*
G36*
G01X1727145Y118675D02*
G02X1725783I-681J-1225D01*
G03Y119375I-194J350D01*
G02X1725238Y119919I680J1226D01*
G03X1724539I-350J-194D01*
G02X1722632Y121826I-1225J682D01*
G03Y122525I-194J350D01*
G02X1722089Y123069I683J1224D01*
G03X1721389I-350J-194D01*
G02Y124431I-1225J681D01*
G03X1722089I350J194D01*
G02X1722633Y124975I1225J-681D01*
G03Y125675I-194J350D01*
G02Y128125I681J1225D01*
G03Y128825I-194J350D01*
G02Y131275I681J1225D01*
G03Y131975I-194J350D01*
G02X1724539Y133881I681J1225D01*
G03X1725239I350J194D01*
G02Y132519I1225J-681D01*
G03X1724539I-350J-194D01*
G02X1723995Y131975I-1225J681D01*
G03Y131275I194J-350D01*
G02Y128825I-681J-1225D01*
G03Y128125I194J-350D01*
G02Y125675I-681J-1225D01*
G03Y124975I194J-350D01*
G02X1724539Y124431I-681J-1225D01*
G03X1725239I350J194D01*
G02X1727145Y122525I1225J-681D01*
G03Y121825I194J-350D01*
G02Y119375I-681J-1225D01*
G03Y118675I194J-350D01*
G37*
G36*
G01X1737139Y116769D02*
G02Y118131I-1225J681D01*
G03X1737839I350J194D01*
G02X1738383Y118675I1225J-681D01*
G03Y119375I-194J350D01*
G02Y121825I681J1225D01*
G03Y122525I-194J350D01*
G02X1737838Y123070I681J1226D01*
G03X1737138I-350J-194D01*
G02Y124430I-1226J680D01*
G03X1737838I350J194D01*
G02X1738383Y124975I1226J-681D01*
G03Y125675I-194J350D01*
G02Y128125I681J1225D01*
G03Y128825I-194J350D01*
G02X1740289Y130731I681J1225D01*
G03X1740989I350J194D01*
G02Y129369I1225J-681D01*
G03X1740289I-350J-194D01*
G02X1739745Y128825I-1225J681D01*
G03Y128125I194J-350D01*
G02Y125675I-681J-1225D01*
G03Y124975I194J-350D01*
G02X1740289Y124431I-681J-1225D01*
G03X1740989I350J194D01*
G02X1743439I1225J-681D01*
G03X1744139I350J194D01*
G02Y123069I1225J-681D01*
G03X1743439I-350J-194D01*
G02X1742895Y122525I-1225J681D01*
G03Y121825I194J-350D01*
G02X1740989Y119919I-681J-1225D01*
G03X1740289I-350J-194D01*
G02X1739745Y119375I-1225J681D01*
G03Y118675I194J-350D01*
G02X1737839Y116769I-681J-1225D01*
G03X1737139I-350J-194D01*
G37*
G36*
G01X1677567Y121263D02*
G02X1676205I-681J-1225D01*
G03Y121963I-194J350D01*
G02X1677567I681J1225D01*
G03Y121263I194J-350D01*
G37*
G36*
G01X1554838Y121420D02*
G02X1554273Y122169I-1337J-421D01*
G03X1554545Y122454I111J167D01*
G02X1554398Y122705I1130J830D01*
G03X1553883Y122911I-364J-164D01*
G02X1554631Y124787I-530J1298D01*
G03X1555146Y124581I364J164D01*
G02X1556219Y124576I530J-1298D01*
G03X1556757Y124830I155J369D01*
G02X1557557Y123134I1343J-403D01*
G03X1557019Y122880I-155J-369D01*
G02X1555321Y121927I-1343J403D01*
G03X1554838Y121420I-102J-387D01*
G37*
G36*
G01X1928184Y121747D02*
G02X1926314Y122480I-1292J-544D01*
G03X1926518Y123000I-165J365D01*
G02X1926888Y124600I1292J544D01*
G03X1926912Y125180I-263J301D01*
G02X1927962Y127557I1006J976D01*
G03X1928366Y128041I13J400D01*
G02X1928815Y129394I1370J296D01*
G03X1928820Y129994I-262J302D01*
G02X1930677Y129980I936J1043D01*
G03X1930672Y129380I262J-302D01*
G02X1929692Y126936I-936J-1043D01*
G03X1929288Y126452I-13J-400D01*
G02X1928840Y125100I-1370J-296D01*
G03X1928816Y124520I263J-301D01*
G02X1928388Y122267I-1006J-976D01*
G03X1928184Y121747I165J-365D01*
G37*
G36*
G01X1401422Y122341D02*
G02X1399879Y122837I-1122J-841D01*
G03X1400078Y123459I-121J381D01*
G02X1399817Y124532I1122J841D01*
G03X1399418Y124998I-394J66D01*
G02X1400783Y126168I-18J1402D01*
G03X1401182Y125702I394J-66D01*
G02X1401621Y122963I18J-1402D01*
G03X1401422Y122341I121J-381D01*
G37*
G36*
G01X1392867Y122173D02*
G02X1390923Y124117I-1167J777D01*
G03Y124783I-222J333D01*
G02Y127117I777J1167D01*
G03Y127783I-222J333D01*
G02X1392867Y129727I777J1167D01*
G03X1393533I333J222D01*
G02X1395477Y127783I1167J-777D01*
G03Y127117I222J-333D01*
G02Y124783I-777J-1167D01*
G03Y124117I222J-333D01*
G02X1393533Y122173I-777J-1167D01*
G03X1392867I-333J-222D01*
G37*
G36*
G01X1525319Y122826D02*
G02X1524803Y124449I-1319J474D01*
G03X1525409Y124642I229J328D01*
G02X1525925Y123019I1319J-474D01*
G03X1525319Y122826I-229J-328D01*
G37*
G36*
G01X3938Y126754D02*
G03X5205Y127157I-2J2199D01*
G02X9264Y125823I1488J-2314D01*
G03X10004Y125805I374J143D01*
G02Y123881I2201J-962D01*
G03X9264Y123863I-366J-161D01*
G02X5221Y122519I-2571J980D01*
G03X3967Y122932I-1283J-1786D01*
G01X3936D01*
G03X2669Y122529I2J-2199D01*
G02X2653Y127167I-1488J2314D01*
G03X3907Y126754I1283J1786D01*
G01X3938D01*
G37*
G36*
G01X1864351Y125131D02*
G02X1864331Y123808I1226J-680D01*
G03X1863626Y123819I-355J-183D01*
G02X1863646Y125142I-1226J680D01*
G03X1864351Y125131I355J183D01*
G37*
G36*
G01X1643312Y124259D02*
G02Y125621I-1225J681D01*
G03X1644012I350J194D01*
G02Y124259I1225J-681D01*
G03X1643312I-350J-194D01*
G37*
G36*
G01X1857797Y127786D02*
G02X1856243I-777J-1167D01*
G03Y128452I-222J333D01*
G02X1857797I777J1167D01*
G03Y127786I222J-333D01*
G37*
G36*
G01X1513634Y127666D02*
G02X1513388Y125945I966J-1016D01*
G03X1512766Y126034I-346J-201D01*
G02X1513012Y127755I-966J1016D01*
G03X1513634Y127666I346J201D01*
G37*
G36*
G01X111501Y129578D02*
G02X111460Y128077I1163J-783D01*
G03X110785Y128096I-344J-205D01*
G02X110826Y129597I-1163J783D01*
G03X111501Y129578I344J205D01*
G37*
G36*
G01X1473905Y130098D02*
G02X1472295I-805J-1148D01*
G03Y130752I-230J327D01*
G02X1473905I805J1148D01*
G03Y130098I230J-327D01*
G37*
G36*
G01X1678067Y130863D02*
G02X1676705I-681J-1225D01*
G03Y131563I-194J350D01*
G02X1678067I681J1225D01*
G03Y130863I194J-350D01*
G37*
G36*
G01X1861800Y131977D02*
G02X1860194Y131952I-785J-1162D01*
G03X1860184Y132607I-234J324D01*
G02X1859998Y134780I785J1162D01*
G03Y135358I-277J289D01*
G02X1861940I971J1011D01*
G03Y134780I277J-289D01*
G02X1861790Y132632I-971J-1011D01*
G03X1861800Y131977I234J-324D01*
G37*
G36*
G01X1608070Y132487D02*
G02X1606565Y132587I-831J-1129D01*
G03X1606610Y133260I-192J351D01*
G02X1606216Y133707I831J1129D01*
G03X1605517I-349J-195D01*
G02X1603611Y135613I-1225J681D01*
G03Y136313I-194J350D01*
G02X1605517Y138220I681J1225D01*
G03X1606216I350J194D01*
G02X1608666Y138219I1225J-682D01*
G03X1609366I350J194D01*
G02X1609910Y138763I1225J-681D01*
G03Y139463I-194J350D01*
G02X1609894Y141905I681J1226D01*
G03X1609906Y142592I-199J347D01*
G02X1611342Y142566I740J1191D01*
G03X1611330Y141879I199J-347D01*
G02X1611816Y141369I-739J-1191D01*
G03X1612516I350J194D01*
G02X1614422Y139463I1225J-681D01*
G03Y138763I194J-350D01*
G02X1614423Y136313I-681J-1225D01*
G03Y135614I194J-350D01*
G02X1612516Y133708I-682J-1225D01*
G03X1611816I-350J-194D01*
G02X1609366I-1225J681D01*
G03X1608666I-350J-194D01*
G02X1608115Y133160I-1225J681D01*
G03X1608070Y132487I192J-351D01*
G37*
G36*
G01X1746868Y132851D02*
G02X1745510I-679J-1227D01*
G03Y133550I-194J350D01*
G02X1746868I679J1227D01*
G03Y132851I194J-350D01*
G37*
G36*
G01X1531353Y133302D02*
G02X1530076Y134073I-1252J-631D01*
G03X1530426Y134653I-7J400D01*
G02X1530308Y135583I1252J631D01*
G03X1529813Y136054I-391J85D01*
G02X1530819Y137109I-364J1354D01*
G03X1531314Y136638I391J-85D01*
G02X1531703Y133882I364J-1354D01*
G03X1531353Y133302I7J-400D01*
G37*
G36*
G01X1324193Y132546D02*
G02Y134100I-1167J777D01*
G03X1324859I333J222D01*
G02Y132546I1167J-777D01*
G03X1324193I-333J-222D01*
G37*
G36*
G01X1262697Y134362D02*
G02X1262517Y132923I1101J-868D01*
G03X1261838Y133008I-365J-163D01*
G02X1262018Y134447I-1101J868D01*
G03X1262697Y134362I365J163D01*
G37*
G36*
G01X1621265Y133707D02*
G02Y135069I-1225J681D01*
G03X1621965I350J194D01*
G02Y133707I1225J-681D01*
G03X1621265I-350J-194D01*
G37*
G36*
G01X1590927Y135783D02*
G02X1588569Y134355I-1047J-932D01*
G03X1588067Y134592I-374J-142D01*
G02X1588931Y136417I-447J1329D01*
G03X1589433Y136180I374J142D01*
G02X1589549Y136213I441J-1331D01*
G03X1589753Y136868I-95J389D01*
G02X1591850Y138729I1047J932D01*
G03X1592450I300J265D01*
G02Y136871I1050J-929D01*
G03X1591850I-300J-265D01*
G02X1591131Y136438I-1050J929D01*
G03X1590927Y135783I95J-389D01*
G37*
G36*
G01X1695917Y137013D02*
G02X1694555I-681J-1225D01*
G03Y137713I-194J350D01*
G02X1695917I681J1225D01*
G03Y137013I194J-350D01*
G37*
G36*
G01X1739745Y137575D02*
G02X1738383I-681J-1225D01*
G03Y138275I-194J350D01*
G02X1737839Y138819I681J1225D01*
G03X1737139I-350J-194D01*
G02Y140181I-1225J681D01*
G03X1737839I350J194D01*
G02X1738383Y140725I1225J-681D01*
G03Y141425I-194J350D01*
G02Y143875I681J1225D01*
G03Y144575I-194J350D01*
G02X1740289Y146481I681J1225D01*
G03X1740989I350J194D01*
G02X1742895Y144575I1225J-681D01*
G03Y143875I194J-350D01*
G02X1743439Y143331I-681J-1225D01*
G03X1744139I350J194D01*
G02Y141969I1225J-681D01*
G03X1743439I-350J-194D01*
G02X1740989I-1225J681D01*
G03X1740289I-350J-194D01*
G02X1739745Y141425I-1225J681D01*
G03Y140725I194J-350D01*
G02Y138275I-681J-1225D01*
G03Y137575I194J-350D01*
G37*
G36*
G01X1568792Y137816D02*
G02X1567154Y137824I-825J-1134D01*
G03X1567157Y138473I-232J326D01*
G02X1568795Y138465I825J1134D01*
G03X1568792Y137816I232J-326D01*
G37*
G36*
G01X1513514Y139046D02*
G02X1513185Y137327I911J-1065D01*
G03X1512571Y137444I-354J-187D01*
G02X1512900Y139163I-911J1065D01*
G03X1513514Y139046I354J187D01*
G37*
G36*
G01X1721389Y138819D02*
G02Y140181I-1225J681D01*
G03X1722089I350J194D01*
G02X1722633Y140725I1225J-681D01*
G03Y141425I-194J350D01*
G02X1722650Y143885I681J1225D01*
G03X1722639Y144595I-190J352D01*
G02X1722070Y145116I626J1255D01*
G03X1721381Y145105I-341J-209D01*
G02X1721358Y146534I-1217J695D01*
G03X1722047Y146545I341J209D01*
G02X1724519Y146475I1217J-695D01*
G03X1725229Y146464I358J179D01*
G02X1725209Y145175I1235J-664D01*
G03X1724499Y145186I-358J-179D01*
G02X1723928Y144615I-1235J664D01*
G03X1723939Y143905I190J-352D01*
G02X1723995Y141425I-625J-1255D01*
G03Y140725I194J-350D01*
G02X1722089Y138819I-681J-1225D01*
G03X1721389I-350J-194D01*
G37*
G36*
G01X1621265Y140006D02*
G02Y141368I-1225J681D01*
G03X1621965I350J194D01*
G02Y140006I1225J-681D01*
G03X1621265I-350J-194D01*
G37*
G36*
G01X1952235Y142296D02*
G02X1950569Y141828I-535J-1296D01*
G03X1950399Y142434I-323J236D01*
G02X1952065Y142902I535J1296D01*
G03X1952235Y142296I323J-236D01*
G37*
G36*
G01X1240805Y142936D02*
G02X1239229Y142929I-783J-1163D01*
G03X1239227Y143591I-226J330D01*
G02X1240803Y143598I783J1163D01*
G03X1240805Y142936I226J-330D01*
G37*
G36*
G01X1822623Y142854D02*
G02X1822532Y144188I-1275J583D01*
G03X1823234Y144236I338J214D01*
G02X1823325Y142902I1275J-583D01*
G03X1822623Y142854I-338J-214D01*
G37*
G36*
G01X1608134Y145056D02*
G02X1606717Y145038I-693J-1219D01*
G03X1606708Y145728I-206J342D01*
G02X1608634Y147615I693J1219D01*
G03X1609342Y147624I352J190D01*
G02X1609910Y148212I1248J-638D01*
G03Y148912I-194J350D01*
G02X1609909Y151362I681J1225D01*
G03Y152061I-194J350D01*
G02X1609366Y152605I683J1224D01*
G03X1608666I-350J-194D01*
G02X1606760Y154511I-1225J681D01*
G03Y155211I-194J350D01*
G02Y157661I681J1225D01*
G03Y158360I-195J350D01*
G02Y160810I682J1225D01*
G03Y161509I-194J350D01*
G02X1608666Y163416I681J1226D01*
G03X1609366I350J194D01*
G02X1609910Y163960I1225J-681D01*
G03Y164660I-194J350D01*
G02X1611816Y166566I681J1225D01*
G03X1612516I350J194D01*
G02X1614966I1225J-681D01*
G03X1615666I350J194D01*
G02X1618116I1225J-681D01*
G03X1618816I350J194D01*
G02X1619294Y167071I1225J-681D01*
G03X1619286Y167753I-213J339D01*
G02X1620753Y167770I720J1203D01*
G03X1620761Y167088I213J-339D01*
G02X1618816Y165204I-720J-1203D01*
G03X1618116I-350J-194D01*
G02X1617572Y164659I-1226J680D01*
G03Y163960I194J-350D01*
G02X1617571Y161510I-682J-1225D01*
G03Y160810I194J-350D01*
G02X1618115Y160266I-681J-1225D01*
G03X1618815I350J194D01*
G02X1621265Y160267I1225J-681D01*
G03X1621964I350J194D01*
G02X1622452Y160778I1225J-682D01*
G03X1622465Y161449I-211J340D01*
G02X1622606Y163856I785J1162D01*
G03X1622611Y164564I-184J355D01*
G02X1624447Y166569I665J1234D01*
G03X1625127Y166588I334J220D01*
G02X1627564Y166565I1212J-704D01*
G03X1628264I350J194D01*
G02X1630171Y164659I1225J-681D01*
G03Y163960I194J-350D01*
G02X1630170Y161510I-682J-1225D01*
G03Y160810I194J-350D01*
G02X1628264Y158904I-681J-1225D01*
G03X1627564I-350J-194D01*
G02X1625114I-1225J681D01*
G03X1624414I-350J-194D01*
G02X1621964Y158903I-1225J681D01*
G03X1621265I-349J-194D01*
G02X1618815Y158904I-1225J682D01*
G03X1618115I-350J-194D01*
G02X1615665Y158903I-1225J681D01*
G03X1614966I-349J-194D01*
G02X1614423Y158360I-1225J682D01*
G03Y157661I194J-349D01*
G02X1614422Y155211I-682J-1225D01*
G03Y154511I194J-350D01*
G02X1614423Y152061I-681J-1225D01*
G03Y151362I194J-350D01*
G02X1614966Y150818I-683J-1224D01*
G03X1615666I350J194D01*
G02Y149456I1225J-681D01*
G03X1614966I-350J-194D01*
G02X1614422Y148912I-1225J681D01*
G03Y148212I194J-350D01*
G02X1612516Y146306I-681J-1225D01*
G03X1611816I-350J-194D01*
G02X1609358Y146319I-1225J681D01*
G03X1608650Y146310I-352J-190D01*
G02X1608125Y145746I-1249J637D01*
G03X1608134Y145056I206J-342D01*
G37*
G36*
G01X1937365Y144773D02*
G02X1935661Y145312I-1178J-760D01*
G03X1935828Y145926I-151J371D01*
G02X1935705Y146112I1272J975D01*
G03X1935056Y146178I-348J-197D01*
G02X1935166Y147879I-1056J922D01*
G03X1935818Y147861I332J222D01*
G02X1937581Y145372I1282J-961D01*
G03X1937365Y144773I120J-382D01*
G37*
G36*
G01X1621265Y146306D02*
G02Y147668I-1225J681D01*
G03X1621965I350J194D01*
G02Y146306I1225J-681D01*
G03X1621265I-350J-194D01*
G37*
G36*
G01X1600850Y149794D02*
G02X1599487Y149780I-669J-1232D01*
G03X1599480Y150479I-198J348D01*
G02X1600843Y150493I669J1232D01*
G03X1600850Y149794I198J-348D01*
G37*
G36*
G01X1595532Y149735D02*
G02X1594240Y150084I-967J-1015D01*
G03X1594423Y150763I-93J389D01*
G02X1595715Y150414I967J1015D01*
G03X1595532Y149735I93J-389D01*
G37*
G36*
G01X1715242Y148118D02*
G02Y149782I-1128J832D01*
G03X1715886I322J238D01*
G02Y148118I1128J-832D01*
G03X1715242I-322J-238D01*
G37*
G36*
G01X1542460Y150283D02*
G02X1540828Y150010I-629J-1253D01*
G03X1540722Y150647I-286J280D01*
G02X1542354Y150920I629J1253D01*
G03X1542460Y150283I286J-280D01*
G37*
G36*
G01X1914684Y148614D02*
G02X1914504Y150391I-1292J767D01*
G03X1915135Y150441I296J269D01*
G02X1917581Y150267I1175J-765D01*
G03X1918286Y150228I363J169D01*
G02X1918213Y148909I1198J-728D01*
G03X1917508Y148948I-363J-169D01*
G02X1915312Y148691I-1198J728D01*
G03X1914684Y148614I-284J-281D01*
G37*
G36*
G01X1578563Y150675D02*
G02X1577117Y150760I-793J-1156D01*
G03X1577157Y151444I-186J354D01*
G02X1576957Y153590I793J1156D01*
G03X1576901Y154201I-283J282D01*
G02X1578693Y154363I799J1152D01*
G03X1578749Y153752I283J-282D01*
G02X1578603Y151359I-799J-1152D01*
G03X1578563Y150675I186J-354D01*
G37*
G36*
G01X1829274Y151006D02*
G02X1827889Y151287I-933J-1046D01*
G03X1828026Y151964I-129J379D01*
G02X1829411Y151683I933J1046D01*
G03X1829274Y151006I129J-379D01*
G37*
G36*
G01X1626991Y151377D02*
G02X1625666Y151366I-652J-1241D01*
G03X1625661Y152071I-192J351D01*
G02X1625150Y152530I653J1241D01*
G03X1624459Y152482I-332J-224D01*
G02X1621948Y152468I-1259J618D01*
G03X1621260Y152513I-357J-180D01*
G02X1620815Y152094I-1160J787D01*
G03Y151406I204J-344D01*
G02X1619385I-715J-1206D01*
G03Y152094I-204J344D01*
G02X1621352Y153932I715J1206D01*
G03X1622040Y153887I357J180D01*
G02X1624363Y153882I1160J-787D01*
G03X1625054Y153930I332J224D01*
G02X1627554Y153964I1259J-618D01*
G03X1628259Y153959I354J187D01*
G02X1630714Y153968I1230J-673D01*
G03X1631413I350J194D01*
G02X1633863Y153967I1225J-682D01*
G03X1634563I350J194D01*
G02Y152605I1225J-681D01*
G03X1633863I-350J-194D01*
G02X1631413Y152604I-1225J681D01*
G03X1630714I-349J-194D01*
G02X1628248Y152634I-1225J682D01*
G03X1627543Y152639I-354J-187D01*
G02X1626986Y152082I-1230J673D01*
G03X1626991Y151377I192J-351D01*
G37*
G36*
G01X1655367Y151363D02*
G02X1654005I-681J-1225D01*
G03Y152063I-194J350D01*
G02X1654003Y154513I681J1226D01*
G03Y155211I-194J349D01*
G02X1653461Y155754I684J1224D01*
G03X1652762I-349J-194D01*
G02X1650311I-1225J681D01*
G03X1649611I-350J-194D01*
G02X1649066Y155209I-1226J681D01*
G03X1649068Y154509I194J-349D01*
G02X1647713Y154506I-675J-1229D01*
G03X1647711Y155206I-194J349D01*
G02X1647705Y157661I675J1229D01*
G03Y158360I-194J350D01*
G02X1647162Y158904I683J1224D01*
G03X1646462I-350J-194D01*
G02X1644012I-1225J681D01*
G03X1643312I-350J-194D01*
G02X1640862Y158903I-1225J681D01*
G03X1640163I-349J-194D01*
G02X1637713Y158904I-1225J682D01*
G03X1637013I-350J-194D01*
G02X1635107Y160810I-1225J681D01*
G03Y161510I-194J350D01*
G02Y163960I681J1225D01*
G03Y164660I-194J350D01*
G02X1637014Y166566I681J1225D01*
G03X1637713I350J194D01*
G02X1640163I1225J-682D01*
G03X1640862I350J194D01*
G02X1643313I1225J-681D01*
G03X1644012I349J195D01*
G02X1646462I1225J-682D01*
G03X1647161I350J195D01*
G02X1649612I1225J-681D01*
G03X1650311I350J194D01*
G02X1652218Y164659I1225J-682D01*
G03Y163960I194J-350D01*
G02X1652761Y163417I-682J-1225D01*
G03X1653460I350J194D01*
G02X1655910Y163416I1225J-682D01*
G03X1656610I350J194D01*
G02X1657153Y163960I1226J-680D01*
G03Y164659I-194J350D01*
G02X1659060Y166566I682J1225D01*
G03X1659759I350J194D01*
G02X1661666Y164660I1226J-681D01*
G03Y163960I194J-350D01*
G02Y161510I-681J-1225D01*
G03Y160810I194J-350D01*
G02Y158360I-681J-1225D01*
G03Y157660I194J-350D01*
G02X1662210Y157117I-680J-1226D01*
G03X1662909I350J195D01*
G02X1664816Y155211I1225J-681D01*
G03Y154512I194J-349D01*
G02X1663453Y154511I-681J-1226D01*
G03Y155210I-194J350D01*
G02X1662909Y155754I681J1225D01*
G03X1662210I-350J-195D01*
G02X1659759I-1225J681D01*
G03X1659060I-349J-194D01*
G02X1658518Y155212I-1225J683D01*
G03Y154513I195J-349D01*
G02X1656611Y152607I-682J-1225D01*
G03X1655911I-350J-194D01*
G02X1655367Y152063I-1225J681D01*
G03Y151363I194J-350D01*
G37*
G36*
G01X1906106Y151138D02*
G02X1904426Y151404I-1014J-968D01*
G03X1904526Y152032I-190J352D01*
G02X1906206Y151766I1014J968D01*
G03X1906106Y151138I190J-352D01*
G37*
G36*
G01X1493400Y154196D02*
G02X1491916Y153632I-331J-1362D01*
G03X1491682Y154248I-329J227D01*
G02X1493166Y154812I331J1362D01*
G03X1493400Y154196I329J-227D01*
G37*
G36*
G01X1263621Y155695D02*
G02X1263522Y154039I1079J-895D01*
G03X1262879Y154078I-336J-217D01*
G02X1262978Y155734I-1079J895D01*
G03X1263621Y155695I336J217D01*
G37*
G36*
G01X1808218Y163430D02*
G02X1806662I-778J-1400D01*
G03Y164130I-194J350D01*
G02Y166930I778J1400D01*
G03Y167630I-194J350D01*
G02X1808218I778J1400D01*
G03Y166930I194J-350D01*
G02Y164130I-778J-1400D01*
G03Y163430I194J-350D01*
G37*
G36*
G01X-14373Y161787D02*
G02X-14902Y163024I-1395J135D01*
G03X-14256Y163300I248J315D01*
G02X-13727Y162063I1395J-135D01*
G03X-14373Y161787I-248J-315D01*
G37*
G36*
G01X1455114Y164296D02*
G02X1453485Y164634I-1044J-936D01*
G03X1453616Y165264I-167J363D01*
G02X1455245Y164926I1044J936D01*
G03X1455114Y164296I167J-363D01*
G37*
G36*
G01X1929290Y171119D02*
G02X1929132Y169372I1010J-972D01*
G03X1928510Y169428I-333J-221D01*
G02X1928668Y171175I-1010J972D01*
G03X1929290Y171119I333J221D01*
G37*
G36*
G01X1452032Y171551D02*
G02X1450714Y171560I-667J-1233D01*
G03X1450719Y172266I-185J354D01*
G02X1450374Y174469I667J1233D01*
G03X1450369Y175027I-289J276D01*
G02X1450089Y176595I996J987D01*
G03X1449904Y177118I-364J165D01*
G02X1451808Y177791I628J1254D01*
G03X1451993Y177268I364J-165D01*
G02X1452377Y175044I-628J-1254D01*
G03X1452382Y174486I289J-276D01*
G02X1452037Y172257I-996J-987D01*
G03X1452032Y171551I185J-354D01*
G37*
G36*
G01X1675688Y171990D02*
G02X1675669Y173359I-1233J668D01*
G03X1676367Y173368I346J200D01*
G02X1676386Y171999I1233J-668D01*
G03X1675688Y171990I-346J-200D01*
G37*
G36*
G01X1623864Y173803D02*
G02X1623715Y172303I1102J-867D01*
G03X1623044Y172370I-357J-180D01*
G02X1623193Y173870I-1102J867D01*
G03X1623864Y173803I357J180D01*
G37*
G36*
G01X1929349Y174614D02*
G02X1927318Y176518I-1131J829D01*
G03X1927325Y177125I-257J307D01*
G02X1929149Y177104I924J1054D01*
G03X1929142Y176497I257J-307D01*
G02X1929302Y176332I-923J-1055D01*
G03X1929934Y176349I309J253D01*
G02X1930489Y176798I1130J-830D01*
G03X1930617Y177437I-164J365D01*
G02X1932215Y177118I1022J959D01*
G03X1932087Y176479I164J-365D01*
G02X1929981Y174631I-1022J-959D01*
G03X1929349Y174614I-309J-253D01*
G37*
G36*
G01X1720013Y177316D02*
G02X1718316Y177397I-913J-1316D01*
G03X1718371Y178058I-195J349D01*
G02X1720021Y177979I879J1092D01*
G03X1720013Y177316I220J-334D01*
G37*
G36*
G01X1752390Y178036D02*
X1757391D01*
G02X1758902Y176535I0J-1512D01*
G01Y176440D01*
X1758892Y176356D01*
G02X1757390Y175014I-1502J169D01*
G01X1752390D01*
G02X1751337Y175442I1J1511D01*
G03X1750706Y175345I-279J-287D01*
G02X1750451Y177213I-1411J759D01*
G03X1751086Y177288I289J276D01*
G02X1752390Y178036I1304J-763D01*
G37*
G36*
G01X1884675Y177325D02*
G02X1883084Y177255I-745J-1188D01*
G03X1883055Y177912I-242J318D01*
G02X1884957Y179892I745J1188D01*
G03X1885534Y179803I330J226D01*
G02X1885243Y177908I866J-1103D01*
G03X1884666Y177997I-330J-226D01*
G02X1884646Y177982I-851J1114D01*
G03X1884675Y177325I242J-318D01*
G37*
G36*
G01X63421Y177506D02*
G02X62786Y176279I766J-1174D01*
G03X62168Y176599I-400J-15D01*
G02X62803Y177826I-766J1174D01*
G03X63421Y177506I400J15D01*
G37*
G36*
G01X1489739Y177922D02*
G02X1488381Y177890I-650J-1242D01*
G03X1488364Y178590I-202J345D01*
G02X1489722Y178622I650J1242D01*
G03X1489739Y177922I202J-345D01*
G37*
G36*
G01X1227947Y178203D02*
G02X1226003Y180147I-1167J777D01*
G03Y180813I-222J333D01*
G02X1225919Y183086I777J1167D01*
G03X1225948Y183692I-246J315D01*
G02X1227775Y183602I966J1016D01*
G03X1227746Y182996I246J-315D01*
G02X1227947Y182757I-966J-1016D01*
G03X1228613I333J222D01*
G02X1230947I1167J-777D01*
G03X1231613I333J222D01*
G02X1233557Y180813I1167J-777D01*
G03Y180147I222J-333D01*
G02X1231613Y178203I-777J-1167D01*
G03X1230947I-333J-222D01*
G02X1228613I-1167J777D01*
G03X1227947I-333J-222D01*
G37*
G36*
G01X1597025Y179619D02*
G02Y180981I-1225J681D01*
G03X1597725I350J194D01*
G02Y179619I1225J-681D01*
G03X1597025I-350J-194D01*
G37*
G36*
G01X1855682Y182846D02*
G02X1854144Y182808I-740J-1191D01*
G03X1854128Y183476I-228J329D01*
G02X1855666Y183514I740J1191D01*
G03X1855682Y182846I228J-329D01*
G37*
G36*
G01X87704Y182904D02*
G02X86355Y182989I-752J-1183D01*
G03X86399Y183689I-170J362D01*
G02X87748Y183604I752J1183D01*
G03X87704Y182904I170J-362D01*
G37*
G36*
G01X767754Y183850D02*
G02X765216Y182837I-1386J-214D01*
G03X764664Y182940I-328J-229D01*
G02X762508Y184389I-783J1163D01*
G03X762239Y184851I-391J81D01*
G02X761777Y185103I428J1335D01*
G03X761242Y185079I-254J-309D01*
G02X759160Y186949I-984J999D01*
G03X759122Y187489I-313J249D01*
G02X759037Y187575I954J1028D01*
G03X758734Y187570I-149J-133D01*
G02X756760Y187384I-1080J894D01*
G03X756226Y187363I-255J-308D01*
G02X754226Y187408I-978J1005D01*
G03X753662Y187428I-292J-273D01*
G02X751706Y187475I-954J1027D01*
G03X751142Y187482I-286J-280D01*
G02X749159Y187515I-975J1008D01*
G03X748561Y187488I-287J-278D01*
G02X746453Y187402I-1092J880D01*
G03X745889Y187417I-290J-276D01*
G02X743856Y187534I-961J1021D01*
G03X743227Y187511I-305J-258D01*
G02X741097Y187344I-1136J822D01*
G03X740491Y187298I-283J-282D01*
G02X737962Y188013I-1132J827D01*
G03X737509Y188377I-399J-32D01*
G02X737404Y188367I-185J1389D01*
G03X737028Y187967I24J-399D01*
G02X734269Y187614I-1402J-2D01*
G03X733811Y187908I-387J-100D01*
G02X732641Y188233I-247J1380D01*
G03X732106Y188226I-264J-301D01*
G02X732078Y190311I-951J1030D01*
G03X732613Y190318I264J301D01*
G02X734921Y189639I951J-1030D01*
G03X735379Y189345I387J100D01*
G02X735541Y189364I244J-1380D01*
G03X735917Y189764I-24J399D01*
G02X736450Y190866I1402J2D01*
G03X736498Y191449I-248J314D01*
G02X738938Y192406I1038J943D01*
G03X739405Y192016I400J4D01*
G02X740525Y189546I236J-1382D01*
G03X740463Y188989I253J-310D01*
G02X740499Y188941I-1103J-865D01*
G03X740840Y188967I163J116D01*
G02X743163Y189237I1251J-634D01*
G03X743792Y189260I305J258D01*
G02X745944Y189404I1136J-822D01*
G03X746508Y189389I290J276D01*
G02X748477Y189343I961J-1021D01*
G03X749075Y189370I287J278D01*
G02X751169Y189470I1091J-880D01*
G03X751733Y189463I286J280D01*
G02X753730Y189415I975J-1008D01*
G03X754294Y189395I292J273D01*
G02X756142Y189448I954J-1027D01*
G03X756676Y189469I255J308D01*
G02X758581Y189516I978J-1005D01*
G03X759120Y189526I264J300D01*
G02X760987Y189580I964J-1018D01*
G03X761531Y189606I258J306D01*
G02X763513Y189628I1002J-980D01*
G03X764062Y189619I279J286D01*
G02X766074Y189493I945J-1036D01*
G03X766622Y189435I304J259D01*
G02X768495Y187360I854J-1112D01*
G03X768543Y186768I291J-274D01*
G02X768047Y184298I-851J-1114D01*
G03X767754Y183850I102J-387D01*
G37*
G36*
G01X1643138Y183981D02*
G02X1640433Y184087I-1338J419D01*
G03X1639869Y184358I-390J-89D01*
G02X1640658Y185686I-611J1262D01*
G03X1640976Y185534I200J10D01*
G02X1641128Y185630I823J-1135D01*
G03X1641274Y186196I-192J351D01*
G02X1643844Y187149I1183J752D01*
G03X1644283Y186809I396J58D01*
G02X1643722Y184206I150J-1394D01*
G03X1643138Y183981I-203J-345D01*
G37*
G36*
G01X1703257Y188180D02*
G02X1701704Y188154I-757J-1180D01*
G03X1701693Y188820I-227J329D01*
G02X1703246Y188846I757J1180D01*
G03X1703257Y188180I227J-329D01*
G37*
G36*
G01X1709077Y188435D02*
G02X1708544Y186943I823J-1135D01*
G03X1707923Y187165I-387J-102D01*
G02X1708456Y188657I-823J1135D01*
G03X1709077Y188435I387J102D01*
G37*
G36*
G01X726687Y189694D02*
G02X726618Y188021I1089J-883D01*
G03X725977Y188047I-330J-226D01*
G02X726046Y189720I-1089J883D01*
G03X726687Y189694I330J226D01*
G37*
G36*
G01X1945242Y191496D02*
G02X1943626Y191653I-942J-1296D01*
G03X1943713Y192323I-169J363D01*
G02X1945285Y192170I898J1077D01*
G03X1945242Y191496I192J-351D01*
G37*
G36*
G01X1264031Y192350D02*
G02X1261842Y190662I-951J-1030D01*
G03X1261189Y190740I-354J-187D01*
G02X1258828Y191177I-1049J930D01*
G03X1258177Y191325I-374J-141D01*
G02X1255826Y192116I-967J1015D01*
G03X1255404Y192451I-395J-64D01*
G02X1254628Y192625I-94J1399D01*
G03X1254099Y192497I-196J-349D01*
G02X1251543Y193067I-1169J773D01*
G03X1251134Y193409I-396J-58D01*
G02X1249691Y194909I-45J1401D01*
G03X1249354Y195333I-399J29D01*
G02X1248169Y196692I217J1385D01*
G03X1247777Y197084I-400J-8D01*
G02X1246401Y198520I26J1402D01*
G03X1246021Y198930I-400J11D01*
G02X1244688Y200354I69J1400D01*
G03X1244309Y200760I-400J7D01*
G02X1242987Y202316I71J1400D01*
G03X1242636Y202758I-398J45D01*
G02X1242119Y205375I164J1392D01*
G03X1242207Y206008I-194J350D01*
G02X1241812Y206781I990J993D01*
G03X1241202Y207056I-395J-63D01*
G02X1239442Y209213I-750J1184D01*
G03Y209767I-288J277D01*
G02Y211713I1010J973D01*
G03Y212267I-288J277D01*
G02Y214213I1010J973D01*
G03Y214767I-288J277D01*
G02X1239446Y216717I1010J973D01*
G03X1239457Y217263I-287J279D01*
G02X1241506Y217223I1043J937D01*
G03X1241495Y216677I287J-279D01*
G02X1241462Y214767I-1043J-937D01*
G03Y214213I288J-277D01*
G02Y212267I-1010J-973D01*
G03Y211713I288J-277D01*
G02Y209767I-1010J-973D01*
G03Y209213I288J-277D01*
G02X1241836Y208461I-1011J-972D01*
G03X1242446Y208186I395J63D01*
G02X1244589Y207161I750J-1184D01*
G03X1244992Y206807I397J46D01*
G02X1246416Y205371I22J-1402D01*
G03X1246772Y204964I400J-10D01*
G02X1248021Y203529I-152J-1394D01*
G03X1248392Y203118I400J-12D01*
G02X1248785Y203032I-100J-1398D01*
G03X1249304Y203272I142J374D01*
G02X1252027Y202824I1321J-468D01*
G03X1252405Y202430I400J5D01*
G02X1252469Y202425I-77J-1400D01*
G03X1252908Y202827I39J398D01*
G02X1255088Y204006I1402J13D01*
G03X1255643Y204117I222J333D01*
G02X1256982Y204731I1167J-777D01*
G03X1257426Y205064I49J397D01*
G02X1258739Y206240I1384J-224D01*
G03X1259117Y206684I-20J400D01*
G02X1260386Y208236I1393J156D01*
G03X1260734Y208747I-36J398D01*
G02X1262016Y210541I1346J393D01*
G03X1262382Y211052I-18J399D01*
G02X1265099Y211149I1346J392D01*
G03X1265481Y210665I391J-84D01*
G02X1266852Y209289I-31J-1402D01*
G03X1267244Y208897I400J8D01*
G02X1268620Y207521I-26J-1402D01*
G03X1269012Y207129I400J8D01*
G02X1270388Y205753I-26J-1402D01*
G03X1270780Y205361I400J8D01*
G02X1272156Y203985I-26J-1402D01*
G03X1272548Y203593I400J8D01*
G02X1272678Y200798I-26J-1402D01*
G03X1272325Y200360I45J-398D01*
G02X1270974Y198819I-1395J-140D01*
G03X1270602Y198309I13J-400D01*
G02X1269325Y196523I-1348J-386D01*
G03X1268947Y196079I20J-400D01*
G02X1267382Y194532I-1393J-156D01*
G03X1266941Y194218I-50J-397D01*
G02X1264803Y193336I-1371J292D01*
G03X1264242Y193208I-219J-335D01*
G02X1264022Y192929I-1202J722D01*
G03X1264031Y192350I280J-285D01*
G37*
G36*
G01X706309Y191605D02*
G02X705545Y192886I-1402J32D01*
G03X706127Y193233I182J356D01*
G02X707720Y194589I1402J-33D01*
G03X708135Y195158I54J396D01*
G02X710728Y196211I1264J605D01*
G03X711280Y195978I379J128D01*
G02X712356Y196035I606J-1264D01*
G03X712855Y196250I133J377D01*
G02X715433Y196217I1282J-568D01*
G03X715953Y195999I370J153D01*
G02X715184Y194165I527J-1299D01*
G03X714664Y194383I-370J-153D01*
G02X713667Y194361I-527J1299D01*
G03X713168Y194146I-133J-377D01*
G02X710558Y194266I-1282J568D01*
G03X710006Y194499I-379J-128D01*
G02X709209Y194374I-607J1264D01*
G03X708794Y193805I-54J-396D01*
G02X706891Y191952I-1265J-605D01*
G03X706309Y191605I-182J-356D01*
G37*
G36*
G01X698454Y194415D02*
G02X696900Y194323I-708J-1210D01*
G03X696860Y194987I-242J319D01*
G02X698414Y195079I708J1210D01*
G03X698454Y194415I242J-319D01*
G37*
G36*
G01X98575Y195729D02*
G02X97147Y195683I-675J-1229D01*
G03X97125Y196371I-214J337D01*
G02X97155Y198845I675J1229D01*
G03Y199555I-184J355D01*
G02X98445I645J1245D01*
G03Y198845I184J-355D01*
G02X98553Y196417I-645J-1245D01*
G03X98575Y195729I214J-337D01*
G37*
G36*
G01X1630836Y196158D02*
G02X1630732Y196162I2J1402D01*
G03X1630314Y195670I-29J-399D01*
G02X1629054Y196742I-1364J-326D01*
G03X1629472Y197234I29J399D01*
G02X1632121Y197000I1364J326D01*
G03X1632340Y196724I184J-79D01*
G02X1632363Y196727I193J-1387D01*
G03X1632691Y197196I-65J395D01*
G02X1634296Y196071I1378J258D01*
G03X1633968Y195602I65J-395D01*
G02X1631226Y195666I-1378J-258D01*
G03X1630837Y196158I-389J92D01*
G01X1630836D01*
G37*
G36*
G01X105535Y196906D02*
G02X104105I-715J-1206D01*
G03Y197594I-204J344D01*
G02X105535I715J1206D01*
G03Y196906I204J-344D01*
G37*
G36*
G01X1731771Y195558D02*
G02X1731397Y196835I-1371J292D01*
G03X1732076Y197045I285J281D01*
G02X1733563Y198288I1487J-268D01*
G01X1738564D01*
G02X1740074Y196786I-1J-1512D01*
G01Y196691D01*
X1740065Y196607D01*
G02X1738563Y195264I-1502J168D01*
G01X1733563D01*
G02X1732456Y195747I1J1512D01*
G03X1731771Y195558I-294J-272D01*
G37*
G36*
G01X1675197Y195838D02*
G02X1675158Y197545I-1131J828D01*
G03X1675793Y197559I312J250D01*
G02X1675832Y195852I1131J-828D01*
G03X1675197Y195838I-312J-250D01*
G37*
G36*
G01X607489Y199401D02*
G02X605767Y199172I-716J-1205D01*
G03X605684Y199795I-287J279D01*
G02X605006Y201146I716J1205D01*
G03X604573Y201586I-398J41D01*
G02X605847Y202837I-120J1397D01*
G03X606280Y202397I398J-41D01*
G02X607406Y200024I120J-1397D01*
G03X607489Y199401I287J-279D01*
G37*
G36*
G01X799413Y200497D02*
G02X798046Y199727I-113J-1397D01*
G03X797694Y200305I-358J178D01*
G02X799100Y201098I23J1602D01*
G03X799413Y200497I345J-202D01*
G37*
G36*
G01X1894193Y200047D02*
G02X1893186Y201414I-1402J22D01*
G03X1893698Y201792I112J384D01*
G02X1894569Y203068I1402J-22D01*
G03X1894683Y203737I-152J370D01*
G02X1896145Y203487I932J1048D01*
G03X1896031Y202818I152J-370D01*
G02X1894705Y200425I-931J-1048D01*
G03X1894193Y200047I-112J-384D01*
G37*
G36*
G01X579220Y203377D02*
G02X578123Y202280I277J-1374D01*
G03X577652Y202751I-392J79D01*
G02X578749Y203848I-277J1374D01*
G03X579220Y203377I392J-79D01*
G37*
G36*
G01X1403833Y206100D02*
G02X1402555Y205885I-433J-1334D01*
G03X1402437Y206584I-241J319D01*
G02X1403715Y206799I433J1334D01*
G03X1403833Y206100I241J-319D01*
G37*
G36*
G01X562584Y206877D02*
G02X561487Y205780I277J-1374D01*
G03X561016Y206251I-392J79D01*
G02X562113Y207348I-277J1374D01*
G03X562584Y206877I392J-79D01*
G37*
G36*
G01X1955487Y214076D02*
G03X1955651Y214607I-193J350D01*
G02X1956220Y216466I1250J634D01*
G03Y217166I-194J350D01*
G02X1957582I681J1225D01*
G03Y216466I194J-350D01*
G02X1958147Y214599I-681J-1225D01*
G03X1958308Y214067I356J-183D01*
G02X1959541Y212715I-1418J-2532D01*
G03X1960200Y212606I365J163D01*
G02X1959928Y209839I1690J-1563D01*
G03X1959260Y209861I-341J-209D01*
G02X1957697Y208747I-2371J1673D01*
G01X1957552Y208706D01*
Y204492D01*
X1946598D01*
Y213346D01*
X1954623D01*
G02X1955487Y214076I2269J-1809D01*
G37*
G36*
G01X1330337Y207982D02*
G02X1330256Y209998I-1013J969D01*
G03X1330811Y210020I266J299D01*
G02X1332952Y209883I1013J-969D01*
G03X1333596I322J238D01*
G02Y208219I1128J-832D01*
G03X1332952I-322J-238D01*
G02X1330892Y208004I-1128J832D01*
G03X1330337Y207982I-266J-299D01*
G37*
G36*
G01X1884653Y211688D02*
G02X1882947I-853J-1113D01*
G03Y212323I-243J317D01*
G02X1885092Y213981I853J1113D01*
G03X1885791Y213912I368J155D01*
G02X1885660Y212580I1161J-787D01*
G03X1884961Y212649I-368J-155D01*
G02X1884653Y212323I-1160J788D01*
G03Y211688I243J-318D01*
G37*
G36*
G01X565773Y212929D02*
G02X564656Y211694I278J-1374D01*
G03X564178Y212126I-398J40D01*
G02X565295Y213361I-278J1374D01*
G03X565773Y212929I398J-40D01*
G37*
G36*
G01X174500Y210839D02*
G02X172195Y213060I-1200J1061D01*
G03Y213640I-275J290D01*
G02Y215960I1105J1160D01*
G03Y216540I-275J290D01*
G02X174636Y218584I1105J1160D01*
G03X175236Y218505I334J220D01*
G02X177852Y217706I1064J-1197D01*
G03X178451Y217467I387J100D01*
G02X180500Y217169I849J-1359D01*
G03X181100I300J265D01*
G02Y215047I1200J-1061D01*
G03X180500I-300J-265D01*
G02X180405Y214948I-1202J1059D01*
G03Y214368I275J-290D01*
G02X178469Y211839I-1105J-1159D01*
G03X177869Y211577I-208J-342D01*
G02X175100Y210839I-1569J323D01*
G03X174500I-300J-265D01*
G37*
G36*
G01X1848935Y212284D02*
G02Y213608I-1236J662D01*
G03X1849640I353J189D01*
G02Y212284I1236J-662D01*
G03X1848935I-352J-189D01*
G37*
G36*
G01X116300Y214684D02*
G02X114751Y214669I-763J-1176D01*
G03X114744Y215336I-224J331D01*
G02X116293Y215351I763J1176D01*
G03X116300Y214684I224J-331D01*
G37*
G36*
G01X765908D02*
G02X764359Y214669I-763J-1176D01*
G03X764352Y215336I-224J331D01*
G02X765901Y215351I763J1176D01*
G03X765908Y214684I224J-331D01*
G37*
G36*
G01X1220270Y214898D02*
G02X1218893Y216271I-1402J-29D01*
G03X1219300Y216679I7J400D01*
G02X1219317Y216923I1402J25D01*
G03X1218979Y217097I-198J31D01*
G02X1219396Y218228I-979J1003D01*
G03X1219996Y217919I398J37D01*
G02X1220677Y215306I706J-1211D01*
G03X1220270Y214898I-7J-400D01*
G37*
G36*
G01X1331241Y215723D02*
G02Y217277I-1167J777D01*
G03X1331907I333J222D01*
G02X1334241I1167J-777D01*
G03X1334907I333J222D01*
G02Y215723I1167J-777D01*
G03X1334241I-333J-222D01*
G02X1331907I-1167J777D01*
G03X1331241I-333J-222D01*
G37*
G36*
G01X580354Y218161D02*
G02X579257Y219258I-1374J-277D01*
G03X579728Y219729I79J392D01*
G02X580825Y218632I1374J277D01*
G03X580354Y218161I-79J-392D01*
G37*
G36*
G01X743908Y222185D02*
G02X741579Y220827I-971J-1011D01*
G03X741024Y221091I-388J-99D01*
G02X739426Y221393I-587J1273D01*
G03X738848I-289J-277D01*
G02X736866Y223375I-1011J971D01*
G03Y223953I-277J289D01*
G02X738848Y225935I971J1011D01*
G03X739426I289J277D01*
G02X739696Y226154I1011J-971D01*
G03X739665Y226850I-212J339D01*
G02X741685Y228317I635J1250D01*
G03X742262Y228023I395J62D01*
G02X743690Y225617I635J-1250D01*
G03X743699Y224951I226J-330D01*
G02X743908Y222763I-762J-1177D01*
G03Y222185I277J-289D01*
G37*
G36*
G01X642709Y222556D02*
G02X640382Y222440I-1109J-1156D01*
G03Y222960I-304J260D01*
G02Y225040I1218J1040D01*
G03Y225560I-304J260D01*
G02Y227640I1218J1040D01*
G03Y228160I-304J260D01*
G02Y230240I1218J1040D01*
G03Y230760I-304J260D01*
G02X642760Y232905I1218J1040D01*
G03X643340I290J275D01*
G02X645740Y232814I1160J-1105D01*
G03X646360I310J253D01*
G02X648840I1240J-1014D01*
G03X649460I310J253D01*
G02X651918Y230760I1240J-1014D01*
G03Y230240I304J-260D01*
G02Y228160I-1218J-1040D01*
G03Y227640I304J-260D01*
G02X652239Y227044I-1218J-1040D01*
G03X652849Y226824I385J111D01*
G02X652903Y224140I901J-1324D01*
G03X652294Y223840I-211J-340D01*
G02X649460Y222986I-1594J160D01*
G03X648840I-310J-253D01*
G02X646360I-1240J1014D01*
G03X645740I-310J-253D01*
G02X643340Y222895I-1240J1014D01*
G03X642760I-290J-275D01*
G02X642709Y222844I-1158J1107D01*
G03Y222556I139J-144D01*
G37*
G36*
G01X1904069Y226851D02*
G02X1901981Y226861I-1049J-1075D01*
G03X1901999Y227420I-277J289D01*
G02X1902167Y229471I1033J948D01*
G03X1902139Y230121I-247J315D01*
G02X1903772Y230191I768J1173D01*
G03X1903800Y229541I247J-315D01*
G02X1904056Y227410I-768J-1173D01*
G03X1904069Y226851I292J-273D01*
G37*
G36*
G01X1398440Y226716D02*
G02X1395924Y225485I-1229J-675D01*
G03X1395407Y225697I-367J-159D01*
G02X1396168Y227553I-526J1300D01*
G03X1396685Y227341I367J159D01*
G02X1397063Y227435I524J-1300D01*
G03X1397371Y228025I-43J398D01*
G02X1399574Y229708I1229J675D01*
G03X1400233Y229871I279J287D01*
G02X1400591Y228427I1332J-436D01*
G03X1399932Y228264I-279J-287D01*
G02X1398748Y227306I-1332J436D01*
G03X1398440Y226716I43J-398D01*
G37*
G36*
G01X602200Y227570D02*
G02X602143Y225908I1100J-870D01*
G03X601500Y225930I-330J-226D01*
G02X601557Y227592I-1100J870D01*
G03X602200Y227570I330J226D01*
G37*
G36*
G01X775868Y228446D02*
G02X774497Y228458I-697J-1330D01*
G03X774503Y229170I-180J358D01*
G02X775874Y229158I697J1330D01*
G03X775868Y228446I180J-358D01*
G37*
G36*
G01X1279850Y230736D02*
G02X1278675Y229922I99J-1398D01*
G03X1278283Y230488I-363J167D01*
G02X1276858Y232344I-100J1398D01*
G03X1276513Y232873I-378J130D01*
G02X1275240Y234465I115J1397D01*
G03X1274912Y234915I-396J56D01*
G02X1276542Y236101I242J1381D01*
G03X1276870Y235651I396J-56D01*
G02X1277953Y233812I-242J-1381D01*
G03X1278298Y233283I378J-130D01*
G02X1279458Y231302I-115J-1397D01*
G03X1279850Y230736I363J-167D01*
G37*
G36*
G01X1398802Y232142D02*
G02X1398004Y233383I-1402J-24D01*
G03X1398576Y233751I172J361D01*
G02X1399003Y234783I1402J24D01*
G03X1399023Y235337I-278J287D01*
G02X1398664Y236309I1043J937D01*
G03X1398073Y236670I-400J10D01*
G02X1398802Y237865I-673J1230D01*
G03X1399393Y237504I400J-10D01*
G02X1401041Y235266I674J-1230D01*
G03X1401021Y234712I278J-287D01*
G02X1399374Y232510I-1043J-937D01*
G03X1398802Y232142I-172J-361D01*
G37*
G36*
G01X1837228Y234063D02*
G02X1835822Y233596I-328J-1363D01*
G03X1835608Y234241I-307J256D01*
G02X1837014Y234708I328J1363D01*
G03X1837228Y234063I307J-256D01*
G37*
G36*
G01X1735168Y232256D02*
G02X1734900Y233771I-1288J553D01*
G03X1735559Y233888I291J274D01*
G02X1738014Y234111I1288J-554D01*
G03X1738680I333J222D01*
G02X1740447Y234601I1167J-777D01*
G03X1741013Y234900I171J362D01*
G02X1741153Y235327I1385J-218D01*
G03X1740972Y235871I-355J184D01*
G02X1740632Y236092I696J1443D01*
G03X1740108Y236086I-259J-305D01*
G02X1737864Y236200I-1064J1198D01*
G03X1737310Y236234I-295J-271D01*
G02X1735427Y236290I-911J1066D01*
G03X1734873I-277J-288D01*
G02Y238310I-973J1010D01*
G03X1735427I277J288D01*
G02X1737323Y238355I973J-1010D01*
G03X1737878Y238382I264J301D01*
G02X1740080Y238506I1166J-1098D01*
G03X1740604Y238512I259J305D01*
G02X1742733Y238511I1064J-1198D01*
G03X1743260Y238507I266J299D01*
G02X1745469Y238399I1048J-1212D01*
G03X1746052Y238403I290J276D01*
G02X1746066Y236210I1175J-1089D01*
G03X1745483Y236206I-290J-276D01*
G02X1744132Y235703I-1175J1089D01*
G03X1743713Y235167I-44J-398D01*
G02X1741798Y233414I-1315J-486D01*
G03X1741232Y233115I-171J-362D01*
G02X1738680Y232557I-1385J219D01*
G03X1738014I-333J-222D01*
G02X1735827Y232373I-1167J777D01*
G03X1735168Y232256I-291J-274D01*
G37*
G36*
G01X126246Y235654D02*
G02X124199Y233687I-683J-1338D01*
G03X123515Y233758I-363J-168D01*
G02X121399Y236085I-1284J958D01*
G03X121479Y236704I-208J342D01*
G02X123805Y238907I1153J1112D01*
G03X124391I293J272D01*
G02X126255Y236371I1173J-1091D01*
G03X126246Y235654I173J-361D01*
G37*
G36*
G01X1608415Y241546D02*
G02X1607183Y242777I-1566J-336D01*
G03X1607662Y243223I83J391D01*
G02X1608861Y242026I1389J192D01*
G03X1608415Y241546I-55J-396D01*
G37*
G36*
G01X1667018Y243217D02*
G02X1665659Y243210I-673J-1230D01*
G03X1665656Y243909I-196J349D01*
G02X1667015Y243916I673J1230D01*
G03X1667018Y243217I196J-349D01*
G37*
G36*
G01X1682647Y243237D02*
G02X1682508Y241656I1082J-892D01*
G03X1681851Y241714I-348J-196D01*
G02X1680454Y243971I-1082J891D01*
G03X1680674Y244614I-90J390D01*
G02X1682786Y246455I1086J886D01*
G03X1683397Y246484I293J272D01*
G02X1683483Y244676I1112J-853D01*
G03X1682872Y244647I-293J-272D01*
G02X1682075Y244134I-1113J853D01*
G03X1681855Y243491I90J-390D01*
G02X1681990Y243295I-1083J-890D01*
G03X1682647Y243237I348J196D01*
G37*
G36*
G01X128755Y242876D02*
G02X128442Y244539I-1255J625D01*
G03X129069Y244657I269J296D01*
G02X129382Y242994I1255J-625D01*
G03X128755Y242876I-269J-296D01*
G37*
G36*
G01X778282Y242932D02*
G02X778000Y244483I-1282J568D01*
G03X778650Y244601I285J281D01*
G02X778932Y243050I1282J-568D01*
G03X778282Y242932I-285J-281D01*
G37*
G36*
G01X1437365Y245552D02*
G02X1436078Y244616I35J-1402D01*
G03X1435690Y245148I-377J132D01*
G02X1436977Y246084I-35J1402D01*
G03X1437365Y245552I377J-132D01*
G37*
G36*
G01X116289Y246548D02*
G02X114740Y246533I-763J-1176D01*
G03X114733Y247200I-224J331D01*
G02X116282Y247215I763J1176D01*
G03X116289Y246548I224J-331D01*
G37*
G36*
G01X765908Y246684D02*
G02X764359Y246669I-763J-1176D01*
G03X764352Y247336I-224J331D01*
G02X765901Y247351I763J1176D01*
G03X765908Y246684I224J-331D01*
G37*
G36*
G01X849482Y245366D02*
G02X847064Y247467I-1200J1061D01*
G03Y247987I-304J260D01*
G02X847099Y250107I1218J1040D01*
G03Y250647I-295J270D01*
G02X846842Y251026I1184J1079D01*
G03X846196Y251130I-360J-175D01*
G02X846594Y252679I-1146J1120D01*
G03X846952Y252620I193J53D01*
G02X847064Y252767I1328J-896D01*
G03Y253287I-304J260D01*
G02X849482Y255388I1218J1040D01*
G03X850082I300J265D01*
G02X852482I1200J-1061D01*
G03X853082I300J265D01*
G02X855482I1200J-1061D01*
G03X856082I300J265D01*
G02X858500Y253287I1200J-1061D01*
G03Y252767I304J-260D01*
G02X858465Y250647I-1218J-1040D01*
G03Y250107I295J-270D01*
G02X858500Y247987I-1183J-1080D01*
G03Y247467I304J-260D01*
G02X856082Y245366I-1218J-1040D01*
G03X855482I-300J-265D01*
G02X853082I-1200J1061D01*
G03X852482I-300J-265D01*
G02X850082I-1200J1061D01*
G03X849482I-300J-265D01*
G37*
G36*
G01X1663900Y249338D02*
G02X1662940Y248226I424J-1336D01*
G03X1662424Y248672I-395J65D01*
G02X1663384Y249784I-424J1336D01*
G03X1663900Y249338I395J-65D01*
G37*
G36*
G01X718606Y249173D02*
G02X718591Y250691I-1186J747D01*
G03X719264Y250697I335J219D01*
G02X721584Y250774I1186J-747D01*
G03X722239Y250786I323J236D01*
G02X724545Y250809I1161J-786D01*
G03X725195Y250805I326J231D01*
G02X725183Y249170I1133J-826D01*
G03X724533Y249174I-326J-231D01*
G02X722266Y249176I-1133J826D01*
G03X721611Y249164I-323J-236D01*
G02X719279Y249179I-1161J786D01*
G03X718606Y249173I-335J-219D01*
G37*
G36*
G01X658864Y249391D02*
G02X658783Y251062I-1164J781D01*
G03X659424Y251093I309J254D01*
G02X659505Y249422I1164J-781D01*
G03X658864Y249391I-309J-254D01*
G37*
G36*
G01X1500777Y249858D02*
G02X1500262Y251528I-1305J512D01*
G03X1500860Y251712I226J330D01*
G02X1501375Y250042I1305J-512D01*
G03X1500777Y249858I-226J-330D01*
G37*
G36*
G01X1588322Y250980D02*
G02X1587633Y252491I-1372J287D01*
G03X1588220Y252759I195J349D01*
G02X1588909Y251248I1372J-287D01*
G03X1588322Y250980I-195J-349D01*
G37*
G36*
G01X1440096Y254445D02*
G02X1438370Y253545I-396J-1345D01*
G03X1438104Y254055I-379J127D01*
G02X1437463Y256344I396J1345D01*
G03X1437308Y256987I-296J269D01*
G02X1438837Y257356I492J1313D01*
G03X1438992Y256713I296J-269D01*
G02X1439830Y254955I-492J-1313D01*
G03X1440096Y254445I379J-127D01*
G37*
G36*
G01X1859705Y253139D02*
G02X1859613Y254436I-1285J561D01*
G03X1860320Y254486I340J210D01*
G02X1862690Y254813I1285J-561D01*
G03X1863289Y254791I309J254D01*
G02X1863220Y252937I1016J-966D01*
G03X1862621Y252959I-309J-254D01*
G02X1860412Y253189I-1016J966D01*
G03X1859705Y253139I-340J-210D01*
G37*
G36*
G01X749809Y253142D02*
G02X749663Y255019I-1109J858D01*
G03X750254Y255065I275J291D01*
G02X752491Y255039I1109J-858D01*
G03X753135I322J238D01*
G02Y253375I1128J-832D01*
G03X752491I-322J-238D01*
G02X750400Y253188I-1128J832D01*
G03X749809Y253142I-275J-291D01*
G37*
G36*
G01X1671347Y255991D02*
G02X1669766Y255613I-525J-1300D01*
G03X1669615Y256247I-301J263D01*
G02X1669027Y256694I525J1300D01*
G03X1668478Y256777I-318J-243D01*
G02X1666532Y258743I-811J1144D01*
G03X1666377Y259340I-324J234D01*
G02X1668103Y259788I591J1271D01*
G03X1668258Y259191I324J-234D01*
G02X1668780Y258773I-590J-1272D01*
G03X1669329Y258690I318J243D01*
G02X1671196Y256625I810J-1144D01*
G03X1671347Y255991I301J-263D01*
G37*
G36*
G01X1621068Y255879D02*
G02X1619424Y255874I-819J-1138D01*
G03X1619422Y256522I-236J323D01*
G02X1621066Y256527I819J1138D01*
G03X1621068Y255879I236J-323D01*
G37*
G36*
G01X1309929Y256611D02*
G02X1309831Y254805I1021J-961D01*
G03X1309221Y254839I-319J-241D01*
G02X1306892Y256305I-1021J961D01*
G03X1306534Y256849I-373J144D01*
G02X1307893Y257745I51J1401D01*
G03X1308251Y257201I373J-144D01*
G02X1309319Y256645I-51J-1401D01*
G03X1309929Y256611I319J241D01*
G37*
G36*
G01X1592716Y258175D02*
G02X1590523Y255841I-1118J-1147D01*
G03X1590003Y255856I-269J-297D01*
G02X1587961Y255884I-1004J1248D01*
G03X1587442Y255883I-259J-305D01*
G02X1585039Y256252I-1043J1216D01*
G03X1584369Y256267I-340J-211D01*
G02X1581977Y258363I-1323J903D01*
G03X1581983Y258953I-267J298D01*
G02X1584496Y260867I1095J1169D01*
G03X1585166Y260808I354J186D01*
G02X1587478Y261035I1264J-984D01*
G03X1587998Y261032I262J303D01*
G02X1590015Y261071I1033J-1225D01*
G03X1590534Y261094I246J315D01*
G02X1592722Y258754I1094J-1170D01*
G03X1592716Y258175I273J-292D01*
G37*
G36*
G01X643632Y262228D02*
G02X641968I-832J-1128D01*
G03Y262872I-238J322D01*
G02X642408Y265346I832J1128D01*
G03X642583Y266008I-112J384D01*
G02X642443Y267787I1008J974D01*
G03X642279Y268382I-328J230D01*
G02X644003Y268856I576J1278D01*
G03X644167Y268261I328J-230D01*
G02X643983Y265637I-576J-1278D01*
G03X643808Y264975I112J-384D01*
G02X643632Y262872I-1008J-975D01*
G03Y262228I238J-322D01*
G37*
G36*
G01X445821Y262562D02*
G02X444136Y262342I-698J-1216D01*
G03X444054Y262972I-282J284D01*
G02X443931Y265325I698J1216D01*
G03X443855Y266017I-234J325D01*
G02X445229Y266168I554J1288D01*
G03X445305Y265476I234J-325D01*
G02X445739Y263192I-553J-1288D01*
G03X445821Y262562I282J-284D01*
G37*
G36*
G01X1087254Y263369D02*
G02X1084819Y263312I-1193J-1069D01*
G03X1084807Y263831I-310J252D01*
G02X1087551Y265303I1193J1069D01*
G03X1087913Y265247I193J51D01*
G02X1088053Y265432I1184J-751D01*
G03X1088031Y265987I-299J266D01*
G02X1090047Y266068I969J1013D01*
G03X1090069Y265513I299J-266D01*
G02X1090267Y265277I-969J-1014D01*
G03X1090933I333J222D01*
G02X1091255Y265619I1167J-777D01*
G03X1091299Y266218I-241J319D01*
G02X1093145Y266081I1001J982D01*
G03X1093101Y265482I241J-319D01*
G02X1090933Y263723I-1001J-982D01*
G03X1090267I-333J-222D01*
G02X1087763Y264079I-1167J777D01*
G03X1087397Y264117I-191J-60D01*
G02X1087242Y263888I-1399J780D01*
G03X1087254Y263369I310J-252D01*
G37*
G36*
G01X440857Y264577D02*
G02X439243Y265001I-1093J-878D01*
G03X439407Y265622I-148J371D01*
G02X441021Y265198I1093J878D01*
G03X440857Y264577I148J-371D01*
G37*
G36*
G01X451230Y266487D02*
G02X450517Y264930I653J-1241D01*
G03X449941Y265194I-390J-90D01*
G02X450654Y266751I-653J1241D01*
G03X451230Y266487I390J90D01*
G37*
G36*
G01X1096538Y267024D02*
G02X1094862I-838J-1124D01*
G03Y267666I-239J321D01*
G02X1096538I838J1124D01*
G03Y267024I239J-321D01*
G37*
G36*
G01X126206Y267673D02*
G02X124199Y265687I-643J-1357D01*
G03X123515Y265758I-363J-168D01*
G02X121349Y268053I-1284J958D01*
G03X121409Y268673I-220J334D01*
G02X123704Y270907I1122J1143D01*
G03X124290I293J272D01*
G02X126194Y268391I1173J-1091D01*
G03X126206Y267673I183J-356D01*
G37*
G36*
G01X1481323Y266622D02*
G02X1479417Y268529I-1225J682D01*
G03Y269229I-194J350D01*
G02X1478873Y269773I681J1225D01*
G03X1478173I-350J-194D01*
G02X1475723I-1225J681D01*
G03X1475023I-350J-194D01*
G02X1472573Y269772I-1225J681D01*
G03X1471874I-349J-194D01*
G02X1469967Y271679I-1225J682D01*
G03Y272378I-194J350D01*
G02X1469968Y274828I682J1225D01*
G03Y275528I-194J350D01*
G02X1469967Y277978I681J1225D01*
G03Y278677I-194J350D01*
G02X1469968Y281127I682J1225D01*
G03Y281827I-194J350D01*
G02Y284277I681J1225D01*
G03Y284977I-194J350D01*
G02X1471874Y286884I681J1225D01*
G03X1472573I350J194D01*
G02X1473116Y287427I1225J-682D01*
G03Y288126I-194J350D01*
G02X1475023Y290032I682J1225D01*
G03X1475723I350J194D01*
G02X1477630Y288126I1225J-681D01*
G03Y287427I194J-350D01*
G02X1478173Y286883I-683J-1224D01*
G03X1478873I350J194D01*
G02X1481323Y286884I1225J-681D01*
G03X1482022I350J194D01*
G02X1482565Y287427I1225J-682D01*
G03Y288126I-194J350D01*
G02X1483929I682J1225D01*
G03Y287427I194J-350D01*
G02X1484472Y286883I-683J-1224D01*
G03X1485172I350J194D01*
G02X1487622Y286884I1225J-681D01*
G03X1488321I350J194D01*
G02Y285520I1225J-682D01*
G03X1487622I-349J-194D01*
G02X1487078Y284977I-1224J683D01*
G03Y284277I194J-350D01*
G02X1485172Y282371I-681J-1225D01*
G03X1484472I-350J-194D01*
G02X1483928Y281827I-1225J681D01*
G03Y281127I194J-350D01*
G02X1482566I-681J-1225D01*
G03Y281827I-194J350D01*
G02X1482022Y282370I680J1226D01*
G03X1481323I-349J-194D01*
G02X1479417Y284277I-1225J682D01*
G03Y284977I-194J350D01*
G02X1478873Y285521I681J1225D01*
G03X1478173I-350J-194D01*
G02X1475723I-1225J681D01*
G03X1475023I-350J-194D01*
G02X1474479Y284977I-1225J681D01*
G03Y284277I194J-350D01*
G02Y281827I-681J-1225D01*
G03Y281127I194J-350D01*
G02X1475023Y280583I-681J-1225D01*
G03X1475723I350J194D01*
G02X1477630Y278677I1225J-681D01*
G03Y277978I194J-350D01*
G02X1478173Y277434I-683J-1224D01*
G03X1478873I350J194D01*
G02X1480779Y275528I1225J-681D01*
G03Y274828I194J-350D01*
G02X1481323Y274285I-680J-1226D01*
G03X1482022I350J194D01*
G02X1483929Y272378I1225J-682D01*
G03Y271679I194J-350D01*
G02X1484472Y271135I-683J-1224D01*
G03X1485172I350J194D01*
G02Y269773I1225J-681D01*
G03X1484472I-350J-194D01*
G02X1483928Y269229I-1225J681D01*
G03Y268529I194J-350D01*
G02X1482022Y266622I-681J-1225D01*
G03X1481323I-349J-194D01*
G37*
G36*
G01X653393Y271818D02*
G02X651851Y271716I-694J-1218D01*
G03X651807Y272382I-242J318D01*
G02X653349Y272484I694J1218D01*
G03X653393Y271818I242J-318D01*
G37*
G36*
G01X710700Y273831D02*
G02X709004Y273683I-751J-1184D01*
G03X708949Y274316I-269J295D01*
G02X708692Y276474I751J1184D01*
G03X708670Y277051I-288J278D01*
G02X708511Y277217I930J1049D01*
G03X707889I-311J-252D01*
G02Y278983I-1089J883D01*
G03X708511I311J252D01*
G02X710608Y277126I1090J-882D01*
G03X710630Y276549I288J-278D01*
G02X710645Y274464I-930J-1049D01*
G03X710700Y273831I269J-295D01*
G37*
G36*
G01X1624564Y272426D02*
G02X1624542Y274148I-1117J847D01*
G03X1625174Y274156I313J249D01*
G02X1625196Y272434I1117J-847D01*
G03X1624564Y272426I-313J-249D01*
G37*
G36*
G01X755577Y274494D02*
G02X754007Y274540I-819J-1138D01*
G03X754027Y275202I-214J338D01*
G02X755597Y275156I819J1138D01*
G03X755577Y274494I214J-338D01*
G37*
G36*
G01X128755Y274876D02*
G02X128442Y276539I-1255J625D01*
G03X129069Y276657I269J296D01*
G02X129382Y274994I1255J-625D01*
G03X128755Y274876I-269J-296D01*
G37*
G36*
G01X116300Y278684D02*
G02X114751Y278669I-763J-1176D01*
G03X114744Y279336I-224J331D01*
G02X116293Y279351I763J1176D01*
G03X116300Y278684I224J-331D01*
G37*
G36*
G01X765908D02*
G02X764359Y278669I-763J-1176D01*
G03X764352Y279336I-224J331D01*
G02X765901Y279351I763J1176D01*
G03X765908Y278684I224J-331D01*
G37*
G36*
G01X750187Y280386D02*
G02X748558Y280793I-1087J-886D01*
G03X748713Y281414I-155J369D01*
G02X750342Y281007I1087J886D01*
G03X750187Y280386I155J-369D01*
G37*
G36*
G01X690825Y282220D02*
G02X689271I-777J-1167D01*
G03Y282886I-222J333D01*
G02X690825I777J1167D01*
G03Y282220I222J-333D01*
G37*
G36*
G01X1495494Y282261D02*
G02X1495450Y280598I1106J-861D01*
G03X1494806Y280615I-328J-229D01*
G02X1494850Y282278I-1106J861D01*
G03X1495494Y282261I328J229D01*
G37*
G36*
G01X1405610Y282190D02*
G02X1402952Y282162I-1324J-461D01*
G03X1402465Y282671I-380J124D01*
G02X1403191Y283152I-373J1351D01*
G03X1403465Y282866I157J-124D01*
G02X1403822Y283052I820J-1138D01*
G03X1404068Y283561I-132J378D01*
G02X1405856Y282699I1324J461D01*
G03X1405610Y282190I132J-378D01*
G37*
G36*
G01X684678Y281366D02*
G02X684620Y282940I-1188J744D01*
G03X685282Y282964I323J236D01*
G02X685340Y281390I1188J-744D01*
G03X684678Y281366I-323J-236D01*
G37*
G36*
G01X59894Y282265D02*
G02X59782Y283892I-1194J735D01*
G03X60431Y283936I309J254D01*
G02X60965Y284438I1194J-735D01*
G03X61026Y285104I-188J353D01*
G02X62560Y284963I874J1096D01*
G03X62499Y284297I188J-353D01*
G02X60543Y282309I-874J-1096D01*
G03X59894Y282265I-309J-254D01*
G37*
G36*
G01X766364Y284716D02*
G02X765442Y285696I-1357J-353D01*
G03X765953Y286177I124J380D01*
G02X765923Y286323I1357J355D01*
G03X765406Y286644I-395J-60D01*
G02X766367Y288187I-426J1336D01*
G03X766884Y287866I395J60D01*
G02X766875Y285197I426J-1336D01*
G03X766364Y284716I-124J-380D01*
G37*
G36*
G01X656121Y285442D02*
G02X654689Y285967I-1121J-842D01*
G03X654921Y286597I-88J390D01*
G02X656353Y286072I1121J842D01*
G03X656121Y285442I88J-390D01*
G37*
G36*
G01X1357775Y285582D02*
G02X1357735Y284295I1225J-682D01*
G03X1357025Y284318I-361J-172D01*
G02X1357065Y285605I-1225J682D01*
G03X1357775Y285582I361J172D01*
G37*
G36*
G01X1116937Y288227D02*
G02X1115684Y287313I62J-1401D01*
G03X1115292Y287851I-375J139D01*
G02X1116545Y288765I-62J1401D01*
G03X1116937Y288227I375J-139D01*
G37*
G36*
G01X465845Y293836D02*
G02X464680Y292661I221J-1384D01*
G03X464221Y293116I-396J60D01*
G02X465386Y294291I-221J1384D01*
G03X465845Y293836I396J-60D01*
G37*
G36*
G01X1048213Y293855D02*
G02X1048209Y291958I1289J-951D01*
G03X1047565Y291959I-322J-237D01*
G02X1047569Y293856I-1289J951D01*
G03X1048213Y293855I322J237D01*
G37*
G36*
G01X412461Y292127D02*
G02Y293681I-1167J777D01*
G03X413127I333J222D01*
G02Y292127I1167J-777D01*
G03X412461I-333J-222D01*
G37*
G36*
G01X419661D02*
G02Y293681I-1167J777D01*
G03X420327I333J222D01*
G02Y292127I1167J-777D01*
G03X419661I-333J-222D01*
G37*
G36*
G01X426861D02*
G02Y293681I-1167J777D01*
G03X427527I333J222D01*
G02Y292127I1167J-777D01*
G03X426861I-333J-222D01*
G37*
G36*
G01X434061D02*
G02Y293681I-1167J777D01*
G03X434727I333J222D01*
G02Y292127I1167J-777D01*
G03X434061I-333J-222D01*
G37*
G36*
G01X441261D02*
G02Y293681I-1167J777D01*
G03X441927I333J222D01*
G02Y292127I1167J-777D01*
G03X441261I-333J-222D01*
G37*
G36*
G01X1062069D02*
G02Y293681I-1167J777D01*
G03X1062735I333J222D01*
G02Y292127I1167J-777D01*
G03X1062069I-333J-222D01*
G37*
G36*
G01X1069269D02*
G02Y293681I-1167J777D01*
G03X1069935I333J222D01*
G02Y292127I1167J-777D01*
G03X1069269I-333J-222D01*
G37*
G36*
G01X1076469D02*
G02Y293681I-1167J777D01*
G03X1077135I333J222D01*
G02Y292127I1167J-777D01*
G03X1076469I-333J-222D01*
G37*
G36*
G01X1083669D02*
G02Y293681I-1167J777D01*
G03X1084335I333J222D01*
G02Y292127I1167J-777D01*
G03X1083669I-333J-222D01*
G37*
G36*
G01X1090869D02*
G02Y293681I-1167J777D01*
G03X1091535I333J222D01*
G02Y292127I1167J-777D01*
G03X1090869I-333J-222D01*
G37*
G36*
G01X1321162Y296032D02*
G02X1320246Y295063I438J-1332D01*
G03X1319735Y295546I-387J103D01*
G02X1320651Y296515I-438J1332D01*
G03X1321162Y296032I387J-103D01*
G37*
G36*
G01X1475023Y294968D02*
G02X1473116Y296874I-1225J681D01*
G03Y297573I-194J350D01*
G02X1472573Y298116I682J1225D01*
G03X1471874I-349J-194D01*
G02X1469968Y300023I-1225J682D01*
G03Y300723I-194J350D01*
G02Y303173I681J1225D01*
G03Y303873I-194J350D01*
G02X1469967Y306323I681J1225D01*
G03Y307022I-194J350D01*
G02X1469968Y309472I682J1225D01*
G03Y310172I-194J350D01*
G02X1469967Y312622I681J1225D01*
G03Y313321I-194J350D01*
G02X1471874Y315228I682J1225D01*
G03X1472573I350J194D01*
G02X1474480Y313321I1225J-682D01*
G03Y312622I194J-350D01*
G02X1475023Y312078I-683J-1224D01*
G03X1475723I350J194D01*
G02X1478173I1225J-681D01*
G03X1478873I350J194D01*
G02X1479416Y312622I1226J-680D01*
G03Y313321I-194J350D01*
G02X1481323Y315228I682J1225D01*
G03X1482022I350J194D01*
G02X1484472Y315227I1225J-682D01*
G03X1485172I350J194D01*
G02X1485715Y315771I1226J-680D01*
G03Y316470I-194J349D01*
G02X1487621Y318377I681J1226D01*
G03X1488321I350J194D01*
G02Y317015I1225J-681D01*
G03X1487621I-350J-194D01*
G02X1487078Y316471I-1226J680D01*
G03Y315772I194J-349D01*
G02X1485172Y313865I-681J-1226D01*
G03X1484472I-350J-194D01*
G02X1483929Y313321I-1226J680D01*
G03Y312622I194J-350D01*
G02X1482022Y310715I-682J-1225D01*
G03X1481323I-349J-194D01*
G02X1480779Y310172I-1224J683D01*
G03Y309472I194J-350D01*
G02X1478873Y307566I-681J-1225D01*
G03X1478173I-350J-194D01*
G02X1477630Y307022I-1226J680D01*
G03Y306323I194J-350D01*
G02X1475723Y304417I-682J-1225D01*
G03X1475023I-350J-194D01*
G02X1474479Y303873I-1225J681D01*
G03Y303173I194J-350D01*
G02Y300723I-681J-1225D01*
G03Y300023I194J-350D01*
G02X1475023Y299479I-681J-1225D01*
G03X1475723I350J194D01*
G02X1478173I1225J-681D01*
G03X1478873I350J194D01*
G02X1479417Y300023I1225J-681D01*
G03Y300723I-194J350D01*
G02X1481323Y302630I681J1225D01*
G03X1482022I350J194D01*
G02X1482566Y303173I1224J-683D01*
G03Y303873I-194J350D01*
G02X1484472Y305779I681J1225D01*
G03X1485172I350J194D01*
G02X1485715Y306323I1226J-680D01*
G03Y307022I-194J350D01*
G02X1487622Y308929I682J1225D01*
G03X1488321I350J194D01*
G02X1488865Y309472I1224J-683D01*
G03Y310172I-194J350D01*
G02X1490777Y312067I681J1225D01*
G03X1491478Y312062I352J191D01*
G02X1492031Y312608I1223J-685D01*
G03Y313312I-190J352D01*
G02X1493864Y315321I665J1234D01*
G03X1494531I334J221D01*
G02X1496328Y313293I1168J-775D01*
G03X1496317Y312584I179J-357D01*
G02X1494496Y310555I-666J-1234D01*
G03X1493841Y310561I-330J-226D01*
G02X1491469Y310706I-1141J815D01*
G03X1490768Y310711I-352J-191D01*
G02X1490227Y310172I-1222J686D01*
G03Y309472I194J-350D01*
G02X1488321Y307565I-681J-1225D01*
G03X1487622I-349J-194D01*
G02X1487079Y307022I-1225J682D01*
G03Y306323I194J-350D01*
G02X1487078Y303873I-682J-1225D01*
G03Y303173I194J-350D01*
G02X1487622Y302630I-680J-1226D01*
G03X1488321I350J194D01*
G02Y301266I1225J-682D01*
G03X1487622I-349J-194D01*
G02X1487078Y300723I-1224J683D01*
G03Y300023I194J-350D01*
G02X1487079Y297573I-681J-1225D01*
G03Y296874I194J-349D01*
G02X1485715I-682J-1225D01*
G03Y297573I-194J350D01*
G02X1485172Y298117I683J1224D01*
G03X1484472I-350J-194D01*
G02X1482022Y298116I-1225J681D01*
G03X1481323I-349J-194D01*
G02X1480780Y297573I-1225J682D01*
G03Y296874I194J-349D01*
G02X1478873Y294968I-682J-1225D01*
G03X1478173I-350J-194D01*
G02X1475723I-1225J681D01*
G03X1475023I-350J-194D01*
G37*
G36*
G01X1115777Y297174D02*
G02X1114706Y295993I319J-1365D01*
G03X1114219Y296435I-397J52D01*
G02X1115290Y297616I-319J1365D01*
G03X1115777Y297174I397J-52D01*
G37*
G36*
G01X59608Y298174D02*
G02X57670Y298249I-1008J-974D01*
G03X57692Y298826I-266J299D01*
G02X57830Y300900I1008J975D01*
G03X57808Y301543I-248J313D01*
G02X59470Y301600I792J1157D01*
G03X59492Y300957I248J-313D01*
G02X59630Y298751I-792J-1157D01*
G03X59608Y298174I266J-299D01*
G37*
G36*
G01X672778Y298889D02*
G02X672637Y297518I1144J-810D01*
G03X671944Y297589I-367J-160D01*
G02X669711Y297517I-1144J811D01*
G03X669089I-311J-252D01*
G02Y299283I-1089J883D01*
G03X669711I311J252D01*
G02X672085Y298960I1089J-883D01*
G03X672778Y298889I367J160D01*
G37*
G36*
G01X126357Y299591D02*
G02X124199Y297687I-794J-1275D01*
G03X123515Y297758I-363J-168D01*
G02X121403Y300088I-1284J958D01*
G03X121503Y300687I-206J342D01*
G02X123904Y302807I1228J1029D01*
G03X124490I293J272D01*
G02X126388Y300287I1173J-1091D01*
G03X126357Y299591I181J-357D01*
G37*
G36*
G01X4973Y301570D02*
G02Y303124I-1167J777D01*
G03X5639I333J222D01*
G02Y301570I1167J-777D01*
G03X4973I-333J-222D01*
G37*
G36*
G01X848882Y305666D02*
G02X846464Y307767I-1200J1061D01*
G03Y308287I-304J260D01*
G02X846499Y310407I1218J1040D01*
G03Y310947I-295J270D01*
G02X846225Y311362I1184J1079D01*
G03X845549Y311447I-364J-166D01*
G02X845757Y313115I-1249J1003D01*
G03X846433Y313030I364J166D01*
G02X846464Y313067I1243J-1010D01*
G03Y313587I-304J260D01*
G02X848882Y315688I1218J1040D01*
G03X849482I300J265D01*
G02X851882I1200J-1061D01*
G03X852482I300J265D01*
G02X854882I1200J-1061D01*
G03X855482I300J265D01*
G02X857900Y313587I1200J-1061D01*
G03Y313067I304J-260D01*
G02X857865Y310947I-1218J-1040D01*
G03Y310407I295J-270D01*
G02X857900Y308287I-1183J-1080D01*
G03Y307767I304J-260D01*
G02X855482Y305666I-1218J-1040D01*
G03X854882I-300J-265D01*
G02X852482I-1200J1061D01*
G03X851882I-300J-265D01*
G02X849482I-1200J1061D01*
G03X848882I-300J-265D01*
G37*
G36*
G01X1506795Y307781D02*
G02X1505065Y307774I-861J-1107D01*
G03X1505063Y308403I-248J314D01*
G02X1506793Y308410I861J1107D01*
G03X1506795Y307781I248J-314D01*
G37*
G36*
G01X777591Y306631D02*
G02X777150Y308191I-1321J469D01*
G03X777779Y308369I252J311D01*
G02X778220Y306809I1321J-469D01*
G03X777591Y306631I-252J-311D01*
G37*
G36*
G01X128755Y306876D02*
G02X128442Y308539I-1255J625D01*
G03X129069Y308657I269J296D01*
G02X129382Y306994I1255J-625D01*
G03X128755Y306876I-269J-296D01*
G37*
G36*
G01X1104766Y308814D02*
G02X1102437Y307365I-1010J-972D01*
G03X1101882Y307587I-376J-136D01*
G02X1099937Y308365I-626J1254D01*
G03X1099382Y308587I-376J-136D01*
G02X1097553Y309122I-626J1254D01*
G03X1096875Y309136I-343J-205D01*
G02X1094573Y309072I-1173J768D01*
G03X1093919Y309058I-322J-237D01*
G02X1091553Y309122I-1163J783D01*
G03X1090875Y309136I-343J-205D01*
G02X1090905Y310623I-1173J767D01*
G03X1091583Y310609I343J205D01*
G02X1093885Y310673I1173J-768D01*
G03X1094539Y310687I322J237D01*
G02X1096905Y310623I1163J-783D01*
G03X1097583Y310609I343J205D01*
G02X1100075Y310317I1173J-768D01*
G03X1100630Y310095I376J136D01*
G02X1101805Y310131I626J-1254D01*
G03X1102359Y310464I156J368D01*
G02X1104766Y309368I1397J-123D01*
G03Y308814I288J-277D01*
G37*
G36*
G01X116300Y310684D02*
G02X114751Y310669I-763J-1176D01*
G03X114744Y311336I-224J331D01*
G02X116293Y311351I763J1176D01*
G03X116300Y310684I224J-331D01*
G37*
G36*
G01X765908D02*
G02X764359Y310669I-763J-1176D01*
G03X764352Y311336I-224J331D01*
G02X765901Y311351I763J1176D01*
G03X765908Y310684I224J-331D01*
G37*
G36*
G01X377166Y310554D02*
G02X377121Y309128I1411J-758D01*
G03X376405Y309151I-364J-167D01*
G02X376450Y310577I-1411J758D01*
G03X377166Y310554I364J167D01*
G37*
G36*
G01X369925Y310765D02*
G02X369890Y308978I1312J-920D01*
G03X369226Y308991I-336J-216D01*
G02X369261Y310778I-1312J920D01*
G03X369925Y310765I336J216D01*
G37*
G36*
G01X441282Y309097D02*
G02Y310585I-1188J744D01*
G03X441960I339J213D01*
G02Y309097I1188J-744D01*
G03X441282I-339J-213D01*
G37*
G36*
G01X412461Y309127D02*
G02Y310681I-1167J777D01*
G03X413127I333J222D01*
G02Y309127I1167J-777D01*
G03X412461I-333J-222D01*
G37*
G36*
G01X419661D02*
G02Y310681I-1167J777D01*
G03X420327I333J222D01*
G02Y309127I1167J-777D01*
G03X419661I-333J-222D01*
G37*
G36*
G01X426861D02*
G02Y310681I-1167J777D01*
G03X427527I333J222D01*
G02Y309127I1167J-777D01*
G03X426861I-333J-222D01*
G37*
G36*
G01X434061D02*
G02Y310681I-1167J777D01*
G03X434727I333J222D01*
G02Y309127I1167J-777D01*
G03X434061I-333J-222D01*
G37*
G36*
G01X1062069D02*
G02Y310681I-1167J777D01*
G03X1062735I333J222D01*
G02Y309127I1167J-777D01*
G03X1062069I-333J-222D01*
G37*
G36*
G01X1069269D02*
G02Y310681I-1167J777D01*
G03X1069935I333J222D01*
G02Y309127I1167J-777D01*
G03X1069269I-333J-222D01*
G37*
G36*
G01X1076469D02*
G02Y310681I-1167J777D01*
G03X1077135I333J222D01*
G02Y309127I1167J-777D01*
G03X1076469I-333J-222D01*
G37*
G36*
G01X1083669D02*
G02Y310681I-1167J777D01*
G03X1084335I333J222D01*
G02Y309127I1167J-777D01*
G03X1083669I-333J-222D01*
G37*
G36*
G01X77011Y310638D02*
G02X74355Y309826I-1385J-221D01*
G03X73684Y309910I-362J-170D01*
G02X73871Y311392I-1084J890D01*
G03X74542Y311308I362J170D01*
G02X75699Y311818I1083J-890D01*
G03X76115Y312280I21J399D01*
G02X76713Y313660I1385J220D01*
G03X76668Y314348I-225J331D01*
G02X78087Y314440I631J1252D01*
G03X78132Y313752I225J-331D01*
G02X77427Y311100I-632J-1252D01*
G03X77011Y310638I-21J-399D01*
G37*
G36*
G01X766382Y316635D02*
G02X765182Y317754I-1375J-272D01*
G03X765625Y318228I50J397D01*
G02X765973Y319454I1375J272D01*
G03X765913Y320051I-293J272D01*
G02X767759Y320235I819J1138D01*
G03X767819Y319638I293J-272D01*
G02X766825Y317109I-819J-1138D01*
G03X766382Y316635I-50J-397D01*
G37*
G36*
G01X76830Y321972D02*
G02X76259Y320391I770J-1172D01*
G03X75657Y320608I-382J-117D01*
G02X73796Y320899I-770J1172D01*
G03X73178Y320903I-311J-252D01*
G02X73191Y322681I-1078J897D01*
G03X73809Y322677I311J252D01*
G02X76228Y322189I1078J-897D01*
G03X76830Y321972I382J117D01*
G37*
G36*
G01X94042Y324546D02*
G02X93615Y323004I896J-1078D01*
G03X92982Y323179I-377J-132D01*
G02X93409Y324721I-896J1078D01*
G03X94042Y324546I377J132D01*
G37*
G36*
G01X688114Y326341D02*
G02X686563Y326393I-815J-1141D01*
G03X686586Y327059I-210J341D01*
G02X688137Y327007I815J1141D01*
G03X688114Y326341I210J-341D01*
G37*
G36*
G01X637524Y328453D02*
G02X635905Y327850I-381J-1453D01*
G03X635691Y328459I-330J226D01*
G02X636069Y331202I409J1341D01*
G03X636420Y331777I-8J400D01*
G02X637712Y330988I1261J613D01*
G03X637361Y330413I8J-400D01*
G02X637286Y329053I-1261J-613D01*
G03X637524Y328453I339J-213D01*
G37*
G36*
G01X195992Y326582D02*
G02X193556Y326623I-1200J1061D01*
G03X192957Y326643I-308J-254D01*
G02X190464Y326847I-1165J1100D01*
G03X189837Y326893I-332J-224D01*
G02X187593Y329173I-1184J1079D01*
G03Y329773I-265J300D01*
G02X187561Y332145I1061J1201D01*
G03X187557Y332734I-273J293D01*
G02X187430Y332862I1072J1190D01*
G03X186830I-300J-265D01*
G02X184441Y334997I-1199J1062D01*
G03X184375Y335592I-297J268D01*
G02X184064Y335880I924J1309D01*
G03X183465Y335900I-308J-254D01*
G02X181100Y335939I-1165J1100D01*
G03X180500I-300J-265D01*
G02X178100I-1200J1061D01*
G03X177500I-300J-265D01*
G02X175100I-1200J1061D01*
G03X174500I-300J-265D01*
G02X172195Y338160I-1200J1061D01*
G03Y338740I-275J290D01*
G02X172558Y341320I1105J1160D01*
G03Y342028I-186J354D01*
G02X174500Y344509I742J1420D01*
G03X175100I300J265D01*
G02X177500I1200J-1061D01*
G03X178100I300J265D01*
G02X180500I1200J-1061D01*
G03X181100I300J265D01*
G02X183536Y344468I1200J-1061D01*
G03X184135Y344448I308J254D01*
G02X186500Y344409I1165J-1100D01*
G03X187100I300J265D01*
G02X189536Y344368I1200J-1061D01*
G03X190135Y344348I308J254D01*
G02X192114Y341868I1165J-1100D01*
G03Y341180I204J-344D01*
G02X190064Y338780I-815J-1380D01*
G03X189465Y338800I-308J-254D01*
G02X189361Y338700I-1161J1104D01*
G03Y338100I265J-300D01*
G02X189489Y335826I-1061J-1200D01*
G03X189555Y335231I297J-268D01*
G02X189723Y332751I-925J-1308D01*
G03X189727Y332162I273J-293D01*
G02X189715Y329773I-1073J-1189D01*
G03Y329173I265J-300D01*
G02X189982Y328869I-1060J-1201D01*
G03X190609Y328823I332J224D01*
G02X193028Y328763I1183J-1080D01*
G03X193627Y328743I308J254D01*
G02X195992Y328704I1165J-1100D01*
G03X196592I300J265D01*
G02Y326582I1200J-1061D01*
G03X195992I-300J-265D01*
G37*
G36*
G01X1514594Y328782D02*
G02X1513308Y328680I-545J-1292D01*
G03X1513252Y329388I-211J340D01*
G02X1514538Y329490I545J1292D01*
G03X1514594Y328782I211J-340D01*
G37*
G36*
G01X126430Y331542D02*
G02X124199Y329687I-867J-1226D01*
G03X123515Y329758I-363J-168D01*
G02X121500Y332142I-1284J958D01*
G03X121600Y332781I-182J356D01*
G02X124009Y334882I1131J1134D01*
G03X124562Y334799I319J241D01*
G02X126429Y332195I938J-1299D01*
G03X126430Y331542I232J-326D01*
G37*
G36*
G01X1106728Y335132D02*
G02X1104994Y335070I-828J-1132D01*
G03X1104972Y335698I-258J305D01*
G02X1106706Y335760I828J1132D01*
G03X1106728Y335132I258J-305D01*
G37*
G36*
G01X451673Y334540D02*
G02X449473Y334871I-973J1010D01*
G03X448830Y334949I-350J-194D01*
G02X449027Y336579I-1030J951D01*
G03X449670Y336501I350J194D01*
G02X451673Y336560I1030J-951D01*
G03X452227I277J288D01*
G02Y334540I973J-1010D01*
G03X451673I-277J-288D01*
G37*
G36*
G01X1093950Y606510D02*
G03X1094379Y606112I400J1D01*
G02Y603116I109J-1498D01*
G03X1093950Y602718I-29J-399D01*
G01Y595455D01*
G03X1094380Y595057I400J1D01*
G02Y592261I108J-1398D01*
G03X1093950Y591863I-30J-399D01*
G01Y587518D01*
G03X1094380Y587120I400J1D01*
G02X1095374Y584636I108J-1398D01*
G03X1095344Y584043I253J-310D01*
G01X1099074Y580314D01*
Y576375D01*
G02X1097891Y575174I-1201J0D01*
G03Y574372I7J-401D01*
G02X1099074Y573171I-18J-1201D01*
G01Y570993D01*
G02X1097798Y569599I-1402J2D01*
G03Y568801I36J-399D01*
G02X1099074Y567407I-126J-1396D01*
G01Y553732D01*
X1098193Y553486D01*
G03Y552714I107J-386D01*
G01X1099074Y552468D01*
Y550401D01*
X1098059Y550239D01*
X1098057Y550238D01*
G03Y549448I61J-395D01*
G01X1098059Y549447D01*
X1099074Y549285D01*
Y537235D01*
X1097998Y537121D01*
G03X1097819Y536390I43J-398D01*
G02X1097911Y534123I-777J-1167D01*
G03X1097874Y533529I249J-314D01*
G02X1097763Y531465I-1001J-981D01*
G03X1097981Y530757I255J-309D01*
G02X1099074Y529561I-109J-1197D01*
G01Y515932D01*
X1098193Y515686D01*
G03X1097944Y515117I107J-386D01*
G02X1097200Y513168I-1247J-641D01*
G03X1097417Y512401I144J-373D01*
G02X1099074Y511024I255J-1378D01*
G01Y497542D01*
X1069204Y467672D01*
Y399687D01*
X1067758Y398242D01*
X1066402Y396886D01*
Y396857D01*
X1064666Y395121D01*
Y395087D01*
X1063423Y393845D01*
G02X1061847Y393562I-991J991D01*
G02X1060933Y392978I-1153J797D01*
G02X1060795Y392375I-1401J3D01*
G03X1061053Y391815I361J-173D01*
G02X1060779Y389061I-360J-1355D01*
G03X1060404Y388663I25J-399D01*
G01Y388357D01*
G03X1060779Y387959I400J1D01*
G02Y385161I-85J-1399D01*
G03X1060404Y384763I25J-399D01*
G01Y384457D01*
G03X1060779Y384059I400J1D01*
G02Y381261I-85J-1399D01*
G03X1060404Y380863I25J-399D01*
G01Y380557D01*
G03X1060779Y380159I400J1D01*
G02Y377361I-85J-1399D01*
G03X1060404Y376963I25J-399D01*
G01Y375213D01*
X1060320Y375004D01*
G03Y374716I374J-144D01*
G01X1060404Y374507D01*
Y372753D01*
G03X1060839Y372355I400J0D01*
G02Y369563I124J-1396D01*
G03X1060404Y369165I-35J-398D01*
G01Y366615D01*
X1073802Y353217D01*
Y348330D01*
G03X1074257Y347934I400J0D01*
G02Y345158I195J-1388D01*
G03X1073802Y344762I-55J-396D01*
G01Y342287D01*
X1074596Y341492D01*
X1081604D01*
X1082747Y340349D01*
X1082861Y340381D01*
G02X1084465Y339942I441J-1540D01*
G03X1085029Y339925I291J275D01*
G02X1084962Y337657I1097J-1167D01*
G03X1084398Y337674I-291J-275D01*
G02X1083132Y337248I-1097J1167D01*
G03X1082690Y336851I-42J-398D01*
G01Y335652D01*
X1081538Y334498D01*
X1031302D01*
X1027896Y337905D01*
X1027818Y337908D01*
G02X1026474Y339252I57J1401D01*
G01X1026471Y339330D01*
X1023183Y342618D01*
G02X1021203Y344598I-938J1042D01*
G01X1018818Y346983D01*
G02X1018422Y348179I991J992D01*
G02X1017595Y348914I442J1330D01*
G01X1016877D01*
G02X1016601Y348942I3J1402D01*
G03X1016428Y348598I-39J-196D01*
G02X1014542I-943J-1038D01*
G03X1014369Y348942I-134J148D01*
G02X1014093Y348914I-279J1374D01*
G01X1013375D01*
G02X1010835I-1270J595D01*
G01X1010117D01*
G02X1009841Y348942I3J1402D01*
G03X1009668Y348598I-39J-196D01*
G02X1007782I-943J-1038D01*
G03X1007609Y348942I-134J148D01*
G02X1007333Y348914I-279J1374D01*
G01X1006022D01*
X1005715Y349660D01*
Y349661D01*
G03X1004975I-370J-152D01*
G01Y349660D01*
X1004668Y348914D01*
X1003357D01*
G02X1003081Y348942I3J1402D01*
G03X1002908Y348598I-39J-196D01*
G02X1001862Y348958I-942J-1038D01*
G03X1002171Y349570I-30J399D01*
G02X1001979Y350058I1185J748D01*
G02X1000726Y350803I-14J1402D01*
G02X999531Y350962I-431J1334D01*
G01X997715D01*
X997261Y351416D01*
G03X996585Y351206I-283J-283D01*
G02X995281Y352860I-1379J254D01*
G03X995702Y353259I21J399D01*
G01Y353561D01*
G03X995281Y353960I-400J0D01*
G02Y356760I-75J1400D01*
G03X995702Y357159I21J399D01*
G01Y361361D01*
G03X995281Y361760I-400J0D01*
G02Y364560I-75J1400D01*
G03X995702Y364959I21J399D01*
G01Y365261D01*
G03X995281Y365660I-400J0D01*
G02Y368460I-75J1400D01*
G03X995702Y368859I21J399D01*
G01Y369160D01*
G03X995281Y369559I-400J0D01*
G02Y372359I-75J1400D01*
G03X995702Y372758I21J399D01*
G01Y373061D01*
G03X995281Y373460I-400J0D01*
G02X994117Y375743I-75J1400D01*
G03X994108Y376005I-155J126D01*
G02X993734Y376904I1026J954D01*
G03X993350Y377288I-400J-16D01*
G02X992415Y377697I56J1400D01*
G01X991868Y378243D01*
G02X991464Y379355I992J990D01*
G02X991148Y381936I362J1354D01*
G01Y383382D01*
G02X990490Y385034I678J1227D01*
G01X990500Y385064D01*
Y386354D01*
X986604Y390249D01*
Y398495D01*
X986616Y398507D01*
Y465198D01*
X959492Y492323D01*
Y503066D01*
X959504Y503078D01*
Y507794D01*
X958884Y508415D01*
X959539Y509066D01*
X959433Y509206D01*
G02X959127Y510078I1196J909D01*
G02X957894Y511469I168J1391D01*
G01Y512261D01*
X958104Y512568D01*
G03X957911Y513170I-330J226D01*
G01X957658Y513261D01*
X956988Y513931D01*
Y516679D01*
X956849Y516724D01*
G02X956876Y519399I434J1333D01*
G01X957018Y519442D01*
Y527703D01*
G02Y530023I788J1160D01*
G01Y532099D01*
X957574Y532654D01*
X957755Y532730D01*
G03X957761Y533467I-155J370D01*
G01X957565Y533546D01*
X957018Y534081D01*
Y536322D01*
X957494Y536616D01*
G03Y537298I-211J341D01*
G01X957018Y537592D01*
Y547565D01*
X957494Y547859D01*
G03Y548541I-211J341D01*
G01X957018Y548835D01*
Y551339D01*
X957828Y551621D01*
X957831Y551622D01*
G03Y552378I-130J378D01*
G01X957828Y552379D01*
X957018Y552661D01*
Y554472D01*
X956876Y554515D01*
G02Y557199I407J1342D01*
G01X957018Y557242D01*
Y559203D01*
X955802Y560419D01*
Y565035D01*
G02X956331Y566131I1402J-1D01*
G02Y567355I1261J612D01*
G02X955802Y568451I873J1097D01*
G01Y569142D01*
G02X957512Y570509I1402J0D01*
G03Y571291I88J391D01*
G02X955927Y572080I-308J1367D01*
G03X955221Y572122I-364J-165D01*
G02X955259Y573610I-1285J777D01*
G03X955965Y573612I352J189D01*
G02X957266Y574357I1239J-655D01*
G03Y575157I17J400D01*
G02X955802Y576557I-62J1400D01*
G01Y586550D01*
G02X957400Y587938I1402J0D01*
G03X957730Y588626I56J396D01*
G02X957765Y590699I960J1021D01*
G03X957736Y591324I-265J301D01*
G02X957173Y592259I824J1133D01*
G02X956150Y594483I110J1398D01*
G02X955802Y595407I1054J924D01*
G01Y605508D01*
G02X956464Y606698I1402J-1D01*
G02X956727Y608162I1301J522D01*
G02X956842Y610011I1107J859D01*
G01X957736Y610905D01*
Y612461D01*
X961223Y615948D01*
X1028255D01*
G02X1029591Y614971I0J-1402D01*
G02X1029963I186J-1390D01*
G02X1031299Y615948I1336J-425D01*
G01X1031833D01*
G02X1032973Y613733I-1J-1401D01*
G03X1033426Y613120I326J-233D01*
G02X1034573Y613000I441J-1331D01*
G03X1034838Y613058I101J172D01*
G02X1038102Y614594I2959J-2053D01*
G03X1038317Y614762I17J199D01*
G02X1039700Y615948I1385J-216D01*
G01X1043660D01*
X1044318Y615289D01*
G02X1044715Y614099I-990J-992D01*
G02X1045099Y613924I-425J-1441D01*
G02X1046160Y614410I1061J-915D01*
G01X1049115D01*
G02X1050176Y613924I0J-1401D01*
G02X1051792I808J-1266D01*
G02X1052853Y614410I1061J-915D01*
G01X1062502D01*
G02X1063562Y613924I-1J-1401D01*
G02X1065176I807J-1267D01*
G02X1066236Y614410I1061J-915D01*
G01X1069296D01*
G02X1070440Y613817I-1J-1401D01*
G02X1071684I622J-1257D01*
G02X1072828Y614410I1145J-808D01*
G01X1075888D01*
G02X1076948Y613924I-1J-1401D01*
G02X1078562I807J-1267D01*
G02X1079622Y614410I1061J-915D01*
G01X1082581D01*
G02X1083641Y613924I-1J-1401D01*
G02X1085255I807J-1267D01*
G02X1086315Y614410I1061J-915D01*
G01X1090007D01*
X1090050Y614454D01*
X1092694D01*
X1093950Y613196D01*
Y611760D01*
G03X1094379Y611362I400J1D01*
G02Y608366I109J-1498D01*
G03X1093950Y607968I-29J-399D01*
G01Y606510D01*
G37*
G36*
G01X69546Y336983D02*
G02X67743Y337379I-1128J-833D01*
G03X67872Y337967I-193J350D01*
G02X67735Y338195I1128J833D01*
G03X67025Y338218I-361J-172D01*
G02X64643Y338108I-1225J682D01*
G03X64000Y338130I-330J-226D01*
G02X64057Y339792I-1100J870D01*
G03X64700Y339770I330J226D01*
G02X67065Y339505I1100J-870D01*
G03X67775Y339482I361J172D01*
G02X70167Y339577I1225J-682D01*
G03X70833I333J222D01*
G02X73073Y339702I1167J-777D01*
G03X73695Y339713I307J257D01*
G02X73727Y337948I1105J-863D01*
G03X73105Y337937I-307J-257D01*
G02X70833Y338023I-1105J863D01*
G03X70167I-333J-222D01*
G02X69675Y337571I-1167J777D01*
G03X69546Y336983I193J-350D01*
G37*
G36*
G01X1409740Y336269D02*
G02X1408622Y337811I-1392J167D01*
G03X1409097Y338155I78J392D01*
G02X1409130Y338332I1392J-168D01*
G03X1408866Y338568I-194J49D01*
G02X1409775Y339789I-490J1314D01*
G03X1410244Y339368I399J-27D01*
G02X1410215Y336613I245J-1380D01*
G03X1409740Y336269I-78J-392D01*
G37*
G36*
G01X1101253Y337632D02*
G02X1101084Y336002I1047J-932D01*
G03X1100438Y336069I-347J-199D01*
G02X1100607Y337699I-1047J932D01*
G03X1101253Y337632I347J199D01*
G37*
G36*
G01X1483734Y337311D02*
G02X1482776Y338273I-1348J-385D01*
G03X1483272Y338767I112J384D01*
G02X1483219Y339088I1348J387D01*
G03X1482768Y339466I-399J-18D01*
G02X1483986Y340920I-183J1390D01*
G03X1484437Y340542I399J18D01*
G02X1484230Y337805I183J-1390D01*
G03X1483734Y337311I-112J-384D01*
G37*
G36*
G01X346090Y361361D02*
G03X345670Y361760I-400J0D01*
G02Y364560I-72J1400D01*
G03X346090Y364959I20J399D01*
G01Y365261D01*
G03X345670Y365660I-400J0D01*
G02Y368460I-72J1400D01*
G03X346090Y368859I20J399D01*
G01Y369160D01*
G03X345670Y369559I-400J0D01*
G02Y372359I-72J1400D01*
G03X346090Y372758I20J399D01*
G01Y373061D01*
G03X345670Y373460I-400J0D01*
G02X345387Y376246I-71J1400D01*
G03X345676Y376836I-60J395D01*
G02X345509Y377361I1226J679D01*
G02X344199Y378671I89J1399D01*
G02X343363Y379073I155J1393D01*
G01X342938Y379498D01*
X342811Y379439D01*
G02X341165Y381635I-593J1270D01*
G03X341149Y382181I-300J264D01*
G01X341136Y382194D01*
X341636Y382689D01*
Y383333D01*
G02X340939Y385183I582J1276D01*
G01X340996Y385309D01*
X339814Y386490D01*
Y387012D01*
G02X340179Y387954I1402J-1D01*
G03X340105Y388556I-296J269D01*
G02X339893Y388729I776J1167D01*
G01X337016Y391606D01*
Y465198D01*
X309020Y493195D01*
Y508310D01*
G02X309657Y509484I1401J-1D01*
G02Y510744I1364J630D01*
G02X309020Y511918I764J1175D01*
G01Y512811D01*
X307202Y514629D01*
Y516731D01*
X307086Y516785D01*
G02Y519329I589J1272D01*
G01X307202Y519383D01*
Y527877D01*
G02X307646Y530152I996J986D01*
G02X308006Y531373I1377J257D01*
G01Y532534D01*
X308282Y532824D01*
G03Y533376I-290J276D01*
G01X308006Y533666D01*
Y536679D01*
X308060Y536846D01*
G03Y537068I-385J111D01*
G01X308006Y537235D01*
Y547922D01*
X308060Y548089D01*
G03Y548311I-385J111D01*
G01X308006Y548478D01*
Y551395D01*
X308359Y551695D01*
G03X308176Y552393I-259J305D01*
G01X307202Y552580D01*
Y554531D01*
X307086Y554585D01*
G02Y557129I589J1272D01*
G01X307202Y557183D01*
Y565580D01*
G02Y567906I782J1163D01*
G01Y568610D01*
X307194Y568617D01*
Y570006D01*
X307855Y570666D01*
X308240D01*
X308382Y570808D01*
G03X307874Y571283I-390J92D01*
G02X306221Y571969I-413J1339D01*
G03X305543Y572018I-354J-186D01*
G02X305595Y573706I-1215J882D01*
G03X306272Y573710I337J215D01*
G02X307627Y574359I1189J-742D01*
G03Y575155I48J398D01*
G02X306060Y576546I-166J1391D01*
G01Y586575D01*
G02X307762Y587943I1401J-1D01*
G03X308122Y588626I86J391D01*
G02X308157Y590699I960J1021D01*
G03X308128Y591324I-265J301D01*
G02X307565Y592259I824J1133D01*
G02X306631Y594593I110J1398D01*
G02X306370Y595406I1141J815D01*
G01Y605461D01*
G02X306916Y606569I1401J-2D01*
G02Y607871I1241J651D01*
G02X306370Y608979I855J1110D01*
G01Y609635D01*
X311261Y614526D01*
X326695D01*
G02X327306Y613891I-653J-1240D01*
G02X328202I448J-1434D01*
G02X329466Y614688I1264J-604D01*
G01X332735D01*
G02X333999Y613891I0J-1401D01*
G02X334895I448J-1434D01*
G02X336159Y614688I1264J-604D01*
G01X346173D01*
G02X347471Y613815I0J-1402D01*
G02X348195I362J-1458D01*
G02X349493Y614688I1298J-529D01*
G01X352865D01*
G02X354162Y613816I-1J-1402D01*
G02X354888I363J-1458D01*
G02X356185Y614688I1298J-530D01*
G01X359630D01*
G02X360961Y613722I-1J-1402D01*
G02X362643Y612717I257J-1480D01*
G02X363140I249J-1379D01*
G02X364822Y613722I1425J-475D01*
G02X366153Y614688I1332J-436D01*
G01X369537D01*
G02X370831Y613822I-1J-1402D01*
G02X371437I303J-1369D01*
G02X372731Y614688I1295J-536D01*
G01X383774D01*
X384993Y613468D01*
G03X385567Y613476I283J283D01*
G02X390092Y614062I2620J-2471D01*
G03X390359Y614113I106J169D01*
G02X391490Y614688I1132J-827D01*
G01X392888D01*
G02X394075Y614031I-1J-1402D01*
G02X395289I607J-1374D01*
G02X396476Y614688I1188J-745D01*
G01X399581D01*
G02X400767Y614031I-1J-1401D01*
G02X401985I609J-1373D01*
G02X403171Y614688I1187J-744D01*
G01X412967D01*
G02X414154Y614031I-1J-1402D01*
G02X415368I607J-1374D01*
G02X416555Y614688I1188J-745D01*
G01X418606D01*
X419822Y613471D01*
G03X420404Y613489I283J283D01*
G02X422565Y613415I1050J-929D01*
G03X423165Y613376I317J244D01*
G01X423905Y614116D01*
X426246D01*
G02X427153Y613783I0J-1402D01*
G02X429141I994J-1126D01*
G02X430048Y614116I907J-1069D01*
G01X432939D01*
G02X433846Y613783I0J-1402D01*
G02X435834I994J-1126D01*
G02X436741Y614116I907J-1069D01*
G01X443707D01*
X445646Y612177D01*
Y611156D01*
G02Y608572I-766J-1292D01*
G01Y605906D01*
G02Y603322I-766J-1292D01*
G01Y596393D01*
X445661Y596377D01*
Y594823D01*
G02Y592495I-781J-1164D01*
G01Y586886D01*
G02X445662Y584558I-781J-1164D01*
G01Y583063D01*
X450404Y578320D01*
Y576428D01*
G02X448449Y575141I-1401J0D01*
G03Y574405I-158J-368D01*
G02X450404Y573118I554J-1287D01*
G01Y570825D01*
G02X448399Y569561I-1401J1D01*
G03Y568839I-173J-361D01*
G02X450268Y568178I604J-1265D01*
G03X450827Y568003I361J172D01*
G02X450966Y565325I746J-1304D01*
G03X450404Y564959I-162J-366D01*
G01Y557697D01*
G03X450966Y557331I400J0D01*
G02X450883Y554623I607J-1374D01*
G03X450322Y554403I-184J-355D01*
G02X448761Y553495I-1319J472D01*
G03Y552705I-69J-395D01*
G02X450404Y551325I242J-1380D01*
G01Y550086D01*
X448927D01*
X448682Y550205D01*
G03X448620Y549457I-171J-362D01*
G02X450404Y548110I383J-1348D01*
G01Y538432D01*
G02X448559Y537103I-1401J0D01*
G03X448177Y536415I-126J-380D01*
G02X448274Y534344I-894J-1080D01*
G03X448305Y533750I283J-283D01*
G02X448189Y531491I-884J-1087D01*
G03X448541Y530778I220J-335D01*
G02X450163Y530241I462J-1323D01*
G03X450721Y530136I331J224D01*
G02X450966Y527525I852J-1237D01*
G03X450404Y527159I-162J-366D01*
G01Y519897D01*
G03X450966Y519531I400J0D01*
G02Y516783I607J-1374D01*
G03X450404Y516417I-162J-366D01*
G01Y510171D01*
X449520Y509287D01*
Y497502D01*
X419604Y467585D01*
Y399778D01*
X415248Y395422D01*
Y365227D01*
X415184Y365163D01*
Y360343D01*
X423522Y352005D01*
Y348094D01*
G03X424126Y347750I400J0D01*
G02Y345342I718J-1204D01*
G03X423522Y344998I-204J-344D01*
G01Y344510D01*
X431807D01*
X432894Y343422D01*
Y337196D01*
X431557Y335858D01*
X391385D01*
X385392Y341851D01*
X385288Y341832D01*
G02X383650Y343470I-261J1377D01*
G01X383669Y343574D01*
X378012Y349231D01*
G03X377349Y349073I-283J-283D01*
G02X374623Y349656I-1332J437D01*
G03X374226Y350098I-398J42D01*
G01X372972D01*
X372950Y350093D01*
G02X372324I-313J1367D01*
G01X372302Y350098D01*
X371048D01*
G03X370651Y349656I1J-400D01*
G02X367863I-1394J-147D01*
G03X367466Y350098I-398J42D01*
G01X366212D01*
X366190Y350093D01*
G02X365564I-313J1367D01*
G01X365542Y350098D01*
X364288D01*
G03X363891Y349656I1J-400D01*
G02X361103I-1394J-147D01*
G03X360706Y350098I-398J42D01*
G01X359452D01*
X359430Y350093D01*
G02X358804I-313J1367D01*
G01X358782Y350098D01*
X352692D01*
X352670Y350093D01*
G02X352044I-313J1367D01*
G01X352022Y350098D01*
X351441D01*
X349454Y352085D01*
X349343Y352055D01*
G02X347624Y353774I-365J1354D01*
G01X347654Y353885D01*
X347163Y354377D01*
G03X346596Y354375I-283J-283D01*
G02X345670Y356760I-998J985D01*
G03X346090Y357159I20J399D01*
G01Y361361D01*
G37*
G36*
G01X53874Y338591D02*
G02X52942Y338875I-849J-1116D01*
G03X53248Y339502I-23J399D01*
G02X55802Y340299I1152J798D01*
G03X56224Y339900I400J0D01*
G02X57463Y339283I76J-1400D01*
G03X58162Y339350I331J224D01*
G02X58289Y338017I1290J-550D01*
G03X57590Y337950I-331J-224D01*
G02X54898Y338501I-1290J550D01*
G03X54476Y338900I-400J0D01*
G02X54045Y338944I-75J1400D01*
G03X53874Y338591I-50J-194D01*
G37*
G36*
G01X1488712Y338646D02*
G02X1487060Y338620I-808J-1146D01*
G03X1487050Y339266I-240J319D01*
G02X1488702Y339292I808J1146D01*
G03X1488712Y338646I240J-319D01*
G37*
G36*
G01X99363Y339304D02*
G02X97886Y339236I-684J-1224D01*
G03X97855Y339915I-226J330D01*
G02X99332Y339983I684J1224D01*
G03X99363Y339304I226J-330D01*
G37*
G36*
G01X128370Y338700D02*
G02X127731Y340196I-1370J299D01*
G03X128330Y340452I208J341D01*
G02X128969Y338956I1370J-299D01*
G03X128370Y338700I-208J-341D01*
G37*
G36*
G01X1564167Y340223D02*
G02Y341777I-1167J777D01*
G03X1564833I333J222D01*
G02Y340223I1167J-777D01*
G03X1564167I-333J-222D01*
G37*
G36*
G01X116300Y342684D02*
G02X114751Y342669I-763J-1176D01*
G03X114744Y343336I-224J331D01*
G02X116293Y343351I763J1176D01*
G03X116300Y342684I224J-331D01*
G37*
G36*
G01X765908D02*
G02X764359Y342669I-763J-1176D01*
G03X764352Y343336I-224J331D01*
G02X765901Y343351I763J1176D01*
G03X765908Y342684I224J-331D01*
G37*
G36*
G01X50027Y344982D02*
G02X48007I-1010J-973D01*
G03Y345536I-288J277D01*
G02X48048Y347522I1010J973D01*
G03X48070Y348077I-277J289D01*
G02X48097Y349971I1047J932D01*
G03X48091Y350526I-291J274D01*
G02X48312Y352675I1000J983D01*
G03X48314Y353339I-222J333D01*
G02X49879Y353334I786J1161D01*
G03X49877Y352670I222J-333D01*
G02X50336Y352153I-786J-1161D01*
G03X50960Y352040I355J184D01*
G02X50557Y350596I940J-1041D01*
G03X50207Y350660I-191J-57D01*
G02X50111Y350547I-1115J850D01*
G03X50117Y349992I291J-274D01*
G02X50086Y347996I-1000J-983D01*
G03X50064Y347441I277J-289D01*
G02X50244Y347187I-1047J-933D01*
G03X50889Y347111I350J194D01*
G02X50696Y345486I1034J-947D01*
G03X50051Y345562I-350J-194D01*
G02X50027Y345536I-1042J938D01*
G03Y344982I288J-277D01*
G37*
G36*
G01X102884Y347278D02*
G02X101000Y347391I-1004J-978D01*
G03X101036Y347982I-251J312D01*
G02X101165Y350055I1004J978D01*
G03X101169Y350676I-250J312D01*
G02X101336Y352959I891J1082D01*
G03X101358Y353630I-207J343D01*
G02X102884Y353580I802J1150D01*
G03X102862Y352909I207J-343D01*
G02X102935Y350664I-802J-1150D01*
G03X102931Y350043I250J-312D01*
G02X102920Y347869I-891J-1083D01*
G03X102884Y347278I251J-312D01*
G37*
G36*
G01X1331530Y347307D02*
G02X1331474Y345600I1083J-890D01*
G03X1330840Y345621I-325J-233D01*
G02X1330896Y347328I-1083J890D01*
G03X1331530Y347307I325J233D01*
G37*
G36*
G01X65595Y349131D02*
G02X65121Y347275I755J-1181D01*
G03X64555Y347419I-350J-193D01*
G02X62757Y347664I-755J1181D01*
G03X62113Y347597I-298J-267D01*
G02X61943Y349236I-1213J702D01*
G03X62587Y349303I298J267D01*
G02X65029Y349275I1213J-703D01*
G03X65595Y349131I350J193D01*
G37*
G36*
G01X1644113Y349711D02*
G02X1642615Y349988I-963J-1019D01*
G03X1642737Y350648I-153J370D01*
G02X1644235Y350371I963J1019D01*
G03X1644113Y349711I153J-370D01*
G37*
G36*
G01X1338882Y350962D02*
G02X1338203Y349606I715J-1206D01*
G03X1337601Y349907I-398J-43D01*
G02X1338280Y351263I-715J1206D01*
G03X1338882Y350962I398J43D01*
G37*
G36*
G01X1588979Y351651D02*
G02X1588978Y350340I1239J-656D01*
G03X1588271I-354J-187D01*
G02X1588272Y351651I-1239J656D01*
G03X1588979I354J187D01*
G37*
G36*
G01X696449Y352760D02*
G02X695006Y352697I-659J-1460D01*
G03X694996Y353401I-195J349D01*
G02X694719Y355697I648J1243D01*
G03X694731Y356287I-264J300D01*
G02X696625Y356247I969J1013D01*
G03X696613Y355657I264J-300D01*
G02X696398Y353462I-969J-1013D01*
G03X696449Y352760I215J-337D01*
G37*
G36*
G01X1508004Y354215D02*
G02X1506340Y354241I-850J-1115D01*
G03X1506350Y354885I-232J326D01*
G02X1506271Y357050I850J1115D01*
G03Y357650I-265J300D01*
G02X1508129I929J1050D01*
G03Y357050I265J-300D01*
G02X1508014Y354859I-929J-1050D01*
G03X1508004Y354215I232J-326D01*
G37*
G36*
G01X1464743Y358094D02*
G02X1462744Y358356I-1126J-835D01*
G03X1462816Y358907I-249J313D01*
G02X1462742Y359017I1125J837D01*
G03X1462092Y359067I-343J-206D01*
G02X1461366Y361323I-1076J898D01*
G03X1461851Y361819I100J387D01*
G02X1464431Y361528I1349J381D01*
G03X1464595Y360983I351J-192D01*
G02X1464815Y358645I-653J-1241D01*
G03X1464743Y358094I249J-313D01*
G37*
G36*
G01X1539469Y360376D02*
G02X1537451Y360293I-969J-1013D01*
G03X1537428Y360848I-299J266D01*
G02X1537462Y362906I969J1013D01*
G03X1537418Y363536I-267J298D01*
G02X1539135Y363655I782J1164D01*
G03X1539179Y363025I267J-298D01*
G02X1539446Y360931I-782J-1164D01*
G03X1539469Y360376I299J-266D01*
G37*
G36*
G01X1343883Y360683D02*
G02X1343419Y359074I848J-1116D01*
G03X1342802Y359252I-375J-141D01*
G02X1343266Y360861I-848J1116D01*
G03X1343883Y360683I375J141D01*
G37*
G36*
G01X102517Y361294D02*
G02X100999Y361304I-767J-1174D01*
G03X101003Y361976I-215J337D01*
G02X102521Y361966I767J1174D01*
G03X102517Y361294I215J-337D01*
G37*
G36*
G01X1559790Y361274D02*
G02X1558147Y361257I-810J-1144D01*
G03X1558140Y361906I-238J322D01*
G02X1559783Y361923I810J1144D01*
G03X1559790Y361274I238J-322D01*
G37*
G36*
G01X1357712Y360037D02*
G02X1357659Y361417I-1246J643D01*
G03X1358354Y361443I340J210D01*
G02X1358407Y360063I1246J-643D01*
G03X1357712Y360037I-340J-210D01*
G37*
G36*
G01X1608786Y360618D02*
G02X1608339Y361947I-1374J277D01*
G03X1608996Y362167I265J300D01*
G02X1609443Y360838I1374J-277D01*
G03X1608786Y360618I-265J-300D01*
G37*
G36*
G01X60254Y363533D02*
G02X59542Y362141I680J-1226D01*
G03X58951Y362443I-397J-48D01*
G02X59663Y363835I-680J1226D01*
G03X60254Y363533I397J48D01*
G37*
G36*
G01X679038Y364209D02*
G02X677514Y363539I-308J-1368D01*
G03X677255Y364128I-347J199D01*
G02X678779Y364798I308J1368D01*
G03X679038Y364209I347J-199D01*
G37*
G36*
G01X174671Y362220D02*
G02X172670Y364668I-1200J1061D01*
G03X172655Y365369I-200J346D01*
G02X172339Y367987I745J1418D01*
G03Y368587I-265J300D01*
G02X174600Y370848I1061J1200D01*
G03X175200I300J265D01*
G02X177600I1200J-1061D01*
G03X178200I300J265D01*
G02X180600I1200J-1061D01*
G03X181200I300J265D01*
G02X183600I1200J-1061D01*
G03X184200I300J265D01*
G02X186600I1200J-1061D01*
G03X187200I300J265D01*
G02X189461Y368587I1200J-1061D01*
G03Y367987I265J-300D01*
G02X189201Y365400I-1061J-1200D01*
G03X189216Y364699I200J-346D01*
G02X187271Y362220I-745J-1418D01*
G03X186671I-300J-265D01*
G02X184271I-1200J1061D01*
G03X183671I-300J-265D01*
G02X181271I-1200J1061D01*
G03X180671I-300J-265D01*
G02X178271I-1200J1061D01*
G03X177671I-300J-265D01*
G02X175271I-1200J1061D01*
G03X174671I-300J-265D01*
G37*
G36*
G01X1381129Y371450D02*
G02X1379271I-929J-1050D01*
G03Y372050I-265J300D01*
G02X1378921Y372526I929J1050D01*
G03X1378233Y372599I-365J-164D01*
G02X1377889Y372267I-1131J828D01*
G03X1377862Y371625I224J-331D01*
G02X1375667Y370041I-883J-1089D01*
G03X1375083Y370239I-374J-142D01*
G02X1373399Y372466I-739J1192D01*
G03X1373369Y373082I-270J296D01*
G02X1375689Y374773I899J1203D01*
G03X1376297Y374575I378J129D01*
G02X1378382Y374002I806J-1147D01*
G03X1379070Y373929I365J164D01*
G02X1381129Y372050I1131J-829D01*
G03Y371450I265J-300D01*
G37*
G36*
G01X128750Y371148D02*
G02X128552Y372417I-1330J442D01*
G03X129255Y372527I323J236D01*
G02X129453Y371258I1330J-442D01*
G03X128750Y371148I-323J-236D01*
G37*
G36*
G01X764923Y374919D02*
G02X763374Y374904I-763J-1176D01*
G03X763367Y375571I-224J331D01*
G02X764916Y375586I763J1176D01*
G03X764923Y374919I224J-331D01*
G37*
G36*
G01X744900Y373222D02*
G02Y374778I-1400J778D01*
G03X745600I350J194D01*
G02X748400I1400J-778D01*
G03X749100I350J194D01*
G02X751900I1400J-778D01*
G03X752600I350J194D01*
G02Y373222I1400J-778D01*
G03X751900I-350J-194D01*
G02X749100I-1400J778D01*
G03X748400I-350J-194D01*
G02X745600I-1400J778D01*
G03X744900I-350J-194D01*
G37*
G36*
G01X1333536Y375536D02*
G02X1331725Y375503I-886J-1086D01*
G03X1331714Y376114I-264J301D01*
G02X1331623Y376195I886J1087D01*
G03X1331090Y376217I-279J-287D01*
G02X1329151Y376370I-890J1083D01*
G03X1328574Y376392I-299J-266D01*
G02X1326551Y376470I-974J1008D01*
G03X1325974Y376492I-299J-266D01*
G02X1323787Y376797I-974J1008D01*
G03X1323143Y376864I-346J-200D01*
G02X1320807Y377258I-1043J936D01*
G03X1320186Y377413I-369J-155D01*
G02X1320673Y378784I-886J1087D01*
G03X1321022Y378697I196J41D01*
G02X1321181Y378859I1077J-898D01*
G03X1321171Y379471I-262J302D01*
G02X1323113Y381479I883J1089D01*
G03X1323738Y381506I302J263D01*
G02X1324095Y381849I1135J-824D01*
G03Y382515I-222J333D01*
G02X1326062Y384424I777J1167D01*
G03X1326711Y384384I339J212D01*
G02X1328875Y384400I1089J-884D01*
G03X1329531Y384464I306J257D01*
G02X1329981Y384952I1226J-679D01*
G03Y385618I-222J333D01*
G02Y387952I777J1167D01*
G03Y388618I-222J333D01*
G02X1331535I777J1167D01*
G03Y387952I222J-333D01*
G02Y385618I-777J-1167D01*
G03Y384952I222J-333D01*
G02X1329683Y382885I-777J-1167D01*
G03X1329027Y382821I-306J-257D01*
G02X1328475Y382271I-1227J679D01*
G03X1328453Y381583I192J-351D01*
G02X1328666Y381416I-755J-1182D01*
G03X1329219Y381417I276J290D01*
G02X1331148Y381430I971J-1011D01*
G03X1331715Y381451I273J292D01*
G02X1331790Y379479I1033J-948D01*
G03X1331223Y379458I-273J-292D01*
G02X1330905Y379200I-1033J948D01*
G03X1330907Y378511I204J-344D01*
G02X1331177Y378305I-709J-1209D01*
G03X1331710Y378283I279J287D01*
G02X1333525Y376147I890J-1083D01*
G03X1333536Y375536I264J-301D01*
G37*
G36*
G01X1446261Y374114D02*
G02X1446234Y375724I-1161J786D01*
G03X1446889Y375736I323J236D01*
G02X1446916Y374126I1161J-786D01*
G03X1446261Y374114I-323J-236D01*
G37*
G36*
G01X1631819Y376659D02*
G02X1629911Y376593I-919J-1059D01*
G03X1629862Y377201I-283J283D01*
G02X1629557Y379511I938J1299D01*
G03X1629414Y380126I-310J252D01*
G02X1631156Y380607I586J1274D01*
G03X1631349Y380005I330J-226D01*
G02X1631825Y377269I-549J-1505D01*
G03X1631819Y376659I256J-308D01*
G37*
G36*
G01X752559Y380778D02*
G02X752489Y379058I1315J-915D01*
G03X751815Y379085I-346J-201D01*
G02X749100Y379222I-1315J915D01*
G03X748400I-350J-194D01*
G02X745600I-1400J778D01*
G03X744900I-350J-194D01*
G02Y380778I-1400J778D01*
G03X745600I350J194D01*
G02X748400I1400J-778D01*
G03X749100I350J194D01*
G02X751885Y380805I1400J-778D01*
G03X752559Y380778I346J201D01*
G37*
G36*
G01X766290Y380798D02*
G02X764936Y381765I-1333J-435D01*
G03X765310Y382289I-6J400D01*
G02X766009Y383974I1333J435D01*
G03X766122Y384602I-181J357D01*
G02X767789Y384300I1033J948D01*
G03X767676Y383672I181J-357D01*
G02X766664Y381322I-1033J-948D01*
G03X766290Y380798I6J-400D01*
G37*
G36*
G01X117981Y382436D02*
G02X117232Y381078I648J-1243D01*
G03X116648Y381400I-399J-33D01*
G02X115528Y383963I-649J1243D01*
G03X115764Y384490I-135J377D01*
G02X117535Y383696I1299J526D01*
G03X117299Y383169I135J-377D01*
G02X117397Y382758I-1299J-527D01*
G03X117981Y382436I399J33D01*
G37*
G36*
G01X1457707Y385768D02*
G02X1456192Y385728I-726J-1199D01*
G03X1456174Y386401I-225J331D01*
G02X1457689Y386441I726J1199D01*
G03X1457707Y385768I225J-331D01*
G37*
G36*
G01X744900Y385222D02*
G02Y386778I-1400J778D01*
G03X745600I350J194D01*
G02X748400I1400J-778D01*
G03X749100I350J194D01*
G02X751900I1400J-778D01*
G03X752600I350J194D01*
G02Y385222I1400J-778D01*
G03X751900I-350J-194D01*
G02X749100I-1400J778D01*
G03X748400I-350J-194D01*
G02X745600I-1400J778D01*
G03X744900I-350J-194D01*
G37*
G36*
G01X680301Y386975D02*
G02X678638Y386895I-777J-1167D01*
G03X678607Y387538I-253J310D01*
G02X680270Y387618I777J1167D01*
G03X680301Y386975I253J-310D01*
G37*
G36*
G01X1381928Y391468D02*
G02Y393132I-1128J832D01*
G03X1382572I322J238D01*
G02Y391468I1128J-832D01*
G03X1381928I-322J-238D01*
G37*
G36*
G01X1470953Y393463D02*
G02X1469582Y393653I-853J-1113D01*
G03X1469737Y394285I-148J371D01*
G02X1469538Y395811I1063J915D01*
G03X1469332Y396354I-360J174D01*
G02X1468706Y396871I542J1293D01*
G03X1468040I-333J-222D01*
G02X1465862Y396677I-1167J777D01*
G03X1465284I-289J-277D01*
G02Y398619I-1011J971D01*
G03X1465862I289J277D01*
G02X1468040Y398425I1011J-971D01*
G03X1468706I333J222D01*
G02X1471135Y397037I1167J-777D01*
G03X1471341Y396494I360J-174D01*
G02X1472183Y395433I-541J-1294D01*
G03X1472689Y395116I394J67D01*
G02X1471700Y393537I394J-1346D01*
G03X1471194Y393854I-394J-67D01*
G02X1471040Y393819I-387J1348D01*
G03X1470953Y393463I34J-197D01*
G37*
G36*
G01X126222Y395666D02*
G02X124199Y393687I-659J-1350D01*
G03X123515Y393758I-363J-168D01*
G02X121035Y395781I-1284J958D01*
G03X120989Y396358I-299J267D01*
G02X123293Y398546I1011J1243D01*
G03X123952Y398566I323J236D01*
G02X126178Y396360I1348J-866D01*
G03X126222Y395666I219J-335D01*
G37*
G36*
G01X1631023Y396730D02*
G02X1629663Y396770I-723J-1430D01*
G03X1629703Y397484I-159J367D01*
G02X1629491Y399767I697J1216D01*
G03X1629524Y400344I-260J304D01*
G02X1631459Y400233I1026J956D01*
G03X1631426Y399656I260J-304D01*
G02X1631025Y397445I-1026J-956D01*
G03X1631023Y396730I178J-358D01*
G37*
G36*
G01X1244795Y398467D02*
G02X1244034Y399589I-1396J-128D01*
G03X1244614Y399982I182J356D01*
G02X1245375Y398860I1396J128D01*
G03X1244795Y398467I-182J-356D01*
G37*
G36*
G01X1332810Y400430D02*
G02X1330695Y398590I-1039J-941D01*
G03X1330094Y398605I-307J-256D01*
G02X1327897Y398779I-1030J951D01*
G03X1327231I-333J-222D01*
G02X1324897I-1167J777D01*
G03X1324231I-333J-222D01*
G02X1322028Y398611I-1167J777D01*
G03X1321442Y398616I-295J-270D01*
G02X1319229Y398844I-1019J963D01*
G03X1318644Y398952I-341J-209D01*
G02X1316778Y401035I-857J1110D01*
G03Y401589I-288J277D01*
G02X1319048Y403176I1010J973D01*
G03X1319361Y403113I180J87D01*
G02X1319442Y403180I933J-1046D01*
G03X1319456Y403487I-121J159D01*
G02X1321567Y405301I944J1037D01*
G03X1322233I333J222D01*
G02X1324567I1167J-777D01*
G03X1325233I333J222D01*
G02X1327567I1167J-777D01*
G03X1328233I333J222D01*
G02X1330380Y405527I1167J-777D01*
G03X1330951Y405539I280J286D01*
G02X1332902Y403530I1022J-959D01*
G03X1332876Y402956I265J-300D01*
G02X1332829Y400986I-1020J-961D01*
G03X1332810Y400430I278J-288D01*
G37*
G36*
G01X1466215Y401593D02*
G02Y403147I-1167J777D01*
G03X1466881I333J222D01*
G02Y401593I1167J-777D01*
G03X1466215I-333J-222D01*
G37*
G36*
G01X175831Y403321D02*
G02X175784Y404774I-1222J688D01*
G03X176467Y404797I335J219D01*
G02X178913Y404794I1222J-688D01*
G03X179603Y404780I349J195D01*
G02X179575Y403364I1196J-732D01*
G03X178885Y403378I-349J-195D01*
G02X176514Y403344I-1196J731D01*
G03X175831Y403321I-335J-219D01*
G37*
G36*
G01X1198437Y406752D02*
G02X1196898Y406240I-408J-1341D01*
G03X1196692Y406859I-323J236D01*
G02X1198231Y407371I408J1341D01*
G03X1198437Y406752I323J-236D01*
G37*
G36*
G01X1467549Y405996D02*
G02Y407550I-1167J777D01*
G03X1468215I333J222D01*
G02Y405996I1167J-777D01*
G03X1467549I-333J-222D01*
G37*
G36*
G01X1513552Y408921D02*
G02X1511886Y408561I-598J-1268D01*
G03X1511752Y409182I-305J259D01*
G02X1511125Y409769I599J1268D01*
G03X1510425I-350J-194D01*
G02Y411131I-1225J681D01*
G03X1511125I350J194D01*
G02X1513418Y409542I1226J-680D01*
G03X1513552Y408921I305J-259D01*
G37*
G36*
G01X1613554Y410172D02*
G02X1611843Y409975I-729J-1198D01*
G03X1611771Y410602I-280J286D01*
G02X1613482Y410799I729J1198D01*
G03X1613554Y410172I280J-286D01*
G37*
G36*
G01X1440497Y410646D02*
G02X1439003Y410566I-684J-1224D01*
G03X1438967Y411242I-231J327D01*
G02X1440461Y411322I684J1224D01*
G03X1440497Y410646I231J-327D01*
G37*
G36*
G01X798376Y410593D02*
G02X797035Y411222I-1176J-763D01*
G03X797324Y411837I-47J397D01*
G02X798834Y413962I1176J763D01*
G03X799302Y414494I95J388D01*
G02X800276Y413638I1308J506D01*
G03X799808Y413106I-95J-388D01*
G02X798665Y411208I-1308J-506D01*
G03X798376Y410593I47J-397D01*
G37*
G36*
G01X1395067Y411723D02*
G02X1392890Y413473I-1167J778D01*
G03Y414027I-288J277D01*
G02X1393952Y416401I1010J973D01*
G03X1394357Y416888I14J400D01*
G02X1397076Y416819I1368J305D01*
G03X1397337Y416332I386J-107D01*
G02X1397910Y414027I-437J-1332D01*
G03Y413473I288J-277D01*
G02X1395733Y411723I-1010J-972D01*
G03X1395067I-333J-222D01*
G37*
G36*
G01X1535647Y412859D02*
G02X1535604Y414219I-1247J641D01*
G03X1536303Y414241I343J205D01*
G02X1536869Y414825I1246J-642D01*
G03Y415525I-194J350D01*
G02X1536325Y416069I681J1225D01*
G03X1535625I-350J-194D01*
G02Y417431I-1225J681D01*
G03X1536325I350J194D01*
G02X1538775I1225J-681D01*
G03X1539475I350J194D01*
G02X1541925I1225J-681D01*
G03X1542625I350J194D01*
G02X1545075I1225J-681D01*
G03X1545775I350J194D01*
G02Y416069I1225J-681D01*
G03X1545075I-350J-194D01*
G02X1544531Y415525I-1225J681D01*
G03Y414825I194J-350D01*
G02X1542625Y412919I-681J-1225D01*
G03X1541925I-350J-194D01*
G02X1539475I-1225J681D01*
G03X1538775I-350J-194D01*
G02X1536346Y412881I-1225J681D01*
G03X1535647Y412859I-343J-205D01*
G37*
G36*
G01X1516725Y412919D02*
G02Y414281I-1225J681D01*
G03X1517425I350J194D01*
G02X1517969Y414825I1225J-681D01*
G03Y415525I-194J350D01*
G02X1519331I681J1225D01*
G03Y414825I194J-350D01*
G02X1517425Y412919I-681J-1225D01*
G03X1516725I-350J-194D01*
G37*
G36*
G01X1526197Y412959D02*
G02X1524289Y414836I-1247J641D01*
G03X1524300Y415535I-189J353D01*
G02X1525661Y415514I699J1215D01*
G03X1525650Y414815I189J-353D01*
G02X1526154Y414319I-700J-1215D01*
G03X1526853Y414341I343J205D01*
G02X1526896Y412981I1247J-641D01*
G03X1526197Y412959I-343J-205D01*
G37*
G36*
G01X149308Y415575D02*
G02X147577Y415801I-1008J-975D01*
G03X147658Y416422I-206J343D01*
G02X149389Y416196I1008J975D01*
G03X149308Y415575I206J-343D01*
G37*
G36*
G01X621202Y416175D02*
G02X620188Y417547I-1402J25D01*
G03X620698Y417925I110J385D01*
G02X620711Y418092I1402J-25D01*
G03X620412Y418292I-198J28D01*
G02X618977Y420701I-712J1208D01*
G03X618973Y421389I-206J343D01*
G02X621066Y422810I707J1211D01*
G03X621537Y422477I396J60D01*
G02X622612Y422243I263J-1377D01*
G03X622924Y422368I116J163D01*
G02X622969Y422540I1376J-268D01*
G03X622794Y422802I-190J63D01*
G02X623345Y425530I107J1398D01*
G03X623855Y425796I127J379D01*
G02X626596Y425274I1345J-396D01*
G03X626996Y424838I398J-36D01*
G02X627621Y424693I4J-1402D01*
G03X628199Y425062I178J358D01*
G02X628979Y423843I1401J38D01*
G03X628401Y423474I-178J-358D01*
G02X627920Y422378I-1401J-39D01*
G03X627862Y421837I262J-302D01*
G02X626470Y419624I-1125J-837D01*
G03X625996Y419268I-76J-393D01*
G02X624051Y418110I-1396J132D01*
G03X623497Y417777I-156J-368D01*
G02X621712Y416553I-1397J123D01*
G03X621202Y416175I-110J-385D01*
G37*
G36*
G01X52868Y415596D02*
G02X52769Y417119I-1223J685D01*
G03X53439Y417163I321J239D01*
G02X53538Y415640I1223J-685D01*
G03X52868Y415596I-321J-239D01*
G37*
G36*
G01X1510425Y416069D02*
G02X1508519Y417975I-1225J681D01*
G03Y418675I-194J350D01*
G02Y421125I681J1225D01*
G03Y421825I-194J350D01*
G02Y424275I681J1225D01*
G03Y424975I-194J350D01*
G02Y427425I681J1225D01*
G03Y428125I-194J350D01*
G02X1508000Y428625I680J1226D01*
G03X1507303Y428602I-342J-207D01*
G02X1507259Y429974I-1244J647D01*
G03X1507956Y429997I342J207D01*
G02X1510425Y430031I1244J-647D01*
G03X1511125I350J194D01*
G02X1513575I1225J-681D01*
G03X1514275I350J194D01*
G02X1516725I1225J-681D01*
G03X1517425I350J194D01*
G02X1519331Y428125I1225J-681D01*
G03Y427425I194J-350D01*
G02Y424975I-681J-1225D01*
G03Y424275I194J-350D01*
G02X1517425Y422369I-681J-1225D01*
G03X1516725I-350J-194D01*
G02X1516181Y421825I-1225J681D01*
G03Y421125I194J-350D01*
G02X1514275Y419219I-681J-1225D01*
G03X1513575I-350J-194D01*
G02X1513031Y418675I-1225J681D01*
G03Y417975I194J-350D01*
G02X1511125Y416069I-681J-1225D01*
G03X1510425I-350J-194D01*
G37*
G36*
G01X1317793Y417890D02*
G02X1315810Y419873I-973J1010D01*
G03Y420427I-288J277D01*
G02X1317830I1010J973D01*
G03Y419873I288J-277D01*
G02X1317914Y419777I-1012J-970D01*
G03X1318226I156J125D01*
G02X1320417Y419773I1094J-877D01*
G03X1321060Y419796I313J249D01*
G02X1321233Y420003I1157J-791D01*
G03X1321267Y420535I-281J285D01*
G02X1323322Y422429I1104J864D01*
G03X1323881Y422445I271J294D01*
G02X1325879Y422462I1007J-975D01*
G03X1326434Y422453I282J284D01*
G02X1328372Y422426I955J-1027D01*
G03X1328927Y422420I281J285D01*
G02X1330862Y422410I962J-1020D01*
G03X1331416I277J288D01*
G02X1333362I973J-1010D01*
G03X1333916I277J288D01*
G02X1335965Y420501I973J-1010D01*
G03X1335982Y419968I306J-257D01*
G02X1333904Y418087I-1014J-968D01*
G03X1333297Y418088I-304J-260D01*
G02X1331263Y417994I-1062J916D01*
G03X1330709I-277J-288D01*
G02X1328753Y418004I-973J1010D01*
G03X1328198Y418010I-281J-285D01*
G02X1326246Y418038I-962J1020D01*
G03X1325691Y418047I-282J-284D01*
G02X1323784Y418045I-955J1027D01*
G03X1323225Y418029I-271J-294D01*
G02X1321120Y418131I-1008J975D01*
G03X1320477Y418108I-313J-249D01*
G02X1318347Y417890I-1157J792D01*
G03X1317793I-277J-288D01*
G37*
G36*
G01X123483Y419851D02*
G02X121934Y420567I-1241J-652D01*
G03X122200Y421143I-88J390D01*
G02X123749Y420427I1241J652D01*
G03X123483Y419851I88J-390D01*
G37*
G36*
G01X1468429Y419934D02*
G02Y421488I-1167J777D01*
G03X1469095I333J222D01*
G02Y419934I1167J-777D01*
G03X1468429I-333J-222D01*
G37*
G36*
G01X1525631Y424275D02*
G02X1524269I-681J-1225D01*
G03Y424975I-194J350D01*
G02Y427425I681J1225D01*
G03Y428125I-194J350D01*
G02X1525631I681J1225D01*
G03Y427425I194J-350D01*
G02Y424975I-681J-1225D01*
G03Y424275I194J-350D01*
G37*
G36*
G01X1532475Y422369D02*
G02X1530569Y424275I-1225J681D01*
G03Y424975I-194J350D01*
G02Y427425I681J1225D01*
G03Y428125I-194J350D01*
G02X1532475Y430031I681J1225D01*
G03X1533175I350J194D01*
G02X1535625I1225J-681D01*
G03X1536325I350J194D01*
G02X1538775I1225J-681D01*
G03X1539475I350J194D01*
G02X1541381Y428125I1225J-681D01*
G03Y427425I194J-350D01*
G02Y424975I-681J-1225D01*
G03Y424275I194J-350D01*
G02X1539475Y422369I-681J-1225D01*
G03X1538775I-350J-194D01*
G02X1536325I-1225J681D01*
G03X1535625I-350J-194D01*
G02X1533175I-1225J681D01*
G03X1532475I-350J-194D01*
G37*
G36*
G01X1668413Y425845D02*
G02X1667107Y425878I-684J-1224D01*
G03X1667125Y426585I-177J358D01*
G02X1666997Y428952I684J1224D01*
G03X1666962Y429627I-231J326D01*
G02X1668461Y429706I687J1222D01*
G03X1668496Y429031I231J-326D01*
G02X1668431Y426552I-687J-1222D01*
G03X1668413Y425845I177J-358D01*
G37*
G36*
G01X1612829Y430595D02*
G02X1611286Y430758I-894J-1080D01*
G03X1611356Y431420I-185J354D01*
G02X1611473Y433667I894J1080D01*
G03Y434333I-222J333D01*
G02X1613027I777J1167D01*
G03Y433667I222J-333D01*
G02X1612899Y431257I-777J-1167D01*
G03X1612829Y430595I185J-354D01*
G37*
G36*
G01X746945Y431271D02*
G02X745331Y431282I-815J-1141D01*
G03X745336Y431936I-228J329D01*
G02X746950Y431925I815J1141D01*
G03X746945Y431271I228J-329D01*
G37*
G36*
G01X1603820Y433694D02*
G02X1602241Y433668I-770J-1171D01*
G03X1602230Y434329I-231J327D01*
G02X1603809Y434355I770J1171D01*
G03X1603820Y433694I231J-327D01*
G37*
G36*
G01X1510425Y434969D02*
G02X1508519Y436875I-1225J681D01*
G03Y437575I-194J350D01*
G02Y440025I681J1225D01*
G03Y440725I-194J350D01*
G02X1510425Y442631I681J1225D01*
G03X1511125I350J194D01*
G02X1513575I1225J-681D01*
G03X1514275I350J194D01*
G02X1516181Y440725I1225J-681D01*
G03Y440025I194J-350D01*
G02X1516725Y439481I-681J-1225D01*
G03X1517425I350J194D01*
G02X1519331Y437575I1225J-681D01*
G03Y436875I194J-350D01*
G02X1517425Y434969I-681J-1225D01*
G03X1516725I-350J-194D01*
G02X1514275I-1225J681D01*
G03X1513575I-350J-194D01*
G02X1511125I-1225J681D01*
G03X1510425I-350J-194D01*
G37*
G36*
G01X1525631Y436875D02*
G02X1524269I-681J-1225D01*
G03Y437575I-194J350D01*
G02X1525631I681J1225D01*
G03Y436875I194J-350D01*
G37*
G36*
G01X1532475Y434969D02*
G02X1530569Y436875I-1225J681D01*
G03Y437575I-194J350D01*
G02X1532475Y439481I681J1225D01*
G03X1533175I350J194D01*
G02X1535625I1225J-681D01*
G03X1536325I350J194D01*
G02X1538775I1225J-681D01*
G03X1539475I350J194D01*
G02X1541381Y437575I1225J-681D01*
G03Y436875I194J-350D01*
G02X1540019I-681J-1225D01*
G03Y437575I-194J350D01*
G02X1539475Y438119I681J1225D01*
G03X1538775I-350J-194D01*
G02X1536325I-1225J681D01*
G03X1535625I-350J-194D01*
G02X1535081Y437575I-1225J681D01*
G03Y436875I194J-350D01*
G02X1533175Y434969I-681J-1225D01*
G03X1532475I-350J-194D01*
G37*
G36*
G01X1665691Y439085D02*
G02X1663833I-929J-1050D01*
G03Y439685I-265J300D01*
G02X1663985Y441902I929J1050D01*
G03Y442568I-222J333D01*
G02X1665539I777J1167D01*
G03Y441902I222J-333D01*
G02X1665812Y441664I-777J-1167D01*
G03X1666412I300J265D01*
G02X1668435Y441745I1050J-929D01*
G03X1668989I277J288D01*
G02X1670527Y439452I973J-1010D01*
G03X1670330Y438907I161J-366D01*
G02X1667769Y438789I-1254J-626D01*
G03X1667411Y439334I-373J145D01*
G02X1666412Y439806I51J1401D01*
G03X1665812I-300J-265D01*
G02X1665691Y439685I-1050J929D01*
G03Y439085I265J-300D01*
G37*
G36*
G01X1544591Y440047D02*
G02X1543231Y440004I-641J-1247D01*
G03X1543209Y440703I-205J343D01*
G02X1543169Y443175I641J1247D01*
G03Y443875I-194J350D01*
G02X1542625Y444419I681J1225D01*
G03X1541925I-350J-194D01*
G02X1539475I-1225J681D01*
G03X1538775I-350J-194D01*
G02X1536325I-1225J681D01*
G03X1535625I-350J-194D01*
G02X1533175I-1225J681D01*
G03X1532475I-350J-194D01*
G02X1530569Y446325I-1225J681D01*
G03Y447025I-194J350D01*
G02X1532475Y448931I681J1225D01*
G03X1533175I350J194D01*
G02X1535625I1225J-681D01*
G03X1536325I350J194D01*
G02X1538775I1225J-681D01*
G03X1539475I350J194D01*
G02X1541381Y447025I1225J-681D01*
G03Y446325I194J-350D01*
G02X1541925Y445781I-681J-1225D01*
G03X1542625I350J194D01*
G02X1544531Y443875I1225J-681D01*
G03Y443175I194J-350D01*
G02X1544569Y440746I-681J-1225D01*
G03X1544591Y440047I205J-343D01*
G37*
G36*
G01X1286805Y441007D02*
G02X1285559Y441448I-1036J-945D01*
G03X1285795Y442113I-60J395D01*
G02X1286911Y444458I1036J945D01*
G03X1287320Y444964I24J399D01*
G02X1288591Y443938I1351J374D01*
G03X1288182Y443432I-24J-399D01*
G02X1287041Y441672I-1351J-374D01*
G03X1286805Y441007I60J-395D01*
G37*
G36*
G01X1725270Y442675D02*
G02X1723640Y442799I-901J-1074D01*
G03X1723689Y443447I-208J342D01*
G02X1723579Y443550I902J1073D01*
G03X1723001I-289J-277D01*
G02Y445492I-1011J971D01*
G03X1723579I289J277D01*
G02X1725804Y445222I1011J-971D01*
G03X1726476Y445191I346J201D01*
G02X1726406Y443679I1144J-811D01*
G03X1725734Y443710I-346J-201D01*
G02X1725319Y443323I-1144J811D01*
G03X1725270Y442675I208J-342D01*
G37*
G36*
G01X1602290Y445654D02*
G02X1601199Y444330I310J-1367D01*
G03X1600710Y444733I-400J13D01*
G02X1601801Y446057I-310J1367D01*
G03X1602290Y445654I400J-13D01*
G37*
G36*
G01X1523025Y444419D02*
G02Y445781I-1225J681D01*
G03X1523725I350J194D01*
G02X1524269Y446325I1225J-681D01*
G03Y447025I-194J350D01*
G02X1525631I681J1225D01*
G03Y446325I194J-350D01*
G02X1523725Y444419I-681J-1225D01*
G03X1523025I-350J-194D01*
G37*
G36*
G01X1504495Y446629D02*
G02X1503769Y448171I-1370J297D01*
G03X1504344Y448442I184J355D01*
G02X1505070Y446900I1370J-297D01*
G03X1504495Y446629I-184J-355D01*
G37*
G36*
G01X1918547Y447249D02*
G02X1916039Y447364I-1225J681D01*
G03X1915340Y447424I-366J-162D01*
G02X1915456Y448766I-1167J777D01*
G03X1916155Y448706I366J162D01*
G02X1918547Y448611I1167J-776D01*
G03X1919247I350J194D01*
G02Y447249I1225J-681D01*
G03X1918547I-350J-194D01*
G37*
G36*
G01X1516725Y447569D02*
G02X1514777Y449451I-1225J681D01*
G03X1514753Y450151I-205J343D01*
G02X1516112Y450199I636J1249D01*
G03X1516136Y449499I205J-343D01*
G02X1516725Y448931I-636J-1249D01*
G03X1517425I350J194D01*
G02X1517996Y449490I1225J-681D01*
G03X1518002Y450195I-186J354D01*
G02X1519896Y452114I673J1230D01*
G03X1520590Y452108I349J196D01*
G02X1520579Y450711I1210J-708D01*
G03X1519885Y450717I-349J-196D01*
G02X1519329Y450185I-1210J708D01*
G03X1519323Y449480I186J-354D01*
G02X1517425Y447569I-673J-1230D01*
G03X1516725I-350J-194D01*
G37*
G36*
G01X1933562Y449612D02*
G02X1933835Y451960I-3243J1567D01*
G03X1934464Y451726I390J87D01*
G02X1934228Y449696I836J-1126D01*
G03X1933562Y449612I-306J-258D01*
G37*
G36*
G01X1887351Y453165D02*
G02X1884768Y453561I-1151J1115D01*
G03X1884063Y453579I-357J-180D01*
G02X1884101Y455087I-1394J790D01*
G03X1884806Y455069I357J180D01*
G02X1887264Y455477I1394J-789D01*
G03X1887817Y455498I266J299D01*
G02X1890228Y455372I1151J-1115D01*
G03X1890858I315J247D01*
G02Y453394I1260J-989D01*
G03X1890228I-315J-247D01*
G02X1887904Y453186I-1260J989D01*
G03X1887351Y453165I-266J-299D01*
G37*
G36*
G01X1842797Y453544D02*
G02Y455098I-1167J777D01*
G03X1843463I333J222D01*
G02Y453544I1167J-777D01*
G03X1842797I-333J-222D01*
G37*
G36*
G01X22038Y453348D02*
G02X19937Y455766I-1040J1218D01*
G03Y456366I-265J300D01*
G02X20141Y458919I1061J1200D01*
G03X20165Y459579I-214J338D01*
G02X22158Y462084I953J1287D01*
G03X22678I260J304D01*
G02X24758I1040J-1218D01*
G03X25278I260J304D01*
G02X27382Y462064I1041J-1218D01*
G03X27915Y462066I265J299D01*
G02X29845Y459523I1073J-1190D01*
G03X29821Y458863I214J-338D01*
G02X29929Y456376I-953J-1287D01*
G03Y455776I265J-300D01*
G02X27804Y453378I-1061J-1200D01*
G03X27271Y453376I-265J-299D01*
G02X25158Y453348I-1072J1190D01*
G03X24638I-260J-304D01*
G02X22558I-1040J1218D01*
G03X22038I-260J-304D01*
G37*
G36*
G01X620740Y465350D02*
G02X619173Y464668I-340J-1360D01*
G03X618920Y465250I-350J194D01*
G02X618450Y467754I340J1360D01*
G03X618479Y468385I-231J327D01*
G02X620200Y468306I911J1065D01*
G03X620171Y467675I231J-327D01*
G02X620487Y465932I-911J-1065D01*
G03X620740Y465350I350J-194D01*
G37*
G36*
G01X-5187Y465904D02*
G02X-6694Y466110I-913J-1064D01*
G03X-6603Y466776I-169J362D01*
G02X-5096Y466570I913J1064D01*
G03X-5187Y465904I169J-362D01*
G37*
G36*
G01X635166Y468771D02*
G02X633700Y469205I-1133J-1133D01*
G03X633917Y469861I-83J391D01*
G02X633628Y471206I1050J929D01*
G03X633151Y471713I-382J118D01*
G02X634270Y472704I-380J1556D01*
G03X634716Y472169I374J-141D01*
G02X635277Y472157I251J-1379D01*
G03X635761Y472605I88J390D01*
G02X636838Y471442I1387J204D01*
G03X636354Y470994I-88J-390D01*
G02X635342Y469439I-1387J-204D01*
G03X635166Y468771I107J-385D01*
G37*
G36*
G01X1617774Y469168D02*
G02Y470722I-1167J777D01*
G03X1618440I333J222D01*
G02Y469168I1167J-777D01*
G03X1617774I-333J-222D01*
G37*
G36*
G01X1911277Y473167D02*
G02X1909723I-777J-1167D01*
G03Y473833I-222J333D01*
G02X1911277I777J1167D01*
G03Y473167I222J-333D01*
G37*
G36*
G01X607004Y472635D02*
G02X604816Y474367I-1179J759D01*
G03Y474921I-288J277D01*
G02X606836I1010J973D01*
G03Y474367I288J-277D01*
G02X606961Y474216I-1015J-967D01*
G03X607622Y474234I324J235D01*
G02X607665Y472653I1178J-759D01*
G03X607004Y472635I-324J-235D01*
G37*
G36*
G01X66784Y476042D02*
G02X65693Y476991I-1334J-432D01*
G03X66143Y477508I70J394D01*
G02X67234Y476559I1334J432D01*
G03X66784Y476042I-70J-394D01*
G37*
G36*
G01X1841917Y474947D02*
G02Y476501I-1167J777D01*
G03X1842583I333J222D01*
G02Y474947I1167J-777D01*
G03X1841917I-333J-222D01*
G37*
G36*
G01X4127Y479339D02*
G02X3786Y477842I973J-1009D01*
G03X3133Y477991I-375J-139D01*
G02X931Y478326I-973J1009D01*
G03X229I-351J-192D01*
G02Y479674I-1229J674D01*
G03X931I351J192D01*
G02X1566Y480270I1229J-674D01*
G03X1661Y480932I-170J362D01*
G02X3795Y482698I928J1051D01*
G03X4483I344J204D01*
G02Y481268I1206J-715D01*
G03X3795I-344J-204D01*
G02X3183Y480713I-1206J715D01*
G03X3088Y480051I170J-362D01*
G02X3474Y479488I-928J-1050D01*
G03X4127Y479339I375J139D01*
G37*
G36*
G01X90883Y478991D02*
G02X90312Y480342I-1386J210D01*
G03X90940Y480608I232J325D01*
G02X93029Y481611I1386J-210D01*
G03X93622Y481881I200J346D01*
G02X94295Y480399I1376J-269D01*
G03X93702Y480129I-200J-346D01*
G02X91511Y479257I-1376J269D01*
G03X90883Y478991I-232J-325D01*
G37*
G36*
G01X1599811Y478370D02*
G02Y480080I-1111J855D01*
G03X1600446I317J243D01*
G02Y478370I1111J-855D01*
G03X1599811I-317J-243D01*
G37*
G36*
G01X1570800Y480997D02*
G02X1569699Y482101I-1375J-271D01*
G03X1570170Y482571I78J392D01*
G02X1571271Y481467I1375J271D01*
G03X1570800Y480997I-78J-392D01*
G37*
G36*
G01X626879Y481069D02*
G02X626695Y482403I-1310J499D01*
G03X627390Y482499I321J239D01*
G02X627574Y481165I1310J-499D01*
G03X626879Y481069I-321J-239D01*
G37*
G36*
G01X32607Y481958D02*
G02X32544Y483698I-1130J830D01*
G03X33170Y483720I304J259D01*
G02X33233Y481980I1130J-830D01*
G03X32607Y481958I-304J-259D01*
G37*
G36*
G01X1688120Y485257D02*
G02X1686836Y485235I-621J-1257D01*
G03X1686823Y485946I-190J352D01*
G02X1688416Y488213I620J1257D01*
G03X1688970I277J288D01*
G02X1690893Y488234I973J-1010D01*
G03X1691448Y488247I271J294D01*
G02X1691493Y486228I995J-988D01*
G03X1690938Y486215I-271J-294D01*
G02X1688970Y486193I-995J988D01*
G03X1688416I-277J-288D01*
G02X1688107Y485968I-972J1010D01*
G03X1688120Y485257I190J-352D01*
G37*
G36*
G01X1457304Y487077D02*
G02X1455890Y487072I-703J-1213D01*
G03X1455888Y487763I-203J345D01*
G02X1457302Y487768I703J1213D01*
G03X1457304Y487077I203J-345D01*
G37*
G36*
G01X657051Y487930D02*
G02X655110Y487893I-951J-1030D01*
G03X655099Y488470I-282J283D01*
G02X657402Y489870I951J1030D01*
G03X658073Y489694I386J105D01*
G02X657718Y488339I997J-985D01*
G03X657047Y488515I-386J-105D01*
G02X657040Y488507I-1056J917D01*
G03X657051Y487930I282J-283D01*
G37*
G36*
G01X1642122Y488168D02*
G02X1641073Y489131I-1341J-408D01*
G03X1641539Y489639I83J391D01*
G02X1642588Y488676I1341J408D01*
G03X1642122Y488168I-83J-391D01*
G37*
G36*
G01X729744Y488062D02*
G02X729310Y489399I-1371J294D01*
G03X729968Y489613I267J298D01*
G02X730402Y488276I1371J-294D01*
G03X729744Y488062I-267J-298D01*
G37*
G36*
G01X1641064Y497040D02*
G02X1640645Y495487I899J-1076D01*
G03X1640012Y495658I-376J-136D01*
G02X1640431Y497211I-899J1076D01*
G03X1641064Y497040I376J136D01*
G37*
G36*
G01X1590192Y495198D02*
G02Y496752I-1167J777D01*
G03X1590858I333J222D01*
G02Y495198I1167J-777D01*
G03X1590192I-333J-222D01*
G37*
G36*
G01X1268014Y497007D02*
G02X1267785Y495327I992J-991D01*
G03X1267154Y495413I-348J-197D01*
G02X1267383Y497093I-992J991D01*
G03X1268014Y497007I348J197D01*
G37*
G36*
G01X1279705Y497522D02*
G02X1279311Y495877I890J-1083D01*
G03X1278690Y496025I-366J-161D01*
G02X1279084Y497670I-890J1083D01*
G03X1279705Y497522I366J161D01*
G37*
G36*
G01X1728637Y501596D02*
X1733639D01*
G02X1735150Y500095I0J-1511D01*
G01Y500000D01*
X1735141Y499916D01*
G02X1733639Y498574I-1502J169D01*
G01X1729602D01*
G03X1729310Y497901I0J-400D01*
G02X1726932Y495754I-1171J-1094D01*
G03X1726418Y495829I-301J-263D01*
G02X1723965Y497144I-852J1357D01*
G03X1723570Y497533I-400J-11D01*
G02X1723600Y500737I21J1602D01*
G03X1724002Y501110I3J400D01*
G02X1727123Y501498I1598J-110D01*
G03X1727741Y501301I380J124D01*
G02X1728637Y501596I897J-1216D01*
G37*
G36*
G01X1789242Y495925D02*
G02X1786803Y496003I-1197J729D01*
G03X1786100Y496014I-354J-185D01*
G02X1786120Y497352I-1222J687D01*
G03X1786823Y497341I354J185D01*
G02X1789235Y497396I1222J-687D01*
G03X1789916Y497399I340J211D01*
G02X1789923Y495928I1197J-730D01*
G03X1789242Y495925I-340J-211D01*
G37*
G36*
G01X689432Y497063D02*
G02X689149Y498770I-1230J673D01*
G03X689770Y498873I270J295D01*
G02X690053Y497166I1230J-673D01*
G03X689432Y497063I-270J-295D01*
G37*
G36*
G01X1616058Y497784D02*
G02X1615976Y499474I-1158J791D01*
G03X1616613Y499505I307J256D01*
G02X1616695Y497815I1158J-791D01*
G03X1616058Y497784I-307J-256D01*
G37*
G36*
G01X55164Y501438D02*
G02X53088Y503514I-1264J812D01*
G03Y504186I-216J336D01*
G02X55164Y506262I812J1264D01*
G03X55836I336J216D01*
G02X58364I1264J-812D01*
G03X59036I336J216D01*
G02X61112Y504186I1264J-812D01*
G03Y503514I216J-336D01*
G02X59036Y501438I-812J-1264D01*
G03X58364I-336J-216D01*
G02X55836I-1264J812D01*
G03X55164I-336J-216D01*
G37*
G36*
G01X1565777Y504496D02*
G02X1564223I-777J-1167D01*
G03Y505162I-222J333D01*
G02X1565777I777J1167D01*
G03Y504496I222J-333D01*
G37*
G36*
G01X680274Y503064D02*
G02X680159Y504602I-1225J682D01*
G03X680825Y504652I317J245D01*
G02X680940Y503114I1225J-682D01*
G03X680274Y503064I-317J-245D01*
G37*
G36*
G01X1689443Y505238D02*
G02X1688723Y503689I648J-1243D01*
G03X1688148Y503957I-391J-87D01*
G02X1686391Y504342I-648J1243D01*
G03X1685759I-316J-245D01*
G02Y506058I-1109J858D01*
G03X1686391I316J245D01*
G02X1688868Y505506I1109J-858D01*
G03X1689443Y505238I391J87D01*
G37*
G36*
G01X1333988Y506103D02*
G02X1331680Y507358I-1388J197D01*
G03X1331658Y507979I-263J302D01*
G02X1333892Y509263I842J1121D01*
G03X1334470Y508952I398J46D01*
G02X1334543Y506413I630J-1252D01*
G03X1333988Y506103I-159J-367D01*
G37*
G36*
G01X1534568Y510040D02*
G02X1532953Y510276I-972J-1010D01*
G03X1533047Y510920I-183J356D01*
G02X1534662Y510684I972J1010D01*
G03X1534568Y510040I183J-356D01*
G37*
G36*
G01X1401610Y509379D02*
G02X1401229Y511321I-1165J780D01*
G03X1401785Y511430I224J332D01*
G02X1404117Y511427I1165J-780D01*
G03X1404783I333J222D01*
G02X1406073Y512047I1167J-777D01*
G03X1406502Y512513I35J398D01*
G02X1407761Y511354I1382J238D01*
G03X1407332Y510888I-35J-398D01*
G02X1404783Y509873I-1382J-238D01*
G03X1404117I-333J-222D01*
G02X1402166Y509488I-1167J777D01*
G03X1401610Y509379I-224J-332D01*
G37*
G36*
G01X1910967Y509923D02*
G02Y511477I-1167J777D01*
G03X1911633I333J222D01*
G02Y509923I1167J-777D01*
G03X1910967I-333J-222D01*
G37*
G36*
G01X1296853Y509800D02*
G02X1294958Y511866I-973J1010D01*
G03X1294975Y512452I-263J301D01*
G02X1295183Y514617I985J998D01*
G03Y515283I-222J333D01*
G02Y517617I777J1167D01*
G03Y518283I-222J333D01*
G02X1296933Y520460I778J1167D01*
G03X1297487I277J288D01*
G02X1299237Y518283I972J-1010D01*
G03Y517617I222J-333D01*
G02Y515283I-777J-1167D01*
G03Y514617I222J-333D01*
G02X1299382Y512394I-777J-1167D01*
G03X1299365Y511808I263J-301D01*
G02X1297407Y509800I-985J-998D01*
G03X1296853I-277J-288D01*
G37*
G36*
G01X713293Y511963D02*
G02X713170Y513605I-1193J736D01*
G03X713816Y513654I305J259D01*
G02X713939Y512012I1193J-736D01*
G03X713293Y511963I-305J-259D01*
G37*
G36*
G01X1828753Y514383D02*
G02X1826598Y513175I-753J-1183D01*
G03X1826088Y513553I-400J-7D01*
G02X1826184Y516216I-388J1347D01*
G03X1826716Y516527I137J375D01*
G02X1827212Y517385I1384J-227D01*
G03X1827234Y517984I-254J309D01*
G02X1829088Y517915I966J1016D01*
G03X1829066Y517316I254J-309D01*
G02X1828775Y515071I-966J-1016D01*
G03X1828753Y514383I192J-351D01*
G37*
G36*
G01X1797553Y514117D02*
G02X1796878Y515400I-1400J83D01*
G03X1797483Y515719I206J343D01*
G02X1799952Y516543I1400J-83D01*
G03X1800555Y516535I305J259D01*
G02X1800531Y514693I1045J-935D01*
G03X1799928Y514701I-305J-259D01*
G02X1798158Y514436I-1045J935D01*
G03X1797553Y514117I-206J-343D01*
G37*
G36*
G01X1340419Y516938D02*
G02X1339015Y517074I-819J-1138D01*
G03X1339081Y517762I-167J363D01*
G02X1340485Y517626I819J1138D01*
G03X1340419Y516938I167J-363D01*
G37*
G36*
G01X1861057Y521367D02*
G02X1859312Y521214I-777J-1167D01*
G03X1859126Y521894I-276J290D01*
G02X1861122Y522069I728J3169D01*
G03X1861057Y521367I156J-368D01*
G37*
G36*
G01X41429Y521343D02*
G02X40279Y522116I-1318J-720D01*
G03X40675Y522705I45J397D01*
G02X41825Y521932I1318J720D01*
G03X41429Y521343I-45J-397D01*
G37*
G36*
G01X1804213Y522569D02*
G02X1802541Y526180I-3227J698D01*
G03X1803122Y526459I188J353D01*
G02X1803575Y527253I1378J-260D01*
G03X1803409Y527942I-264J301D01*
G02X1804677Y528248I343J1359D01*
G03X1804843Y527559I264J-301D01*
G02X1805726Y525521I-343J-1359D01*
G03X1806076Y524927I350J-194D01*
G02X1804931Y522716I0J-1402D01*
G03X1804213Y522569I-327J-231D01*
G37*
G36*
G01X1415993Y520663D02*
G02X1415941Y522214I-1193J736D01*
G03X1416607Y522237I325J233D01*
G02X1416659Y520686I1193J-736D01*
G03X1415993Y520663I-325J-233D01*
G37*
G36*
G01X90674Y523007D02*
G02X90451Y521273I976J-1007D01*
G03X89831Y521352I-342J-208D01*
G02X90054Y523086I-976J1007D01*
G03X90674Y523007I342J208D01*
G37*
G36*
G01X47646Y524933D02*
G02X46049Y525384I-1139J-980D01*
G03X46230Y526025I-122J381D01*
G02X47827Y525574I1139J980D01*
G03X47646Y524933I122J-381D01*
G37*
G36*
G01X1437747Y525335D02*
G02X1436550Y526531I-1389J-193D01*
G03X1437001Y526982I55J396D01*
G02X1438198Y525786I1389J193D01*
G03X1437747Y525335I-55J-396D01*
G37*
G36*
G01X717110Y526173D02*
G02X715090I-1010J-973D01*
G03Y526727I-288J277D01*
G02X715006Y526823I1012J970D01*
G03X714694I-156J-125D01*
G02X713488Y526302I-1094J877D01*
G03X713067Y525810I-32J-399D01*
G02X711816Y526881I-1363J-327D01*
G03X712237Y527373I32J399D01*
G02X712590Y528673I1363J328D01*
G03Y529227I-288J277D01*
G02Y531173I1010J973D01*
G03Y531727I-288J277D01*
G02X714573Y533710I1010J973D01*
G03X715127I277J288D01*
G02X717110Y531727I973J-1010D01*
G03Y531173I288J-277D01*
G02Y529227I-1010J-973D01*
G03Y528673I288J-277D01*
G02Y526727I-1010J-973D01*
G03Y526173I288J-277D01*
G37*
G36*
G01X1296749Y526817D02*
G02X1294883Y528867I-1089J883D01*
G03Y529533I-222J333D01*
G02Y531867I777J1167D01*
G03Y532533I-222J333D01*
G02Y534867I777J1167D01*
G03Y535533I-222J333D01*
G02X1296749Y537583I777J1167D01*
G03X1297371I311J252D01*
G02X1299237Y535533I1089J-883D01*
G03Y534867I222J-333D01*
G02Y532533I-777J-1167D01*
G03Y531867I222J-333D01*
G02Y529533I-777J-1167D01*
G03Y528867I222J-333D01*
G02X1297371Y526817I-777J-1167D01*
G03X1296749I-311J-252D01*
G37*
G36*
G01X686650Y529153D02*
G02X685186Y528521I-275J-1375D01*
G03X684925Y529125I-339J212D01*
G02X683958Y531151I275J1375D01*
G03X683803Y531684I-354J186D01*
G02X685742Y532249I697J1216D01*
G03X685897Y531716I354J-186D01*
G02X686389Y529757I-697J-1216D01*
G03X686650Y529153I339J-212D01*
G37*
G36*
G01X652317Y529423D02*
G02X650121Y531152I-1167J777D01*
G03X650110Y531707I-293J272D01*
G02X652283Y533453I991J992D01*
G03X652971Y533475I337J214D01*
G02X655151Y531770I1229J-675D01*
G03X655140Y531193I271J-294D01*
G02X652983Y529423I-990J-993D01*
G03X652317I-333J-222D01*
G37*
G36*
G01X658223Y530290D02*
G02X656473Y532467I-972J1010D01*
G03Y533133I-222J333D01*
G02X658223Y535310I778J1167D01*
G03X658777I277J288D01*
G02X660527Y533133I972J-1010D01*
G03Y532467I222J-333D01*
G02X658777Y530290I-778J-1167D01*
G03X658223I-277J-288D01*
G37*
G36*
G01X1460414Y532386D02*
G02X1460352Y530695I1086J-886D01*
G03X1459715Y530718I-327J-230D01*
G02X1459777Y532409I-1086J886D01*
G03X1460414Y532386I327J230D01*
G37*
G36*
G01X726180Y532943D02*
G02X726154Y534496I-1180J757D01*
G03X726820Y534507I329J227D01*
G02X726846Y532954I1180J-757D01*
G03X726180Y532943I-329J-227D01*
G37*
G36*
G01X63667Y534723D02*
G02Y536277I-1167J777D01*
G03X64333I333J222D01*
G02X66667I1167J-777D01*
G03X67333I333J222D01*
G02Y534723I1167J-777D01*
G03X66667I-333J-222D01*
G02X64333I-1167J777D01*
G03X63667I-333J-222D01*
G37*
G36*
G01X1385303Y534550D02*
G02X1383533Y536707I-993J990D01*
G03Y537373I-222J333D01*
G02Y539707I777J1167D01*
G03Y540373I-222J333D01*
G02X1382961Y541923I777J1167D01*
G03X1382522Y542429I-384J110D01*
G02X1383680Y543435I-191J1389D01*
G03X1384119Y542929I384J-110D01*
G02X1385295Y542538I191J-1389D01*
G03X1385848Y542529I281J284D01*
G02X1386507Y542871I952J-1029D01*
G03X1386753Y543490I-83J391D01*
G02X1388200Y542915I1154J796D01*
G03X1387954Y542296I83J-391D01*
G02X1387577Y540333I-1154J-796D01*
G03Y539667I222J-333D01*
G02X1387632Y537372I-777J-1167D01*
G03Y536728I238J-322D01*
G02X1385856Y534564I-832J-1128D01*
G03X1385303Y534550I-269J-296D01*
G37*
G36*
G01X71506Y537405D02*
G02X69730Y539561I-984J999D01*
G03X69725Y540224I-226J330D01*
G02X71455Y542419I774J1169D01*
G03X72012Y542430I273J292D01*
G02X73953Y542481I997J-986D01*
G03X74497Y542486I269J296D01*
G02X76433Y542478I964J-1018D01*
G03X76988I277J288D01*
G02X78905Y542504I972J-1010D01*
G03X79444I270J295D01*
G02X81166Y540301I944J-1036D01*
G03Y539635I222J-333D01*
G02X79444Y537432I-778J-1167D01*
G03X78905I-270J-295D01*
G02X76988Y537458I-945J1036D01*
G03X76433I-277J-288D01*
G02X74517Y537431I-972J1010D01*
G03X73973Y537426I-269J-296D01*
G02X72058Y537414I-964J1018D01*
G03X71506Y537405I-271J-294D01*
G37*
G36*
G01X646927Y541517D02*
G02X645373I-777J-1167D01*
G03Y542183I-222J333D01*
G02Y544517I777J1167D01*
G03Y545183I-222J333D01*
G02X646927I777J1167D01*
G03Y544517I222J-333D01*
G02Y542183I-777J-1167D01*
G03Y541517I222J-333D01*
G37*
G36*
G01X1940620Y541958D02*
G02X1938484Y540203I-920J-1058D01*
G03X1937951Y540358I-347J-199D01*
G02X1938516Y542297I-651J1242D01*
G03X1939049Y542142I347J199D01*
G02X1939064Y542150I667J-1233D01*
G03X1939077Y542499I-91J178D01*
G02X1938408Y543537I723J1201D01*
G03X1937830Y543848I-398J-46D01*
G02X1937855Y546340I-630J1252D01*
G03X1938432Y546606I187J354D01*
G02X1940771Y545289I1368J-306D01*
G03Y544711I277J-289D01*
G02X1940642Y542579I-971J-1011D01*
G03X1940620Y541958I241J-319D01*
G37*
G36*
G01X1922965Y544767D02*
G02X1921424Y545028I-965J-1017D01*
G03X1921535Y545683I-164J365D01*
G02X1923076Y545422I965J1017D01*
G03X1922965Y544767I164J-365D01*
G37*
G36*
G01X1453864Y545629D02*
G02X1450791Y544939I-1472J-631D01*
G03X1450287Y545310I-400J-15D01*
G02X1448818Y545799I-365J1354D01*
G03X1448175Y545780I-314J-247D01*
G02X1448126Y547443I-1153J798D01*
G03X1448769Y547462I314J247D01*
G02X1450926Y547642I1153J-798D01*
G03X1451603Y547833I287J279D01*
G02X1454310Y548603I1563J-352D01*
G03X1454892Y548615I285J280D01*
G02X1454936Y546418I1188J-1075D01*
G03X1454354Y546406I-285J-280D01*
G02X1454019Y546125I-1187J1075D01*
G03X1453864Y545629I213J-339D01*
G37*
G36*
G01X1915609Y545971D02*
G02X1914125Y546118I-859J-1108D01*
G03X1914191Y546792I-179J358D01*
G02X1915675Y546645I859J1108D01*
G03X1915609Y545971I179J-358D01*
G37*
G36*
G01X1811291Y544448D02*
G02X1811069Y546068I-1239J655D01*
G03X1811713Y546156I290J275D01*
G02X1811935Y544536I1239J-655D01*
G03X1811291Y544448I-290J-275D01*
G37*
G36*
G01X1278982Y546573D02*
G02X1277957Y545548I336J-1361D01*
G03X1277473Y546032I-389J95D01*
G02X1278498Y547057I-336J1361D01*
G03X1278982Y546573I389J-95D01*
G37*
G36*
G01X1899954Y546114D02*
G02X1898485Y546604I-1104J-864D01*
G03X1898696Y547236I-104J386D01*
G02X1898565Y547436I1103J865D01*
G03X1898010Y547591I-352J-190D01*
G02X1898535Y549464I-710J1209D01*
G03X1899090Y549309I352J190D01*
G02X1900165Y546746I710J-1209D01*
G03X1899954Y546114I104J-386D01*
G37*
G36*
G01X1857125Y548275D02*
G02X1855432Y549365I-1375J-275D01*
G03X1855733Y549833I-91J389D01*
G02X1856137Y551119I1375J275D01*
G03Y551697I-277J289D01*
G02X1856097Y551737I971J1011D01*
G03X1855519I-289J-277D01*
G02X1853146Y553039I-1011J971D01*
G03X1852678Y553526I-389J95D01*
G02X1853762Y554569I-278J1374D01*
G03X1854230Y554082I389J-95D01*
G02X1855519Y553679I278J-1374D01*
G03X1856097I289J277D01*
G02X1858119I1011J-971D01*
G03X1858697I289J277D01*
G02Y551737I1011J-971D01*
G03X1858119I-289J-277D01*
G02X1858079Y551697I-1011J971D01*
G03Y551119I277J-289D01*
G02X1857426Y548743I-971J-1011D01*
G03X1857125Y548275I91J-389D01*
G37*
G36*
G01X1849505Y549465D02*
G02X1848218Y549425I-605J-1265D01*
G03X1848195Y550135I-195J349D01*
G02X1849482Y550175I605J1265D01*
G03X1849505Y549465I195J-349D01*
G37*
G36*
G01X1836978Y550660D02*
G02X1836688Y549207I1022J-959D01*
G03X1836022Y549340I-374J-141D01*
G02X1836312Y550793I-1022J959D01*
G03X1836978Y550660I374J141D01*
G37*
G36*
G01X730541Y549008D02*
G02X728773Y551167I-991J992D01*
G03Y551833I-222J333D01*
G02Y554167I777J1167D01*
G03Y554833I-222J333D01*
G02X730541Y556992I777J1167D01*
G03X731107I283J282D01*
G02X732875Y554833I991J-992D01*
G03Y554167I222J-333D01*
G02Y551833I-777J-1167D01*
G03Y551167I222J-333D01*
G02X731107Y549008I-777J-1167D01*
G03X730541I-283J-282D01*
G37*
G36*
G01X1816995Y551606D02*
G02X1815565I-715J-1206D01*
G03Y552294I-204J344D01*
G02X1816995I715J1206D01*
G03Y551606I204J-344D01*
G37*
G36*
G01X1300777Y553567D02*
G02X1299223I-777J-1167D01*
G03Y554233I-222J333D01*
G02Y556567I777J1167D01*
G03Y557233I-222J333D01*
G02X1300777I777J1167D01*
G03Y556567I222J-333D01*
G02Y554233I-777J-1167D01*
G03Y553567I222J-333D01*
G37*
G36*
G01X1318667Y551623D02*
G02X1316723Y553567I-1167J777D01*
G03Y554233I-222J333D01*
G02Y556567I777J1167D01*
G03Y557233I-222J333D01*
G02X1318667Y559177I777J1167D01*
G03X1319333I333J222D01*
G02X1321667I1167J-777D01*
G03X1322333I333J222D01*
G02X1324277Y557233I1167J-777D01*
G03Y556567I222J-333D01*
G02Y554233I-777J-1167D01*
G03Y553567I222J-333D01*
G02X1322333Y551623I-777J-1167D01*
G03X1321667I-333J-222D01*
G02X1319333I-1167J777D01*
G03X1318667I-333J-222D01*
G37*
G36*
G01X658306Y551785D02*
G02Y553215I-1206J715D01*
G03X658994I344J204D01*
G02Y551785I1206J-715D01*
G03X658306I-344J-204D01*
G37*
G36*
G01X1755319Y553024D02*
G02X1754626Y554754I-1319J476D01*
G03X1755181Y554976I179J358D01*
G02X1757667Y555277I1319J-476D01*
G03X1758333I333J222D01*
G02Y553723I1167J-777D01*
G03X1757667I-333J-222D01*
G02X1755874Y553246I-1167J777D01*
G03X1755319Y553024I-179J-358D01*
G37*
G36*
G01X64667Y553723D02*
G02X62723Y555667I-1167J777D01*
G03Y556333I-222J333D01*
G02X64667Y558277I777J1167D01*
G03X65333I333J222D01*
G02X67667I1167J-777D01*
G03X68333I333J222D01*
G02X70667I1167J-777D01*
G03X71333I333J222D01*
G02X73667I1167J-777D01*
G03X74333I333J222D01*
G02X76667I1167J-777D01*
G03X77333I333J222D01*
G02X79667I1167J-777D01*
G03X80333I333J222D01*
G02X82277Y556333I1167J-777D01*
G03Y555667I222J-333D01*
G02X80333Y553723I-777J-1167D01*
G03X79667I-333J-222D01*
G02X77333I-1167J777D01*
G03X76667I-333J-222D01*
G02X74333I-1167J777D01*
G03X73667I-333J-222D01*
G02X71333I-1167J777D01*
G03X70667I-333J-222D01*
G02X68333I-1167J777D01*
G03X67667I-333J-222D01*
G02X65333I-1167J777D01*
G03X64667I-333J-222D01*
G37*
G36*
G01X1913006Y556655D02*
G02X1912416Y555278I794J-1155D01*
G03X1911794Y555545I-395J-63D01*
G02X1912384Y556922I-794J1155D01*
G03X1913006Y556655I395J63D01*
G37*
G36*
G01X1536281Y560614D02*
G02X1533713Y558729I-1385J-805D01*
G03X1533131Y558740I-296J-269D01*
G02X1530906Y558677I-1145J1120D01*
G03X1530366I-270J-295D01*
G02X1528206I-1080J1183D01*
G03X1527666I-270J-295D01*
G02X1525021Y560201I-1080J1183D01*
G03X1524612Y560686I-391J85D01*
G02X1525595Y563490I-74J1600D01*
G03X1526144Y563510I264J301D01*
G02X1528365Y563569I1141J-1124D01*
G03X1528905I270J295D01*
G02X1531065I1080J-1183D01*
G03X1531605I270J295D01*
G02X1533765I1080J-1183D01*
G03X1534305I270J295D01*
G02X1536151Y563793I1080J-1183D01*
G03X1536740Y564098I192J351D01*
G02X1538930Y565399I1591J-185D01*
G03X1539480Y565787I150J371D01*
G02X1542280Y566920I1600J72D01*
G03X1542880I300J265D01*
G02X1543019Y567059I1200J-1061D01*
G03Y567659I-265J300D01*
G02X1545217Y569988I1062J1200D01*
G03X1545737Y569947I284J282D01*
G02X1547621Y569956I948J-1291D01*
G03X1548140Y570001I233J325D01*
G02X1550532Y567875I1145J-1120D01*
G03X1550560Y567342I311J-251D01*
G02X1550607Y565129I-1135J-1131D01*
G03X1550601Y564596I295J-270D01*
G02X1548459Y562241I-1206J-1055D01*
G03X1547940Y562196I-233J-325D01*
G02X1545716Y562132I-1145J1120D01*
G03X1545151Y562106I-269J-296D01*
G02X1542887Y562002I-1184J1079D01*
G03X1542347I-270J-295D01*
G02X1539752Y562663I-1080J1183D01*
G03X1539426Y562744I-189J-65D01*
G02X1539284Y562625I-1098J1166D01*
G03X1539290Y562300I119J-160D01*
G02X1536784Y561034I-905J-1322D01*
G03X1536451Y561190I-200J7D01*
G02X1536379Y561129I-1071J1191D01*
G03X1536281Y560614I248J-314D01*
G37*
G36*
G01X1377086Y560726D02*
G02X1374974Y560635I-1016J-966D01*
G03X1374935Y561176I-313J249D01*
G02X1377398Y562710I1026J1097D01*
G03X1378051Y562532I383J117D01*
G02X1377603Y561386I949J-1032D01*
G03X1377234Y561476I-199J-16D01*
G02X1377078Y561269I-1273J797D01*
G03X1377086Y560726I298J-267D01*
G37*
G36*
G01X1286743Y560598D02*
G02X1286157Y562180I-1343J402D01*
G03X1286757Y562402I217J336D01*
G02X1288885Y563162I1343J-402D01*
G03X1289506Y563450I224J332D01*
G02X1290115Y562138I1394J-150D01*
G03X1289494Y561850I-224J-332D01*
G02X1287343Y560820I-1394J150D01*
G03X1286743Y560598I-217J-336D01*
G37*
G36*
G01X64667Y560723D02*
G02Y562277I-1167J777D01*
G03X65333I333J222D01*
G02X67667I1167J-777D01*
G03X68333I333J222D01*
G02X70667I1167J-777D01*
G03X71333I333J222D01*
G02X73667I1167J-777D01*
G03X74333I333J222D01*
G02X76667I1167J-777D01*
G03X77333I333J222D01*
G02X79667I1167J-777D01*
G03X80333I333J222D01*
G02Y560723I1167J-777D01*
G03X79667I-333J-222D01*
G02X77333I-1167J777D01*
G03X76667I-333J-222D01*
G02X74333I-1167J777D01*
G03X73667I-333J-222D01*
G02X71333I-1167J777D01*
G03X70667I-333J-222D01*
G02X68333I-1167J777D01*
G03X67667I-333J-222D01*
G02X65333I-1167J777D01*
G03X64667I-333J-222D01*
G37*
G36*
G01X1744116Y562666D02*
G02X1742395Y562912I-1016J-966D01*
G03X1742484Y563534I-201J346D01*
G02X1742513Y565496I1016J966D01*
G03X1742447Y566118I-281J285D01*
G02X1742199Y568282I753J1183D01*
G03X1742155Y568881I-285J280D01*
G02X1744001Y569018I845J1119D01*
G03X1744045Y568419I285J-280D01*
G02X1744187Y566304I-845J-1119D01*
G03X1744253Y565682I281J-285D01*
G02X1744205Y563288I-753J-1182D01*
G03X1744116Y562666I201J-346D01*
G37*
G36*
G01X1934521Y563300D02*
G02X1933278Y562368I79J-1400D01*
G03X1932879Y562900I-377J133D01*
G02X1934122Y563832I-79J1400D01*
G03X1934521Y563300I377J-133D01*
G37*
G36*
G01X1417391Y563595D02*
G02X1417219Y561871I1011J-971D01*
G03X1416593Y561933I-337J-215D01*
G02X1416765Y563657I-1011J971D01*
G03X1417391Y563595I337J215D01*
G37*
G36*
G01X1324551Y564312D02*
G02X1322613Y562358I-778J-1167D01*
G03X1321998Y562415I-331J-224D01*
G02X1319833Y562623I-998J985D01*
G03X1319167I-333J-222D01*
G02X1316833I-1167J777D01*
G03X1316167I-333J-222D01*
G02X1313833I-1167J777D01*
G03X1313167I-333J-222D01*
G02X1310833I-1167J777D01*
G03X1310167I-333J-222D01*
G02X1307833I-1167J777D01*
G03X1307167I-333J-222D01*
G02X1304833I-1167J777D01*
G03X1304167I-333J-222D01*
G02X1301990Y564373I-1167J778D01*
G03Y564927I-288J277D01*
G02X1302223Y567067I1010J973D01*
G03Y567733I-222J333D01*
G02X1301990Y569873I777J1167D01*
G03Y570427I-288J277D01*
G02X1304167Y572177I1010J972D01*
G03X1304833I333J222D01*
G02X1307167I1167J-777D01*
G03X1307833I333J222D01*
G02X1310167I1167J-777D01*
G03X1310833I333J222D01*
G02X1313167I1167J-777D01*
G03X1313833I333J222D01*
G02X1316167I1167J-777D01*
G03X1316833I333J222D01*
G02X1319167I1167J-777D01*
G03X1319833I333J222D01*
G02X1322167I1167J-777D01*
G03X1322833I333J222D01*
G02X1325010Y570427I1167J-778D01*
G03Y569873I288J-277D01*
G02X1324809Y567755I-1010J-973D01*
G03X1324758Y567143I230J-327D01*
G02X1324551Y564978I-984J-998D01*
G03Y564312I222J-333D01*
G37*
G36*
G01X645967Y562523D02*
G02Y564077I-1167J777D01*
G03X646633I333J222D01*
G02X648967I1167J-777D01*
G03X649633I333J222D01*
G02X651967I1167J-777D01*
G03X652633I333J222D01*
G02Y562523I1167J-777D01*
G03X651967I-333J-222D01*
G02X649633I-1167J777D01*
G03X648967I-333J-222D01*
G02X646633I-1167J777D01*
G03X645967I-333J-222D01*
G37*
G36*
G01X1781547Y566291D02*
G02X1780064Y566043I-546J-1291D01*
G03X1779953Y566709I-267J298D01*
G02X1779579Y569057I547J1291D01*
G03Y569661I-262J302D01*
G02X1781421I921J1057D01*
G03Y569057I262J-302D01*
G02X1781436Y566957I-921J-1057D01*
G03X1781547Y566291I267J-298D01*
G37*
G36*
G01X1291833Y574879D02*
G02X1290274Y576083I-4430J-4124D01*
G03X1290847Y576550I190J352D01*
G02X1290798Y577116I1343J401D01*
G03X1290376Y577563I-397J48D01*
G02X1291684Y578798I-84J1399D01*
G03X1292106Y578351I397J-48D01*
G02X1292140Y575551I84J-1399D01*
G03X1291833Y574879I-14J-400D01*
G37*
G36*
G01X1936343Y569287D02*
G02X1935512Y567803I557J-1287D01*
G03X1934957Y568113I-396J-57D01*
G02X1935788Y569597I-557J1287D01*
G03X1936343Y569287I396J57D01*
G37*
G36*
G01X1726471Y569981D02*
G02X1724917I-777J-1167D01*
G03Y570647I-222J333D01*
G02X1726471I777J1167D01*
G03Y569981I222J-333D01*
G37*
G36*
G01X1467630Y570975D02*
G02X1467374Y569429I1019J-963D01*
G03X1466719Y569537I-364J-166D01*
G02X1466975Y571083I-1019J963D01*
G03X1467630Y570975I364J166D01*
G37*
G36*
G01X1808834Y571292D02*
G02X1807280I-777J-1167D01*
G03Y571958I-222J333D01*
G02X1808834I777J1167D01*
G03Y571292I222J-333D01*
G37*
G36*
G01X1418208Y569756D02*
G02X1416196Y569715I-1026J955D01*
G03X1415654Y569735I-282J-284D01*
G02X1413758Y571797I-910J1066D01*
G03X1413757Y572366I-282J284D01*
G02X1415676Y574409I986J996D01*
G03X1416233Y574433I266J299D01*
G02X1416588Y574705I1019J-963D01*
G03X1416596Y575405I-190J352D01*
G02X1416340Y575591I691J1220D01*
G03X1415799I-270J-295D01*
G02Y577657I-948J1033D01*
G03X1416340I271J295D01*
G02X1418229Y577663I948J-1033D01*
G03X1418789Y577685I269J296D01*
G02X1420825Y577689I1020J-962D01*
G03X1421424Y577711I290J276D01*
G02X1423286Y575656I1085J-888D01*
G03Y574990I222J-333D01*
G02Y572656I-777J-1167D01*
G03Y571990I222J-333D01*
G02X1421493Y569857I-777J-1167D01*
G03X1420894Y569835I-290J-276D01*
G02X1418791Y569759I-1085J888D01*
G03X1418208Y569756I-290J-276D01*
G37*
G36*
G01X1764596Y575913D02*
G02X1763899Y574647I704J-1213D01*
G03X1763299Y574978I-400J-15D01*
G02X1763996Y576244I-704J1213D01*
G03X1764596Y575913I400J15D01*
G37*
G36*
G01X1386444Y573872D02*
G02X1384021Y574167I-1128J833D01*
G03X1383396Y574322I-370J-153D01*
G02X1383795Y575938I-896J1078D01*
G03X1384420Y575783I370J153D01*
G02X1386266Y575736I896J-1078D01*
G03X1386858Y575793I270J295D01*
G02X1387036Y573929I1128J-833D01*
G03X1386444Y573872I-270J-295D01*
G37*
G36*
G01X72667Y574223D02*
G02X70723Y576167I-1167J777D01*
G03Y576833I-222J333D01*
G02X72667Y578777I777J1167D01*
G03X73333I333J222D01*
G02X75277Y576833I1167J-777D01*
G03Y576167I222J-333D01*
G02X73333Y574223I-777J-1167D01*
G03X72667I-333J-222D01*
G37*
G36*
G01X79667D02*
G02X77723Y576167I-1167J777D01*
G03Y576833I-222J333D01*
G02X79667Y578777I777J1167D01*
G03X80333I333J222D01*
G02X82277Y576833I1167J-777D01*
G03Y576167I222J-333D01*
G02X80333Y574223I-777J-1167D01*
G03X79667I-333J-222D01*
G37*
G36*
G01X1304167Y575223D02*
G02X1302223Y577167I-1167J777D01*
G03Y577833I-222J333D01*
G02X1304167Y579777I777J1167D01*
G03X1304833I333J222D01*
G02X1306777Y577833I1167J-777D01*
G03Y577167I222J-333D01*
G02X1304833Y575223I-777J-1167D01*
G03X1304167I-333J-222D01*
G37*
G36*
G01X1935503Y577183D02*
G02X1935270Y578606I-1303J517D01*
G03X1935947Y578717I305J259D01*
G02X1936180Y577294I1303J-517D01*
G03X1935503Y577183I-305J-259D01*
G37*
G36*
G01X1383529Y580052D02*
G02X1381918Y580375I-1029J-952D01*
G03X1382045Y581011I-166J364D01*
G02X1383656Y580688I1029J952D01*
G03X1383529Y580052I166J-364D01*
G37*
G36*
G01X1780237Y580693D02*
G02X1778686Y580641I-736J-1193D01*
G03X1778663Y581307I-233J325D01*
G02X1778490Y583566I737J1193D01*
G03X1778401Y584232I-260J304D01*
G02X1778223Y586667I599J1268D01*
G03Y587333I-222J333D01*
G02X1779777I777J1167D01*
G03Y586667I222J-333D01*
G02X1779910Y584434I-777J-1167D01*
G03X1779999Y583768I260J-304D01*
G02X1780214Y581359I-599J-1268D01*
G03X1780237Y580693I233J-325D01*
G37*
G36*
G01X1431862Y580346D02*
G02X1429326Y580244I-1292J544D01*
G03X1428644Y580290I-355J-185D01*
G02X1428744Y581746I-1144J810D01*
G03X1429426Y581700I355J185D01*
G02X1431246Y582118I1144J-810D01*
G03X1431808Y582314I193J350D01*
G02X1432046Y582695I1293J-543D01*
G03X1431933Y583312I-301J264D01*
G02X1433644Y583625I658J1238D01*
G03X1433757Y583008I301J-264D01*
G02X1432424Y580542I-657J-1238D01*
G03X1431862Y580346I-193J-350D01*
G37*
G36*
G01X723628Y580068D02*
G02Y581732I-1128J832D01*
G03X724272I322J238D01*
G02Y580068I1128J-832D01*
G03X723628I-322J-238D01*
G37*
G36*
G01X1283571Y582011D02*
G02X1281629I-971J-1011D01*
G03Y582589I-277J289D01*
G02X1282579Y585002I971J1011D01*
G03X1282872Y585667I-6J400D01*
G02X1284548Y584343I4531J4012D01*
G03X1283969Y583904I-188J-353D01*
G02X1283571Y582589I-1369J-303D01*
G03Y582011I277J-289D01*
G37*
G36*
G01X72667Y581223D02*
G02Y582777I-1167J777D01*
G03X73333I333J222D01*
G02Y581223I1167J-777D01*
G03X72667I-333J-222D01*
G37*
G36*
G01X79667D02*
G02Y582777I-1167J777D01*
G03X80333I333J222D01*
G02Y581223I1167J-777D01*
G03X79667I-333J-222D01*
G37*
G36*
G01X1793330Y584687D02*
G02X1792007Y585292I-1160J-787D01*
G03X1792292Y585914I-46J398D01*
G02X1793615Y585309I1160J787D01*
G03X1793330Y584687I46J-398D01*
G37*
G36*
G01X1857775Y587634D02*
G02X1856700Y586776I225J-1384D01*
G03X1856265Y587320I-371J149D01*
G02X1857340Y588178I-225J1384D01*
G03X1857775Y587634I371J-149D01*
G37*
G36*
G01X1739937Y587832D02*
G02X1738234Y587102I-437J-1332D01*
G03X1737997Y587654I-361J172D01*
G02X1737778Y587747I437J1332D01*
G03X1737239Y587582I-186J-354D01*
G02X1736659Y589483I-1236J662D01*
G03X1737198Y589648I186J354D01*
G02X1738077Y590342I1236J-662D01*
G03X1738243Y591026I-101J387D01*
G02X1738719Y593394I936J1044D01*
G03X1738961Y593916I-131J378D01*
G02X1738950Y594891I1309J502D01*
G03X1738715Y595400I-377J135D01*
G02X1740531Y596239I496J1311D01*
G03X1740766Y595730I377J-135D01*
G02X1740730Y593095I-496J-1311D01*
G03X1740488Y592573I131J-378D01*
G02X1739536Y590714I-1309J-503D01*
G03X1739370Y590030I101J-387D01*
G02X1739700Y588384I-936J-1044D01*
G03X1739937Y587832I361J-172D01*
G37*
G36*
G01X1399147Y586309D02*
G02X1397189Y588243I-1167J777D01*
G03X1397195Y588899I-226J330D01*
G02X1396711Y589513I815J1141D01*
G03X1396056Y589644I-371J-151D01*
G02X1396359Y591157I-996J986D01*
G03X1397014Y591026I371J151D01*
G02X1399282Y590629I996J-986D01*
G03X1399942Y590528I363J168D01*
G02X1401990Y588613I1038J-942D01*
G03Y588059I288J-277D01*
G02X1399813Y586309I-1010J-972D01*
G03X1399147I-333J-222D01*
G37*
G36*
G01X1821030Y593534D02*
G02X1820316Y595039I-1376J269D01*
G03X1820897Y595315I189J353D01*
G02X1821611Y593810I1376J-269D01*
G03X1821030Y593534I-189J-353D01*
G37*
G36*
G01X1938781Y595545D02*
G02X1937060Y595624I-911J-1065D01*
G03X1937089Y596255I-231J327D01*
G02X1938810Y596176I911J1065D01*
G03X1938781Y595545I231J-327D01*
G37*
G36*
G01X1444034Y596099D02*
G02X1442396Y595368I-380J-1350D01*
G03X1442145Y595929I-359J176D01*
G02X1442075Y598607I380J1350D01*
G03X1442286Y599198I-128J379D01*
G02X1443923Y598616I1187J746D01*
G03X1443712Y598025I128J-379D01*
G02X1443783Y596660I-1187J-746D01*
G03X1444034Y596099I359J-176D01*
G37*
G36*
G01X64667Y595223D02*
G02X62723Y597167I-1167J777D01*
G03Y597833I-222J333D01*
G02Y600167I777J1167D01*
G03Y600833I-222J333D01*
G02X64667Y602777I777J1167D01*
G03X65333I333J222D01*
G02X67667I1167J-777D01*
G03X68333I333J222D01*
G02X70667I1167J-777D01*
G03X71333I333J222D01*
G02X73667I1167J-777D01*
G03X74333I333J222D01*
G02X76667I1167J-777D01*
G03X77333I333J222D01*
G02X79667I1167J-777D01*
G03X80333I333J222D01*
G02X82277Y600833I1167J-777D01*
G03Y600167I222J-333D01*
G02Y597833I-777J-1167D01*
G03Y597167I222J-333D01*
G02X80333Y595223I-777J-1167D01*
G03X79667I-333J-222D01*
G02X77333I-1167J777D01*
G03X76667I-333J-222D01*
G02X74333I-1167J777D01*
G03X73667I-333J-222D01*
G02X71333I-1167J777D01*
G03X70667I-333J-222D01*
G02X68333I-1167J777D01*
G03X67667I-333J-222D01*
G02X65333I-1167J777D01*
G03X64667I-333J-222D01*
G37*
G36*
G01X1310267Y597723D02*
G02X1308090Y599473I-1167J778D01*
G03Y600027I-288J277D01*
G02X1310267Y601777I1010J972D01*
G03X1310933I333J222D01*
G02X1313267I1167J-777D01*
G03X1313933I333J222D01*
G02X1316267I1167J-777D01*
G03X1316933I333J222D01*
G02X1319267I1167J-777D01*
G03X1319933I333J222D01*
G02X1322110Y600027I1167J-778D01*
G03Y599473I288J-277D01*
G02X1319933Y597723I-1010J-972D01*
G03X1319267I-333J-222D01*
G02X1316933I-1167J777D01*
G03X1316267I-333J-222D01*
G02X1313933I-1167J777D01*
G03X1313267I-333J-222D01*
G02X1310933I-1167J777D01*
G03X1310267I-333J-222D01*
G37*
G36*
G01X1385675Y603929D02*
G02X1384126Y603796I-675J-1229D01*
G03X1384069Y604460I-249J313D01*
G02X1383529Y604989I675J1229D01*
G03X1382964Y605125I-347J-199D01*
G02X1383415Y607000I-764J1175D01*
G03X1383980Y606864I347J199D01*
G02X1385618Y604593I764J-1175D01*
G03X1385675Y603929I249J-313D01*
G37*
G36*
G01X1454689Y602452D02*
G02X1452656Y604378I-1061J916D01*
G03X1452616Y604988I-278J288D01*
G02X1452404Y605181I833J1128D01*
G03X1451798Y605171I-299J-266D01*
G02X1449720Y605084I-1078J896D01*
G03X1449132Y605065I-285J-280D01*
G02X1447003Y605073I-1061J916D01*
G03X1446354Y605016I-304J-259D01*
G02X1446213Y606635I-1209J710D01*
G03X1446862Y606692I304J259D01*
G02X1449071Y606964I1209J-711D01*
G03X1449659Y606983I285J280D01*
G02X1451767Y607000I1061J-916D01*
G03X1452373Y607010I299J266D01*
G02X1454451Y607097I1078J-896D01*
G03X1455039Y607116I285J280D01*
G02X1457072Y605190I1061J-916D01*
G03X1457112Y604580I278J-288D01*
G02X1455277Y602471I-835J-1126D01*
G03X1454689Y602452I-285J-280D01*
G37*
G36*
G01X713077Y605061D02*
G02X711135I-971J-1011D01*
G03Y605639I-277J289D01*
G02X711703Y607993I971J1011D01*
G03X711931Y608582I-115J383D01*
G02X714356Y609989I1201J724D01*
G03X715016Y609932I349J195D01*
G02X714882Y608367I1090J-882D01*
G03X714222Y608424I-349J-195D01*
G02X713535Y607963I-1090J882D01*
G03X713307Y607374I115J-383D01*
G02X713077Y605639I-1201J-724D01*
G03Y605061I277J-289D01*
G37*
G36*
G01X1758833Y605723D02*
G02X1757309Y605002I-283J-1373D01*
G03X1757036Y605580I-354J186D01*
G02X1758560Y606301I283J1373D01*
G03X1758833Y605723I354J-186D01*
G37*
G36*
G01X1921759Y605264D02*
G02X1921707Y603713I1141J-815D01*
G03X1921041Y603736I-341J-210D01*
G02X1921093Y605287I-1141J815D01*
G03X1921759Y605264I341J210D01*
G37*
G36*
G01X1470066Y608965D02*
G02X1468457Y608910I-765J-1175D01*
G03X1468435Y609564I-241J319D01*
G02X1470044Y609619I765J1175D01*
G03X1470066Y608965I241J-319D01*
G37*
G36*
G01X1498208Y611341D02*
G02X1496845Y611026I-408J-1341D01*
G03X1496689Y611702I-272J293D01*
G02X1495870Y612364I407J1342D01*
G03X1495205Y612417I-350J-193D01*
G02X1493563Y611985I-1105J863D01*
G03X1493011Y611640I-153J-370D01*
G02X1492140Y613096I-1499J92D01*
G03X1492705Y613420I167J364D01*
G02X1492859Y613932I1395J-140D01*
G03X1492559Y614514I-354J186D01*
G02X1493991Y615251I191J1389D01*
G03X1494291Y614669I354J-186D01*
G02X1495327Y613959I-191J-1389D01*
G03X1495992Y613906I350J193D01*
G02X1498052Y612017I1105J-862D01*
G03X1498208Y611341I272J-293D01*
G37*
G36*
G01X730778Y610078D02*
G02X728540Y609964I-1162J785D01*
G03X727928Y609966I-307J-256D01*
G02X727933Y611770I-1071J905D01*
G03X728545Y611768I307J256D01*
G02X730698Y611754I1071J-905D01*
G03X731338Y611785I308J255D01*
G02X731418Y610109I1162J-784D01*
G03X730778Y610078I-308J-255D01*
G37*
G36*
G01X1701138Y618388D02*
G02X1700272Y616314I4633J-3152D01*
G03X1699708Y616752I-392J77D01*
G02X1700430Y618481I-602J1266D01*
G03X1701138Y618388I377J132D01*
G37*
G36*
G01X79667Y611223D02*
G02Y612777I-1167J777D01*
G03X80333I333J222D01*
G02Y611223I1167J-777D01*
G03X79667I-333J-222D01*
G37*
G36*
G01X70667Y614723D02*
G02Y616277I-1167J777D01*
G03X71333I333J222D01*
G02X73667I1167J-777D01*
G03X74333I333J222D01*
G02X76667I1167J-777D01*
G03X77333I333J222D01*
G02X79667I1167J-777D01*
G03X80333I333J222D01*
G02Y614723I1167J-777D01*
G03X79667I-333J-222D01*
G02X77333I-1167J777D01*
G03X76667I-333J-222D01*
G02X74333I-1167J777D01*
G03X73667I-333J-222D01*
G02X71333I-1167J777D01*
G03X70667I-333J-222D01*
G37*
G36*
G01X1471710Y617638D02*
G02X1469044Y617506I-1354J362D01*
G03X1468485Y617720I-374J-141D01*
G02X1469151Y619458I-646J1244D01*
G03X1469710Y619244I374J141D01*
G02X1471006Y619242I646J-1244D01*
G03X1471578Y619493I185J355D01*
G02X1474057Y619968I1354J-362D01*
G03X1474712Y619987I321J239D01*
G02X1476871Y620212I1171J-770D01*
G03X1477451Y620231I281J284D01*
G02X1479164Y620535I1049J-931D01*
G03X1479714Y620712I190J352D01*
G02X1482272Y620633I1261J-612D01*
G03X1482783Y620411I370J152D01*
G02X1481982Y618567I496J-1311D01*
G03X1481471Y618789I-370J-152D01*
G02X1480311Y618865I-497J1311D01*
G03X1479761Y618688I-190J-352D01*
G02X1477512Y618305I-1261J612D01*
G03X1476932Y618286I-281J-284D01*
G02X1474758Y618380I-1049J931D01*
G03X1474103Y618361I-321J-239D01*
G02X1472282Y617889I-1171J770D01*
G03X1471710Y617638I-185J-355D01*
G37*
G36*
G01X92682Y618956D02*
G02X92719Y617218I1118J-846D01*
G03X92131Y617249I-308J-255D01*
G02X89762Y618451I-981J1001D01*
G03X89365Y618908I-396J57D01*
G02X88156Y619592I-5J1402D01*
G03X87461Y619579I-344J-205D01*
G02X87434Y620968I-1231J671D01*
G03X88129Y620981I344J205D01*
G02X90158Y621463I1231J-671D01*
G03X90734Y621594I228J328D01*
G02X92499Y619609I1218J-694D01*
G03X92321Y619021I156J-368D01*
G02X92351Y618974I-1167J-778D01*
G03X92682Y618956I172J103D01*
G37*
G36*
G01X1778267Y620296D02*
G02X1777054Y619294I133J-1396D01*
G03X1776633Y619804I-384J112D01*
G02X1777846Y620806I-133J1396D01*
G03X1778267Y620296I384J-112D01*
G37*
G36*
G01X1517373Y618790D02*
G02X1515315Y618912I-973J1010D01*
G03X1514716Y618934I-309J-254D01*
G02X1512666Y618953I-1016J966D01*
G03X1512112Y618988I-295J-270D01*
G02X1510259Y619021I-908J1068D01*
G03X1509670Y618966I-269J-296D01*
G02X1507346Y619092I-1120J844D01*
G03X1506708Y619159I-344J-204D01*
G02X1506883Y620829I-1029J952D01*
G03X1507521Y620762I344J204D01*
G02X1509495Y620845I1029J-952D01*
G03X1510084Y620900I269J296D01*
G02X1512238Y621003I1120J-844D01*
G03X1512792Y620968I295J270D01*
G02X1514785Y620788I908J-1068D01*
G03X1515384Y620766I309J254D01*
G02X1517373Y620810I1016J-966D01*
G03X1517927I277J288D01*
G02Y618790I973J-1010D01*
G03X1517373I-277J-288D01*
G37*
G36*
G01X1322260Y281218D02*
X1318751D01*
G02Y284242I0J1512D01*
G01X1322261D01*
G02X1323772Y282740I-1J-1512D01*
G01Y282645D01*
X1323762Y282561D01*
G02X1323058Y281447I-1502J170D01*
G03X1323004Y281396I108J-168D01*
G02X1322837Y281316I-160J120D01*
G03X1322763Y281305I-8J-200D01*
G02X1322260Y281218I-505J1425D01*
G37*
G36*
G01X1323733Y281174D02*
X1327244D01*
G02X1328422Y280609I0J-1511D01*
G03X1329023Y280584I311J251D01*
G02X1328993Y278685I1016J-966D01*
G03X1328390Y278679I-299J-266D01*
G02X1327243Y278152I-1147J984D01*
G01X1323734D01*
G02X1322936Y280946I0J1511D01*
G03X1322990Y280997I-108J168D01*
G02X1323157Y281077I160J-120D01*
G03X1323231Y281088I8J200D01*
G02X1323733Y281174I503J-1425D01*
G37*
G36*
G01X1453595Y267493D02*
G02X1452725Y265728I461J-1324D01*
G03X1452214Y265980I-380J-126D01*
G02X1450528Y266623I-461J1324D01*
G03X1449828I-350J-194D01*
G02X1447378Y266622I-1225J681D01*
G03X1446679I-350J-194D01*
G02X1444228Y266623I-1225J682D01*
G03X1443529I-350J-194D01*
G02X1441623Y268529I-1226J680D01*
G03Y269228I-195J349D01*
G02X1441622Y271679I680J1226D01*
G03Y272378I-195J350D01*
G02X1443529Y274284I682J1225D01*
G03X1444229I350J194D01*
G02X1444773Y274828I1225J-681D01*
G03Y275528I-194J350D01*
G02X1444772Y277978I681J1225D01*
G03Y278677I-194J350D01*
G02X1444229Y279221I683J1224D01*
G03X1443529I-350J-194D01*
G02Y280583I-1225J681D01*
G03X1444229I350J194D01*
G02X1446679Y280584I1225J-681D01*
G03X1447378I349J194D01*
G02X1447923Y281128I1225J-682D01*
G03Y281827I-195J349D01*
G02X1447921Y284278I680J1226D01*
G03Y284977I-194J350D01*
G02Y287427I682J1225D01*
G03Y288126I-194J350D01*
G02X1447378Y288669I682J1225D01*
G03X1446679I-350J-194D01*
G02X1444229I-1225J682D01*
G03X1443530I-350J-194D01*
G02X1441622Y290575I-1226J681D01*
G03Y291274I-194J349D01*
G02X1443513Y293209I682J1225D01*
G03X1444206Y293215I345J203D01*
G02X1444711Y293731I1221J-689D01*
G03Y294419I-205J344D01*
G02X1444774Y296864I716J1205D01*
G03X1444780Y297569I-187J354D01*
G02X1444228Y298118I674J1229D01*
G03X1443529I-350J-194D01*
G02Y299479I-1226J681D01*
G03X1444228I349J194D01*
G02X1444773Y300023I1225J-682D01*
G03Y300723I-194J350D01*
G02Y303173I681J1225D01*
G03Y303873I-194J350D01*
G02X1444229Y304417I681J1225D01*
G03X1443529I-350J-194D01*
G02X1441622Y306323I-1225J681D01*
G03Y307022I-194J350D01*
G02X1441623Y309472I682J1225D01*
G03Y310172I-194J350D01*
G02X1443529Y312078I681J1225D01*
G03X1444229I350J194D01*
G02X1446135Y310172I1225J-681D01*
G03Y309472I194J-350D01*
G02X1446679Y308929I-680J-1226D01*
G03X1447378I349J194D01*
G02X1449285Y307022I1225J-682D01*
G03Y306323I194J-350D01*
G02X1449828Y305779I-683J-1224D01*
G03X1450528I350J194D01*
G02X1452434Y303873I1225J-681D01*
G03Y303173I194J-350D01*
G02X1452978Y302630I-680J-1226D01*
G03X1453677I349J194D01*
G02X1455583Y300723I1225J-682D01*
G03Y300023I194J-350D01*
G02X1456127Y299479I-681J-1225D01*
G03X1456827I350J194D01*
G02X1459277I1225J-681D01*
G03X1459977I350J194D01*
G02X1460521Y300023I1225J-681D01*
G03Y300723I-194J350D01*
G02Y303173I681J1225D01*
G03Y303873I-194J350D01*
G02X1459977Y304417I681J1225D01*
G03X1459277I-350J-194D01*
G02X1457370Y306323I-1225J681D01*
G03Y307022I-194J350D01*
G02X1456827Y307566I683J1224D01*
G03X1456127I-350J-194D01*
G02X1454221Y309472I-1225J681D01*
G03Y310172I-194J350D01*
G02X1453677Y310715I680J1226D01*
G03X1452978I-350J-194D01*
G02X1451071Y312622I-1225J682D01*
G03Y313321I-194J350D01*
G02X1450528Y313865I683J1224D01*
G03X1449828I-350J-194D01*
G02X1447922Y315771I-1225J681D01*
G03Y316471I-194J350D01*
G02X1447389Y316995I681J1225D01*
G03X1446706Y317012I-347J-200D01*
G02X1446742Y318473I-1178J760D01*
G03X1447425Y318456I347J200D01*
G02X1449828Y318377I1178J-760D01*
G03X1450528I350J194D01*
G02X1452982Y318370I1225J-681D01*
G03X1453687Y318376I351J192D01*
G02X1455580Y316482I1241J-653D01*
G03X1455574Y315776I185J-355D01*
G02X1456127Y315227I-672J-1230D01*
G03X1456827I350J194D01*
G02X1459277I1225J-681D01*
G03X1459977I350J194D01*
G02X1461884Y313321I1225J-681D01*
G03Y312622I194J-350D01*
G02X1462427Y312079I-682J-1225D01*
G03X1463126I349J194D01*
G02X1465032Y310171I1225J-682D01*
G03Y309472I194J-350D01*
G02Y307022I-682J-1225D01*
G03Y306323I195J-350D01*
G02Y303873I-681J-1225D01*
G03Y303173I194J-350D01*
G02Y300723I-681J-1225D01*
G03Y300023I194J-350D01*
G02X1463126Y298116I-681J-1225D01*
G03X1462427I-350J-194D01*
G02X1461884Y297573I-1225J682D01*
G03Y296874I194J-349D01*
G02X1459977Y294968I-682J-1225D01*
G03X1459277I-350J-194D01*
G02X1456827I-1225J681D01*
G03X1456127I-350J-194D01*
G02X1455618Y294444I-1225J681D01*
G03X1455585Y293778I204J-344D01*
G02X1454035Y293856I-834J-1127D01*
G03X1454068Y294522I-204J344D01*
G02X1453676Y294969I834J1127D01*
G03X1452977I-350J-195D01*
G02X1450521Y294975I-1226J680D01*
G03X1449817Y294970I-351J-192D01*
G02X1447352Y294943I-1240J654D01*
G03X1446652I-350J-194D01*
G02X1446143Y294419I-1225J681D01*
G03Y293731I205J-344D01*
G02X1446101Y291297I-716J-1205D01*
G03X1446107Y290592I192J-351D01*
G02X1446679Y290033I-653J-1241D01*
G03X1447378I349J194D01*
G02X1449828Y290032I1225J-682D01*
G03X1450528I350J194D01*
G02X1452978Y290033I1225J-681D01*
G03X1453677I349J194D01*
G02X1456127Y290032I1225J-682D01*
G03X1456827I350J194D01*
G02X1459277I1225J-681D01*
G03X1459977I350J194D01*
G02X1461884Y288126I1225J-681D01*
G03Y287427I194J-350D01*
G02X1462427Y286884I-682J-1225D01*
G03X1463126I349J194D01*
G02X1465032Y284977I1225J-682D01*
G03Y284277I194J-350D01*
G02Y281827I-681J-1225D01*
G03Y281127I194J-350D01*
G02X1465033Y278677I-681J-1225D01*
G03Y277978I194J-350D01*
G02X1465109Y275573I-682J-1225D01*
G03X1465125Y274890I216J-337D01*
G02X1463666Y274856I-702J-1214D01*
G03X1463650Y275539I-216J337D01*
G02X1463126Y276071I701J1214D01*
G03X1462427I-350J-194D01*
G02X1461883Y275528I-1224J683D01*
G03Y274828I194J-350D01*
G02X1459977Y272922I-681J-1225D01*
G03X1459277I-350J-194D01*
G02X1458715Y272368I-1225J681D01*
G03X1458726Y271657I189J-353D01*
G02X1459346Y271048I-624J-1255D01*
G03X1460056Y271047I355J184D01*
G02Y269754I1244J-646D01*
G03X1459346Y269755I-355J-184D01*
G02X1456847Y269778I-1244J647D01*
G03X1456136Y269789I-358J-178D01*
G02X1453677Y269772I-1234J665D01*
G03X1452978I-350J-194D01*
G02X1452434Y269229I-1224J683D01*
G03Y268529I194J-350D01*
G02X1453084Y267745I-681J-1226D01*
G03X1453595Y267493I380J126D01*
G37*
G36*
G01X1646462Y108510D02*
G02X1644556Y110416I-1225J681D01*
G03Y111116I-194J350D01*
G02Y113566I681J1225D01*
G03Y114266I-194J350D01*
G02X1644010Y114813I681J1225D01*
G03X1643310Y114814I-350J-193D01*
G02X1642626Y114201I-1226J680D01*
G03X1642556Y113501I154J-369D01*
G02X1641228Y113633I-786J-1161D01*
G03X1641298Y114333I-154J369D01*
G02X1641440Y116740I786J1161D01*
G03X1641455Y117442I-183J355D01*
G02X1643356Y119376I695J1218D01*
G03X1644041Y119371I344J204D01*
G02X1645919Y117415I1196J-731D01*
G03Y116716I194J-350D01*
G02X1646462Y116172I-683J-1224D01*
G03X1647162I350J194D01*
G02X1649612Y116173I1225J-681D01*
G03X1650311I350J194D01*
G02X1652217Y114266I1225J-682D01*
G03Y113566I194J-350D01*
G02X1652761Y113023I-680J-1226D01*
G03X1653460I350J194D01*
G02X1655910Y113022I1225J-682D01*
G03X1656610I350J194D01*
G02X1657154Y113566I1225J-681D01*
G03Y114266I-194J350D01*
G02X1657153Y116716I681J1225D01*
G03Y117415I-194J349D01*
G02X1656607Y117963I682J1225D01*
G03X1655906Y117960I-350J-194D01*
G02X1654005Y119861I-1233J668D01*
G03X1654008Y120562I-191J351D01*
G02X1654004Y123016I677J1228D01*
G03Y123715I-194J349D01*
G02X1653461Y124258I682J1225D01*
G03X1652762I-349J-194D01*
G02X1650855Y126164I-1226J681D01*
G03Y126864I-194J350D01*
G02Y129314I681J1225D01*
G03Y130014I-194J350D01*
G02X1650854Y132464I681J1225D01*
G03Y133163I-194J350D01*
G02X1650850Y135611I682J1225D01*
G03Y136309I-195J349D01*
G02X1650855Y138761I682J1225D01*
G03Y139461I-194J350D01*
G02Y141912I681J1226D01*
G03Y142612I-194J350D01*
G02X1650856Y145063I681J1225D01*
G03Y145762I-195J350D01*
G02X1652216I680J1226D01*
G03Y145063I195J-349D01*
G02X1652761Y144519I-680J-1226D01*
G03X1653460I350J194D01*
G02X1655910Y144518I1225J-682D01*
G03X1656610I350J194D01*
G02X1657154Y145062I1225J-681D01*
G03Y145762I-194J350D01*
G02X1659060Y147668I681J1225D01*
G03X1659760I350J194D01*
G02X1660304Y148212I1225J-681D01*
G03Y148912I-194J350D01*
G02X1661666I681J1225D01*
G03Y148212I194J-350D01*
G02X1662220Y147651I-680J-1226D01*
G03X1662930Y147662I352J189D01*
G02X1662951Y146374I1256J-624D01*
G03X1662241Y146363I-352J-189D01*
G02X1661666Y145762I-1255J625D01*
G03Y145062I194J-350D01*
G02X1661667Y142612I-681J-1225D01*
G03Y141913I194J-349D01*
G02Y139463I-682J-1225D01*
G03Y138764I194J-350D01*
G02X1662211Y138219I-682J-1225D01*
G03X1662911I350J194D01*
G02Y136857I1225J-681D01*
G03X1662211I-350J-194D01*
G02X1659761I-1225J681D01*
G03X1659061I-350J-194D01*
G02X1657155Y138763I-1225J681D01*
G03Y139463I-194J350D01*
G02X1656610Y140007I680J1226D01*
G03X1655911I-349J-194D01*
G02X1653460Y140005I-1226J680D01*
G03X1652761I-349J-194D01*
G02X1652213Y139460I-1224J683D01*
G03Y138760I194J-350D01*
G02X1652218Y136311I-681J-1226D01*
G03Y135613I195J-349D01*
G02X1652761Y135070I-682J-1225D01*
G03X1653460I350J194D01*
G02X1655367Y133163I1226J-681D01*
G03Y132464I194J-350D01*
G02X1655910Y131920I-683J-1224D01*
G03X1656610I350J194D01*
G02X1659060I1225J-681D01*
G03X1659760I350J194D01*
G02X1662210I1225J-681D01*
G03X1662910I350J194D01*
G02X1665360Y131921I1225J-681D01*
G03X1666059I350J194D01*
G02Y130557I1225J-682D01*
G03X1665360I-349J-194D01*
G02X1664816Y130014I-1224J683D01*
G03Y129314I194J-350D01*
G02X1662910Y127408I-681J-1225D01*
G03X1662210I-350J-194D01*
G02X1661666Y126864I-1225J681D01*
G03Y126164I194J-350D01*
G02X1661667Y123714I-681J-1225D01*
G03Y123015I194J-350D01*
G02X1662210Y122471I-683J-1224D01*
G03X1662910I350J194D01*
G02X1664816Y120565I1225J-681D01*
G03Y119865I194J-350D01*
G02X1664817Y117415I-681J-1225D01*
G03Y116716I194J-350D01*
G02X1665360Y116173I-682J-1225D01*
G03X1666059I350J194D01*
G02X1668509Y116172I1225J-682D01*
G03X1669209I350J194D01*
G02Y114810I1225J-681D01*
G03X1668509I-350J-194D01*
G02X1667978Y114273I-1225J681D01*
G03X1667968Y113584I198J-347D01*
G02X1666041Y111656I-730J-1197D01*
G03X1665353Y111646I-341J-208D01*
G02X1662910Y111660I-1218J695D01*
G03X1662210I-350J-194D01*
G02X1661666Y111116I-1225J681D01*
G03Y110416I194J-350D01*
G02X1659760Y108510I-681J-1225D01*
G03X1659060I-350J-194D01*
G02X1656610Y108509I-1225J681D01*
G03X1655911I-349J-194D01*
G02X1653461Y108510I-1225J682D01*
G03X1652761I-350J-194D01*
G02X1650311Y108509I-1225J681D01*
G03X1649612I-349J-194D01*
G02X1647162Y108510I-1225J682D01*
G03X1646462I-350J-194D01*
G37*
G36*
G01X1498944Y114388D02*
G02X1501966Y114398I1511J0D01*
G01Y110848D01*
X1501957Y110764D01*
G02X1500456Y109422I-1502J169D01*
G03X1500091Y108859I1J-400D01*
G02X1498755Y109691I-1281J-569D01*
G03X1499098Y110267I-16J400D01*
G02X1498944Y110930I1357J665D01*
G01Y114388D01*
G37*
G36*
G01X1614423Y107267D02*
G02X1613059I-682J-1225D01*
G03Y107966I-194J350D01*
G02X1613060Y110416I682J1225D01*
G03Y111116I-194J350D01*
G02X1612516Y111660I681J1225D01*
G03X1611816I-350J-194D01*
G02X1609366I-1225J681D01*
G03X1608666I-350J-194D01*
G02X1606760Y113566I-1225J681D01*
G03Y114266I-194J350D01*
G02X1608666Y116172I681J1225D01*
G03X1609366I350J194D01*
G02X1609909Y116716I1226J-680D01*
G03Y117415I-194J349D01*
G02X1609910Y119865I682J1225D01*
G03Y120565I-194J350D01*
G02X1609366Y121109I681J1225D01*
G03X1608666I-350J-194D01*
G02X1606759Y123015I-1225J681D01*
G03Y123714I-194J350D01*
G02X1608666Y125620I682J1225D01*
G03X1609366I350J194D01*
G02X1609910Y126164I1225J-681D01*
G03Y126864I-194J350D01*
G02X1611816Y128770I681J1225D01*
G03X1612516I350J194D01*
G02X1614966I1225J-681D01*
G03X1615666I350J194D01*
G02X1618116Y128771I1225J-681D01*
G03X1618815I350J194D01*
G02X1621265Y128770I1225J-682D01*
G03X1621965I350J194D01*
G02X1623872Y126864I1225J-681D01*
G03Y126165I194J-350D01*
G02X1624415Y125622I-682J-1225D01*
G03X1625114I350J194D01*
G02X1627012Y123710I1225J-682D01*
G03X1627018Y123005I192J-351D01*
G02X1627060Y120548I-654J-1240D01*
G03X1627054Y119857I198J-347D01*
G02X1627013Y117422I-715J-1206D01*
G03Y116720I192J-351D01*
G02X1627564Y116172I-674J-1229D01*
G03X1628264I350J194D01*
G02X1630714Y116173I1225J-681D01*
G03X1631413I350J194D01*
G02X1631957Y116716I1224J-683D01*
G03Y117415I-195J349D01*
G02X1633864Y119322I682J1225D01*
G03X1634563I350J194D01*
G02Y117958I1225J-682D01*
G03X1633864I-350J-194D01*
G02X1633320Y117415I-1224J683D01*
G03Y116716I195J-350D01*
G02X1633319Y114266I-682J-1225D01*
G03Y113566I194J-350D01*
G02X1633327Y111120I-681J-1225D01*
G03X1633322Y110426I196J-348D01*
G02X1633309Y107997I-707J-1211D01*
G03X1633299Y107307I197J-348D01*
G02X1631334Y105452I-725J-1200D01*
G03X1630630Y105458I-354J-187D01*
G02X1628753Y107375I-1230J673D01*
G03X1628772Y108074I-185J355D01*
G02X1628282Y108564I716J1206D01*
G03X1627583Y108544I-344J-204D01*
G02X1625615Y110392I-1244J647D01*
G03X1625606Y111082I-207J342D01*
G02X1625664Y113549I694J1218D01*
G03X1625672Y114258I-182J357D01*
G02X1625665Y116720I667J1233D01*
G03Y117422I-192J351D01*
G02X1625643Y119868I674J1229D01*
G03X1625649Y120559I-198J347D01*
G02X1625691Y122995I715J1206D01*
G03X1625685Y123700I-192J351D01*
G02X1625114Y124258I654J1240D01*
G03X1624415I-349J-194D01*
G02X1622508Y126165I-1225J682D01*
G03Y126864I-194J349D01*
G02X1621965Y127408I683J1224D01*
G03X1621265I-350J-194D01*
G02X1618815Y127407I-1225J681D01*
G03X1618116I-350J-194D01*
G02X1615666Y127408I-1225J682D01*
G03X1614966I-350J-194D01*
G02X1614436Y126872I-1225J681D01*
G03X1614425Y126184I199J-347D01*
G02X1614354Y123755I-735J-1194D01*
G03X1614366Y123045I190J-352D01*
G02X1614422Y120565I-625J-1255D01*
G03Y119865I194J-350D01*
G02X1614966Y119322I-680J-1226D01*
G03X1615665I350J195D01*
G02X1617524Y117391I1225J-681D01*
G03X1617515Y116682I181J-357D01*
G02X1617574Y114250I-667J-1233D01*
G03X1617583Y113560I207J-342D01*
G02X1615665Y111659I-693J-1219D01*
G03X1614966I-349J-194D01*
G02X1614422Y111116I-1224J683D01*
G03Y110416I194J-350D01*
G02X1614423Y107966I-681J-1225D01*
G03Y107267I194J-350D01*
G37*
G54D72*
X1950000Y220787D03*
Y228661D03*
G54D47*
X11925Y74867D03*
X11864Y71294D03*
X11539Y39927D03*
X11500Y43400D03*
X44050Y504383D03*
X38389Y523748D03*
X27280Y510420D03*
X1439Y546583D03*
X1539Y550183D03*
Y586183D03*
X1439Y582583D03*
X71500Y298000D03*
X66000Y292700D03*
X76800Y298000D03*
X76900Y292600D03*
X66500Y303400D03*
X76800D03*
X47550Y504367D03*
X132959Y-4100D03*
X130313Y-9901D03*
X126580Y-4100D03*
X123620Y-9901D03*
X147045D03*
X132959Y33700D03*
X130313Y27899D03*
X126580Y33700D03*
X123620Y27899D03*
X147045D03*
X130313Y17157D03*
X132959Y12114D03*
X123620Y17157D03*
X126666Y12114D03*
X147045Y17157D03*
X163391Y-4100D03*
X160431Y-9901D03*
X157084Y-3700D03*
X153738Y-9901D03*
X150391Y-3700D03*
X169770Y-4100D03*
X167124Y-9901D03*
X163391Y33700D03*
X160431Y27899D03*
X153738D03*
X169770Y33700D03*
X167124Y27899D03*
X160431Y17157D03*
X163477Y12114D03*
X153738Y17157D03*
X157084Y12114D03*
X150391D03*
X167124Y17157D03*
X169770Y12114D03*
X130313Y65699D03*
X123620D03*
X147045D03*
X130313Y54957D03*
X132959Y49914D03*
X123620Y54957D03*
X126666Y49914D03*
X147045Y54957D03*
X132959Y87714D03*
X126580Y71500D03*
X123620Y92757D03*
X126666Y87714D03*
X147045Y92757D03*
X132959Y71500D03*
X130313Y92757D03*
X160431Y65699D03*
X153738D03*
X167124D03*
X160431Y54957D03*
X163477Y49914D03*
X157084Y34100D03*
X153738Y54957D03*
X157084Y49914D03*
X150391Y34100D03*
Y49914D03*
X167124Y54957D03*
X169770Y49914D03*
X157084Y71900D03*
X153738Y92757D03*
X157084Y87714D03*
X150391Y71900D03*
Y87714D03*
X169770Y71500D03*
X167124Y92757D03*
X169770Y87714D03*
X163391Y71500D03*
X160431Y92757D03*
X163477Y87714D03*
X125663Y230716D03*
X125563Y227116D03*
Y259116D03*
X125663Y262716D03*
Y294716D03*
X125563Y291116D03*
Y323116D03*
X125663Y326716D03*
X125563Y355116D03*
X125663Y358716D03*
Y390716D03*
X125563Y387116D03*
X132959Y513114D03*
X163477D03*
X160431Y518157D03*
X130313D03*
X169770Y513114D03*
X167124Y518157D03*
X150391Y513114D03*
X147045Y518157D03*
X126666Y513114D03*
X123620Y518157D03*
X157084Y513114D03*
X153738Y518157D03*
X130313Y528899D03*
X132959Y588714D03*
X160431Y528899D03*
X163391Y534700D03*
X132959D03*
X169770Y550914D03*
X167124Y555957D03*
X150391Y550914D03*
X147045Y555957D03*
X126666Y550914D03*
X123620Y555957D03*
X157084Y550914D03*
X153738Y555957D03*
X132959Y550914D03*
X163477D03*
X160431Y555957D03*
X130313D03*
X167124Y528899D03*
X169770Y534700D03*
X147045Y528899D03*
X150391Y535100D03*
X123620Y528899D03*
X126580Y534700D03*
X153738Y528899D03*
X157084Y535100D03*
X169770Y588714D03*
X150391D03*
X126666D03*
X157084D03*
X163477D03*
X167124Y566699D03*
X169770Y572500D03*
X147045Y566699D03*
X150391Y572900D03*
X123620Y566699D03*
X126580Y572500D03*
X153738Y566699D03*
X157084Y572900D03*
X130313Y566699D03*
X160431D03*
X163391Y572500D03*
X132959D03*
X130313Y604499D03*
X167124D03*
Y593757D03*
X169770Y610300D03*
X147045Y604499D03*
X150391Y610700D03*
X147045Y593757D03*
X123620Y604499D03*
X126580Y610300D03*
X123620Y593757D03*
X153738Y604499D03*
X157084Y610700D03*
X153738Y593757D03*
X160431Y604499D03*
X163391Y610300D03*
X160431Y593757D03*
X132959Y610300D03*
X130313Y593757D03*
X193895Y-3700D03*
X190549Y-9901D03*
X187202Y-3700D03*
X183856Y-9901D03*
X206581Y-4100D03*
X203935Y-9901D03*
X200202Y-4100D03*
X197242Y-9901D03*
X190549Y27899D03*
X183856D03*
X206581Y33700D03*
X203935Y27899D03*
X200202Y33700D03*
X197242Y27899D03*
X190549Y17157D03*
X193895Y12114D03*
X183856Y17157D03*
X187202Y12114D03*
X203935Y17157D03*
X206581Y12114D03*
X197242Y17157D03*
X200288Y12114D03*
X224013Y-3700D03*
X220667Y-9901D03*
X230706Y-3700D03*
X227360Y-9901D03*
Y27899D03*
X220667D03*
X227360Y17157D03*
X230706Y12114D03*
X220667Y17157D03*
X224013Y12114D03*
X190549Y65699D03*
X183856D03*
X203935D03*
X197242D03*
X190549Y54957D03*
X193895Y34100D03*
Y49914D03*
X183856Y54957D03*
X187202Y34100D03*
Y49914D03*
X203935Y54957D03*
X206581Y49914D03*
X197242Y54957D03*
X200288Y49914D03*
X193895Y71900D03*
X190549Y92757D03*
X193895Y87714D03*
X187202Y71900D03*
X183856Y92757D03*
X187202Y87714D03*
X206581Y71500D03*
X203935Y92757D03*
X206581Y87714D03*
X200202Y71500D03*
X197242Y92757D03*
X200288Y87714D03*
X227360Y65699D03*
X220667D03*
X227360Y54957D03*
X230706Y34100D03*
Y49914D03*
X220667Y54957D03*
X224013Y34100D03*
Y49914D03*
X230706Y71900D03*
X227360Y92757D03*
X230706Y87714D03*
X224013Y71900D03*
X220667Y92761D03*
X224013Y87714D03*
X200288Y513114D03*
X197242Y518157D03*
X230706Y513114D03*
X227360Y518157D03*
X206581Y513114D03*
X203935Y518157D03*
X187202Y513114D03*
X183856Y518157D03*
X193895Y513114D03*
X190549Y518157D03*
X224013Y513114D03*
X220667Y518161D03*
X224013Y535100D03*
X197242Y528899D03*
X200202Y534700D03*
X227360Y528899D03*
X230706Y535100D03*
X203935Y528899D03*
X206581Y534700D03*
X183856Y528899D03*
X187202Y535100D03*
X190549Y528899D03*
X193895Y535100D03*
X224013Y550914D03*
X220667Y555961D03*
X200288Y550914D03*
X197242Y555957D03*
X230706Y550914D03*
X227360Y555957D03*
X206581Y550914D03*
X203935Y555957D03*
X187202Y550914D03*
X183856Y555957D03*
X193895Y550914D03*
X190549Y555957D03*
X220667Y528899D03*
Y566699D03*
X224013Y572900D03*
X197242Y566699D03*
X200202Y572500D03*
X227360Y566699D03*
X230706Y572900D03*
X203935Y566699D03*
X206581Y572500D03*
X183856Y566699D03*
X187202Y572900D03*
X190549Y566699D03*
X193895Y572900D03*
X224013Y588714D03*
X200288D03*
X230706D03*
X206581D03*
X187202D03*
X193895D03*
X220667Y604499D03*
X224013Y610700D03*
X220667Y593761D03*
X197242Y604499D03*
Y593757D03*
X200202Y610300D03*
X227360Y604499D03*
X230706Y610700D03*
X227360Y593757D03*
X203935Y604499D03*
X206581Y610300D03*
X203935Y593757D03*
X183856Y604499D03*
Y593757D03*
X187202Y610700D03*
X190549Y604499D03*
Y593757D03*
X193895Y610700D03*
X243392Y-4100D03*
X240746Y-9901D03*
X267517Y-3700D03*
X264171Y-9901D03*
X237013Y-4100D03*
X234053Y-9901D03*
X260824Y-3700D03*
X257478Y-9901D03*
X270864D03*
X243392Y33700D03*
X240746Y27899D03*
X264171D03*
X237013Y33700D03*
X234053Y27899D03*
X257478D03*
X270864D03*
X240746Y17157D03*
X243392Y12114D03*
X264171Y17157D03*
X267517Y12114D03*
X234053Y17157D03*
X237099Y12114D03*
X257478Y17157D03*
X260824Y12114D03*
X270864Y17157D03*
X280203Y-4100D03*
X277557Y-9901D03*
X273824Y-4100D03*
X280203Y33700D03*
X277557Y27899D03*
X273824Y33700D03*
X277557Y17157D03*
X280203Y12114D03*
X273910D03*
X240746Y65699D03*
X264171D03*
X234053D03*
X257478D03*
X270864D03*
X240746Y54957D03*
X243392Y49914D03*
X264171Y54957D03*
X267517Y34100D03*
Y49914D03*
X234053Y54957D03*
X237099Y49914D03*
X257478Y54957D03*
X260824Y34100D03*
Y49914D03*
X270864Y54957D03*
X243392Y71500D03*
X240746Y92757D03*
X243392Y87714D03*
X267517Y71900D03*
X264171Y92757D03*
X267517Y87714D03*
X237013Y71500D03*
X234053Y92757D03*
X237099Y87714D03*
X260824Y71900D03*
X257478Y92757D03*
X260824Y87714D03*
X270864Y92757D03*
X277557Y65699D03*
Y54957D03*
X280203Y49914D03*
X273910D03*
X280203Y71500D03*
X277557Y92757D03*
X280203Y87714D03*
X273824Y71500D03*
X273910Y87714D03*
X240746Y112327D03*
X243392Y106934D03*
X264171Y112327D03*
X267517Y107284D03*
X234053Y112327D03*
X237099Y107284D03*
X257478Y112327D03*
X260824Y107284D03*
X270864Y112327D03*
X277557D03*
X280203Y106934D03*
X273910Y107284D03*
X260824Y493744D03*
X257478Y498487D03*
X236892Y490800D03*
X233292Y498500D03*
X267584Y493919D03*
X264171Y498487D03*
X243392Y495694D03*
X239592Y495900D03*
X273910Y513114D03*
X270864Y518157D03*
X280203Y513114D03*
X277557Y518157D03*
X260824Y513114D03*
X257478Y518157D03*
X237099Y513114D03*
X234053Y518157D03*
X267517Y513114D03*
X264171Y518157D03*
X243392Y513114D03*
X240746Y518157D03*
X273992Y493744D03*
X271092Y498644D03*
X280203Y493244D03*
X277557Y498644D03*
X260824Y550914D03*
X257478Y555957D03*
X237099Y550914D03*
X234053Y555957D03*
X267517Y550914D03*
X264171Y555957D03*
X243392Y550914D03*
X240746Y555957D03*
X270864Y528899D03*
X273824Y534700D03*
X277557Y528899D03*
X280203Y534700D03*
X257478Y528899D03*
X260824Y535100D03*
X234053Y528899D03*
X237013Y534700D03*
X264171Y528899D03*
X267517Y535100D03*
X240746Y528899D03*
X243392Y534700D03*
X273910Y550914D03*
X270864Y555957D03*
X280203Y550914D03*
X277557Y555957D03*
X264171Y566699D03*
X267517Y572900D03*
X240746Y566699D03*
X243392Y572500D03*
X280203Y588714D03*
X260824D03*
X237099D03*
X267517D03*
X243392D03*
X270864Y566699D03*
X273824Y572500D03*
X277557Y566699D03*
X280203Y572500D03*
X257478Y566699D03*
X260824Y572900D03*
X234053Y566699D03*
X237013Y572500D03*
X273910Y588714D03*
X277557Y604499D03*
X280203Y610300D03*
X277557Y593757D03*
X257478Y604499D03*
Y593757D03*
X260824Y610700D03*
X234053Y604499D03*
Y593757D03*
X237013Y610300D03*
X264171Y604499D03*
X267517Y610700D03*
X264171Y593757D03*
X240746Y604499D03*
Y593757D03*
X243392Y610300D03*
X270864Y604499D03*
X273824Y610300D03*
X270864Y593757D03*
X304328Y-3700D03*
X300982Y-9901D03*
X297635Y-3700D03*
X294289Y-9901D03*
X300982Y27899D03*
X294289D03*
X300982Y17157D03*
X304328Y12114D03*
X294289Y17157D03*
X297635Y12114D03*
X300982Y65699D03*
X294289D03*
X300982Y54957D03*
X304328Y34100D03*
Y49914D03*
X294289Y54957D03*
X297635Y34100D03*
Y49914D03*
X304328Y71900D03*
X300982Y92757D03*
X304328Y87714D03*
X297635Y71900D03*
X294289Y92757D03*
X297635Y87714D03*
X300982Y109700D03*
X304178Y107684D03*
X294889Y110927D03*
X297635Y105084D03*
X297835Y494944D03*
X294392Y493100D03*
X304392Y494700D03*
X301092Y493300D03*
X297635Y513114D03*
X294289Y518157D03*
X304328Y513114D03*
X300982Y518157D03*
X297635Y550914D03*
X294289Y555957D03*
X304328Y550914D03*
X300982Y555957D03*
X294289Y528899D03*
X297635Y535100D03*
X300982Y528899D03*
X304328Y535100D03*
X297635Y588714D03*
X304328D03*
X294289Y566699D03*
X297635Y572900D03*
X300982Y566699D03*
X294289Y604499D03*
X297635Y610700D03*
X294289Y593757D03*
X300982Y604499D03*
X304328Y610700D03*
X300982Y593757D03*
X451573Y-9901D03*
Y27899D03*
Y17157D03*
X460912Y-4100D03*
X458266Y-9901D03*
X454533Y-4100D03*
X478344Y-3700D03*
X474998Y-9901D03*
X460912Y33700D03*
X458266Y27899D03*
X454533Y33700D03*
X474998Y27899D03*
X458266Y17157D03*
X460912Y12114D03*
X454619D03*
X474998Y17157D03*
X478344Y12114D03*
X451573Y65699D03*
Y54957D03*
Y92757D03*
X458266Y65699D03*
X474998D03*
X458266Y54957D03*
X460912Y49914D03*
X454619Y49564D03*
X474998Y54957D03*
X478344Y34100D03*
Y49914D03*
Y87714D03*
X460912Y71500D03*
X458266Y92757D03*
X460912Y87714D03*
X454533Y71500D03*
X454619Y87714D03*
X478344Y71900D03*
X474998Y92757D03*
X478344Y513114D03*
X474998Y518157D03*
X454619Y513114D03*
X460912D03*
X458266Y518157D03*
X454619Y550914D03*
X474998Y528899D03*
X478344Y535100D03*
X454533Y534700D03*
X458266Y528899D03*
X460912Y534700D03*
X478344Y550914D03*
X474998Y555957D03*
X460912Y550914D03*
X458266Y555957D03*
X478344Y588714D03*
X454619D03*
X460912D03*
X474998Y566699D03*
X478344Y572900D03*
X454533Y572500D03*
X458266Y566699D03*
X460912Y572500D03*
X478344Y610700D03*
X474998Y593757D03*
X451573Y604499D03*
X454533Y610300D03*
X451573Y593757D03*
X458266Y604499D03*
Y593757D03*
X460912Y610300D03*
X474998Y604499D03*
X485037Y-3700D03*
X481691Y-9901D03*
X497723Y-4100D03*
X495077Y-9901D03*
X491344Y-4100D03*
X488384Y-9901D03*
X511809D03*
X481691Y27899D03*
X497723Y33700D03*
X495077Y27899D03*
X491344Y33700D03*
X488384Y27899D03*
X511809D03*
X481691Y17157D03*
X485037Y12114D03*
X495077Y17157D03*
X497723Y12114D03*
X488384Y17157D03*
X491430Y12114D03*
X511809Y17157D03*
X521848Y-3700D03*
X518502Y-9901D03*
X515155Y-3700D03*
X534534Y-4100D03*
X531888Y-9901D03*
X528155Y-4100D03*
X525195Y-9901D03*
X518502Y27899D03*
X534534Y33700D03*
X531888Y27899D03*
X528155Y33700D03*
X525195Y27899D03*
X518502Y17157D03*
X521848Y12114D03*
X515155D03*
X531888Y17157D03*
X534534Y12114D03*
X525195Y17157D03*
X528241Y12114D03*
X481691Y65699D03*
X495077D03*
X488384D03*
X511809D03*
X485037Y34100D03*
X481691Y54957D03*
X485037Y49914D03*
X495077Y54957D03*
X497723Y49914D03*
X488384Y54957D03*
X491430Y49914D03*
X511809Y54957D03*
X497723Y71500D03*
X495077Y92757D03*
X497723Y87714D03*
X491344Y71500D03*
X488384Y92757D03*
X491430Y87714D03*
X511809Y92757D03*
X485037Y71900D03*
X481691Y92757D03*
X485037Y87714D03*
X518502Y65699D03*
X531888D03*
X525195D03*
X521848Y34100D03*
X518502Y54957D03*
X521848Y49914D03*
X515155Y34100D03*
Y49914D03*
X531888Y54957D03*
X534534Y49914D03*
X525195Y54957D03*
X528241Y49914D03*
X521848Y71900D03*
X518502Y92757D03*
X521848Y87714D03*
X515155Y71900D03*
Y87714D03*
X534534Y71500D03*
X531888Y92757D03*
X534534Y87714D03*
X528155Y71500D03*
X525195Y92757D03*
X528241Y87714D03*
X494927Y112357D03*
X497723Y106964D03*
X488634Y112357D03*
X491430Y106964D03*
X512024Y112357D03*
X518317D03*
X521113Y106964D03*
X514820D03*
X531888Y112357D03*
X534534Y106964D03*
X525134Y112357D03*
X528241Y107314D03*
Y513114D03*
X525195Y518157D03*
X534534Y513114D03*
X531888Y518157D03*
X515155Y513114D03*
X511809Y518157D03*
X491430Y513114D03*
X488384Y518157D03*
X521848Y513114D03*
X518502Y518157D03*
X497723Y513114D03*
X495077Y518157D03*
X485037Y513114D03*
X481691Y518157D03*
X528191Y493544D03*
X524595Y498387D03*
X534534Y493394D03*
X530792Y498387D03*
X514755Y493744D03*
X511809Y498487D03*
X491430Y491144D03*
X488384Y498487D03*
X521048Y493844D03*
X517902Y498487D03*
X497723Y490894D03*
X494777Y498487D03*
X525195Y528899D03*
X528155Y534700D03*
X531888Y528899D03*
X534534Y534700D03*
X511809Y528899D03*
X515155Y535100D03*
X488384Y528899D03*
X491344Y534700D03*
X518502Y528899D03*
X521848Y535100D03*
X495077Y528899D03*
X497723Y534700D03*
X481691Y528899D03*
X485037Y535100D03*
X528241Y550914D03*
X525195Y555957D03*
X534534Y550914D03*
X531888Y555957D03*
X515155Y550914D03*
X511809Y555957D03*
X491430Y550914D03*
X488384Y555957D03*
X521848Y550914D03*
X518502Y555957D03*
X497723Y550914D03*
X495077Y555957D03*
X485037Y550914D03*
X481691Y555957D03*
X497723Y588714D03*
X485037D03*
X525195Y566699D03*
X528155Y572500D03*
X531888Y566699D03*
X534534Y572500D03*
X511809Y566699D03*
X515155Y572900D03*
X488384Y566699D03*
X491344Y572500D03*
X518502Y566699D03*
X521848Y572900D03*
X495077Y566699D03*
X497723Y572500D03*
X481691Y566699D03*
X485037Y572900D03*
X528241Y588714D03*
X534534D03*
X515155D03*
X491430D03*
X521848D03*
Y610700D03*
X495077Y604499D03*
Y593757D03*
X498092Y611200D03*
X481691Y604499D03*
Y593757D03*
X485037Y610700D03*
X525195Y604499D03*
Y593757D03*
X531888Y604499D03*
X534534Y610300D03*
X531888Y593757D03*
X511809Y604499D03*
X515155Y610700D03*
X511809Y593757D03*
X488384Y604499D03*
Y593757D03*
X491724Y611668D03*
X518502Y604499D03*
Y593757D03*
X528155Y610300D03*
X558659Y-3700D03*
X555313Y-9901D03*
X551966Y-3700D03*
X548620Y-9901D03*
X571345Y-4100D03*
X568699Y-9901D03*
X564966Y-4100D03*
X562006Y-9901D03*
X555313Y27899D03*
X548620D03*
X571345Y33700D03*
X568699Y27899D03*
X564966Y33700D03*
X562006Y27899D03*
X555313Y17157D03*
X558659Y12114D03*
X548620Y17157D03*
X551966Y12114D03*
X568699Y17157D03*
X571345Y12114D03*
X561868Y17019D03*
X565052Y12114D03*
X595470Y-3700D03*
X592124Y-9901D03*
X588777Y-3700D03*
X585431Y-9901D03*
X592124Y27899D03*
X585431D03*
X592124Y17157D03*
X595470Y12114D03*
X585431Y17157D03*
X588777Y12114D03*
X555313Y65699D03*
X548620D03*
X568699D03*
X562006D03*
X558659Y34100D03*
X555313Y54957D03*
X558659Y49914D03*
X551966Y34100D03*
X548620Y54957D03*
X551966Y49914D03*
X568699Y54957D03*
X571345Y49914D03*
X562006Y54957D03*
X565052Y49914D03*
X565266Y87374D03*
X558659Y71900D03*
X555313Y92757D03*
X558659Y87714D03*
X551966Y71900D03*
X548620Y92757D03*
X551966Y87714D03*
X571345Y71500D03*
X568699Y92757D03*
X571345Y87714D03*
X564966Y71500D03*
X562006Y92757D03*
X592124Y65699D03*
X585431D03*
X592124Y54957D03*
X595470Y34100D03*
Y49914D03*
X585431Y54957D03*
X588777Y34100D03*
Y49914D03*
X595470Y71900D03*
X592124Y92757D03*
X595470Y87714D03*
X588777Y71900D03*
X585431Y92757D03*
X588777Y87714D03*
X555313Y112357D03*
X558659Y107314D03*
X548620Y112357D03*
X551966Y107314D03*
X562006Y518157D03*
X595470Y513114D03*
X592124Y518157D03*
X571345Y513114D03*
X568699Y518157D03*
X551966Y513114D03*
X548620Y518157D03*
X558659Y513114D03*
X555313Y518157D03*
X551366Y493344D03*
X548492Y498400D03*
X558659Y496144D03*
X554792Y498487D03*
X588777Y513114D03*
X585431Y518157D03*
X565266Y512774D03*
X562006Y528899D03*
X564966Y534700D03*
X592124Y528899D03*
X595470Y535100D03*
X568699Y528899D03*
X571345Y534700D03*
X548620Y528899D03*
X551966Y535100D03*
X555313Y528899D03*
X558659Y535100D03*
X588777Y550914D03*
X585431Y555957D03*
X565266Y550574D03*
X562006Y555957D03*
X595470Y550914D03*
X592124Y555957D03*
X571345Y550914D03*
X568699Y555957D03*
X551966Y550914D03*
X548620Y555957D03*
X558659Y550914D03*
X555313Y555957D03*
X585431Y528899D03*
X588777Y535100D03*
X558659Y572900D03*
X588777Y588714D03*
X565052D03*
X595470D03*
X571345D03*
X551966D03*
X558659D03*
X585431Y566699D03*
X588777Y572900D03*
X562006Y566699D03*
X564966Y572500D03*
X592124Y566699D03*
X595470Y572900D03*
X568699Y566699D03*
X571345Y572500D03*
X548620Y566699D03*
X551966Y572900D03*
X555313Y566699D03*
X585431Y604499D03*
Y593757D03*
X588777Y610700D03*
X562006Y604499D03*
Y593757D03*
X592124Y604499D03*
Y593757D03*
X595470Y610700D03*
X568699Y604499D03*
X571345Y610300D03*
X568699Y593757D03*
X548620Y604499D03*
X551966Y610700D03*
X548620Y593757D03*
X555313Y604499D03*
X558659Y610700D03*
X555313Y593757D03*
X564966Y610300D03*
X706500Y207800D03*
X706561Y211417D03*
X782567Y33700D03*
X779921Y27899D03*
X776188Y33700D03*
X773228Y27899D03*
X776274Y12114D03*
X773228Y-9901D03*
X776188Y-4100D03*
X773228Y17157D03*
X782567Y12114D03*
X779921Y-9901D03*
X782567Y-4100D03*
X779921Y17157D03*
Y65699D03*
X773228D03*
X779921Y54957D03*
X782567Y49914D03*
X773228Y54957D03*
X776274Y49914D03*
X782567Y71500D03*
X779921Y92757D03*
X782567Y87714D03*
X776188Y71500D03*
X773228Y92757D03*
X776274Y87714D03*
X775171Y234316D03*
X775271Y262716D03*
X775171Y259116D03*
X775271Y294716D03*
X775171Y291116D03*
X775271Y326716D03*
X775171Y323116D03*
X775271Y358716D03*
X775171Y355116D03*
X775221Y390716D03*
X775121Y387116D03*
X779921Y518157D03*
X782567Y513114D03*
X773228Y518157D03*
X776274Y513114D03*
X782567Y550914D03*
X776274D03*
X779921Y528899D03*
X776188Y534700D03*
X782567Y588714D03*
X776274D03*
X779921Y555957D03*
X782567Y572500D03*
X779921Y566699D03*
X773228Y555957D03*
X776188Y572500D03*
X773228Y566699D03*
X782567Y534700D03*
X773228Y528899D03*
X782567Y610300D03*
X779921Y593757D03*
Y604499D03*
X776188Y610300D03*
X773228Y593757D03*
Y604499D03*
X812999Y33700D03*
X810039Y27899D03*
X803346D03*
X796653D03*
X816732D03*
X833464D03*
X846850D03*
X819378Y33700D03*
X840157Y27899D03*
X796653Y-9901D03*
X833464D03*
X840157D03*
X843503Y-3700D03*
X799999Y12114D03*
X836810D03*
X843503D03*
X840157Y17157D03*
X819378Y12114D03*
X816732Y-9901D03*
Y17157D03*
X819378Y-4100D03*
X799999Y-3700D03*
X796653Y17157D03*
X803346Y-9901D03*
X806692Y12114D03*
Y-3700D03*
X803346Y17157D03*
X846850Y-9901D03*
Y17157D03*
X833464D03*
X836810Y-3700D03*
X810039Y-9901D03*
X813085Y12114D03*
X812999Y-4100D03*
X810039Y17157D03*
Y65699D03*
X803346D03*
X796653D03*
X816732D03*
X810039Y54957D03*
X813085Y49914D03*
X806692Y34100D03*
X803346Y54957D03*
X806692Y49914D03*
X799999Y34100D03*
X796653Y54957D03*
X799999Y49914D03*
X816732Y54957D03*
X812999Y71500D03*
X810039Y92757D03*
X813085Y87714D03*
X806692Y71900D03*
X803346Y92757D03*
X806692Y87714D03*
X799999Y71900D03*
X796653Y92757D03*
X799999Y87714D03*
X816732Y92757D03*
X846850Y65699D03*
X843503Y34100D03*
X833464Y54957D03*
X836810Y34100D03*
Y49914D03*
X846850Y54957D03*
X819378Y49914D03*
X840157Y65699D03*
X833464D03*
X843503Y71900D03*
X840157Y92757D03*
X843503Y87714D03*
X836810Y71900D03*
X833464Y92757D03*
X836810Y87714D03*
X846850Y92757D03*
X819378Y71500D03*
Y87714D03*
X840157Y54957D03*
X843503Y49914D03*
X799999Y513114D03*
X803346Y518157D03*
X806692Y513114D03*
X796653Y518157D03*
X846850D03*
X813085Y513114D03*
X810039Y518157D03*
X819378Y513114D03*
X816732Y518157D03*
X836810Y513114D03*
X833464Y518157D03*
X843503Y513114D03*
X840157Y518157D03*
X796653Y528899D03*
X813085Y550914D03*
X806692D03*
X799999D03*
X806692Y535100D03*
X803346Y528899D03*
X799999Y535100D03*
X816732Y555957D03*
Y566699D03*
X813085Y588714D03*
X806692D03*
X799999D03*
X810039Y555957D03*
X812999Y572500D03*
X810039Y566699D03*
X803346Y555957D03*
X806692Y572900D03*
X803346Y566699D03*
X796653Y555957D03*
X799999Y572900D03*
X796653Y566699D03*
X846850Y528899D03*
X843503Y550914D03*
X836810D03*
X819378D03*
X840157Y555957D03*
X843503Y572900D03*
X840157Y566699D03*
X833464Y555957D03*
Y566699D03*
X846850Y555957D03*
Y566699D03*
X843503Y588714D03*
X836810D03*
X819378D03*
X812999Y534700D03*
X816732Y528899D03*
X819378Y534700D03*
X836810Y535100D03*
X840157Y528899D03*
X843503Y535100D03*
X836810Y572900D03*
X819378Y572500D03*
X810039Y528899D03*
X833464D03*
X812999Y610300D03*
X810039Y593757D03*
Y604499D03*
X806692Y610700D03*
X803346Y593757D03*
Y604499D03*
X799999Y610700D03*
X796653Y593757D03*
Y604499D03*
X816732Y593757D03*
Y604499D03*
X840157Y593757D03*
X843503Y610700D03*
X840157Y604499D03*
X833464Y593757D03*
X836810Y610700D03*
X833464Y604499D03*
X846850Y593757D03*
X819378Y610300D03*
X846850Y604499D03*
X856189Y33700D03*
X853543Y27899D03*
X876968D03*
X849810Y33700D03*
X870275Y27899D03*
X886621Y33700D03*
X883661Y27899D03*
X907086D03*
X893000Y33700D03*
X890354Y27899D03*
X870275Y-9901D03*
X876968D03*
X880314Y-3700D03*
X907086Y-9901D03*
X873621Y12114D03*
X880314D03*
X876968Y17157D03*
X910432Y12114D03*
X907086Y17157D03*
X886707Y12114D03*
X883661Y-9901D03*
Y17157D03*
X886621Y-4100D03*
X893000Y12114D03*
X890354Y-9901D03*
X893000Y-4100D03*
X890354Y17157D03*
X873621Y-3700D03*
X870275Y17157D03*
X849896Y12114D03*
X849810Y-4100D03*
X853543Y-9901D03*
X856189Y12114D03*
Y-4100D03*
X853543Y17157D03*
X910432Y-3700D03*
X870275Y65699D03*
X853543Y54957D03*
X856189Y49914D03*
X876968Y54957D03*
X849896Y49914D03*
X873621Y34100D03*
X870275Y54957D03*
X873621Y49914D03*
X853543Y65699D03*
X876968D03*
X856189Y71500D03*
X853543Y92757D03*
X856189Y87714D03*
X876968Y92757D03*
X849810Y71500D03*
X849896Y87714D03*
X873621Y71900D03*
X870275Y92761D03*
X873621Y87714D03*
X883661Y54957D03*
X886707Y49914D03*
X910432Y34100D03*
X907086Y54957D03*
X910432Y49914D03*
X880314Y71900D03*
Y87714D03*
X893000Y71500D03*
X890354Y92757D03*
X893000Y87714D03*
X886621Y71500D03*
X883661Y92757D03*
X886707Y87714D03*
X910432Y71900D03*
X907086Y92757D03*
X910432Y87714D03*
X890354Y65699D03*
X883661D03*
X907086D03*
X880314Y34100D03*
Y49914D03*
X890354Y54957D03*
X893000Y49914D03*
X890354Y112327D03*
X893000Y106934D03*
X883661Y112327D03*
X886707Y107284D03*
X907086Y112327D03*
X910432Y107284D03*
X849896Y513114D03*
X870275Y518161D03*
X873621Y513114D03*
X853543Y518157D03*
X856189Y513114D03*
X876968Y518157D03*
X910432Y513114D03*
X880314D03*
X890354Y518157D03*
X893000Y513114D03*
X883661Y518157D03*
X907086D03*
X886500Y490800D03*
X882900Y498500D03*
X910432Y493744D03*
X907086Y498487D03*
X893000Y495694D03*
X889200Y495900D03*
X886707Y513114D03*
X849810Y534700D03*
X873621Y535100D03*
X856189Y550914D03*
X849896D03*
X873621D03*
X856189Y534700D03*
X853543Y528899D03*
X876968D03*
X853543Y555957D03*
X856189Y572500D03*
X853543Y566699D03*
X876968Y555957D03*
Y566699D03*
X870275Y555961D03*
X873621Y572900D03*
X870275Y566699D03*
X856189Y588714D03*
X849896D03*
X873621D03*
X907086Y528899D03*
X880314Y550914D03*
Y535100D03*
X893000Y534700D03*
X890354Y528899D03*
X886621Y534700D03*
X880314Y572900D03*
Y588714D03*
X893000D03*
X886707D03*
X910432D03*
X886707Y550914D03*
X883661Y566699D03*
Y555957D03*
X910432Y550914D03*
X893000D03*
X907086Y566699D03*
X910432Y572900D03*
X907086Y555957D03*
X890354Y566699D03*
X893000Y572500D03*
X890354Y555957D03*
X883661Y528899D03*
X870275D03*
X849810Y572500D03*
X910432Y535100D03*
X886621Y572500D03*
X853543Y593757D03*
X856189Y610300D03*
X853543Y604499D03*
X876968Y593757D03*
Y604499D03*
X849810Y610300D03*
X870275Y593761D03*
X873621Y610700D03*
X870275Y604499D03*
X880314Y610700D03*
X893000Y610300D03*
X890354Y593757D03*
Y604499D03*
X886621Y610300D03*
X883661Y593757D03*
X907086Y604499D03*
Y593757D03*
X910432Y610700D03*
X883661Y604499D03*
X929811Y-4100D03*
X927165Y-9901D03*
X923432Y-4100D03*
X920472Y-9901D03*
X929811Y33700D03*
X927165Y27899D03*
X923432Y33700D03*
X920472Y27899D03*
X927165Y17157D03*
X929811Y12114D03*
X920472Y17157D03*
X923518Y12114D03*
X913779Y27899D03*
X953936Y-3700D03*
X950590Y-9901D03*
X947243Y-3700D03*
X943897Y-9901D03*
X950590Y27899D03*
X943897D03*
X950590Y17157D03*
X953936Y12114D03*
X943897Y17157D03*
X947243Y12114D03*
X913779Y-9901D03*
X917125Y-3700D03*
Y12114D03*
X913779Y17157D03*
X927165Y54957D03*
X929811Y49914D03*
X920472Y54957D03*
X923518Y49914D03*
X917125Y71900D03*
X913779Y92757D03*
X917125Y87714D03*
X929811Y71500D03*
X927165Y92757D03*
X913779Y65699D03*
X927165D03*
X920472D03*
X913779Y54957D03*
X917125Y34100D03*
Y49914D03*
X929811Y87714D03*
X923432Y71500D03*
X920472Y92757D03*
X923518Y87714D03*
X950590Y65699D03*
X943897D03*
X953936Y34100D03*
X950590Y54957D03*
X953936Y49914D03*
X947243Y34100D03*
X943897Y54957D03*
X947243Y49914D03*
Y87714D03*
X953936Y71900D03*
X950590Y92757D03*
X953936Y87714D03*
X947243Y71900D03*
X943897Y92757D03*
X913779Y112327D03*
X917125Y107284D03*
X927165Y112327D03*
X929811Y106934D03*
X920472Y112327D03*
X923518Y107284D03*
X950590Y109700D03*
X953786Y107684D03*
X944497Y110927D03*
X947243Y105084D03*
X927165Y518157D03*
X929811Y513114D03*
X920472Y518157D03*
X923518Y513114D03*
X913779Y518157D03*
X917125Y513114D03*
X943897Y518157D03*
X947243Y513114D03*
X947443Y494944D03*
X944000Y493100D03*
X923600Y493744D03*
X929811Y493244D03*
X917192Y493919D03*
X920700Y498644D03*
X927165D03*
X913779Y498487D03*
X954000Y494700D03*
X950700Y493300D03*
X953936Y513114D03*
X950590Y518157D03*
X929811Y534700D03*
X927165Y528899D03*
X923432Y534700D03*
X920472Y528899D03*
X917125Y535100D03*
X913779Y528899D03*
X947243Y535100D03*
X953936Y588714D03*
X929811D03*
X923518D03*
X947243D03*
Y550914D03*
X923518D03*
X929811D03*
X917125D03*
X943897Y566699D03*
X947243Y572900D03*
X943897Y555957D03*
X920472Y566699D03*
X923432Y572500D03*
X920472Y555957D03*
X927165Y566699D03*
X929811Y572500D03*
X927165Y555957D03*
X913779D03*
X953936Y550914D03*
X950590Y555957D03*
X917125Y588714D03*
X950590Y528899D03*
X953936Y535100D03*
X943897Y528899D03*
X913779Y566699D03*
X917125Y572900D03*
X950590Y566699D03*
X917125Y610700D03*
X913779Y593757D03*
X929811Y610300D03*
X927165Y593757D03*
X950590Y604499D03*
X953936Y610700D03*
X950590Y593757D03*
X927165Y604499D03*
X923432Y610300D03*
X920472Y593757D03*
Y604499D03*
X947243Y610700D03*
X943897Y593757D03*
Y604499D03*
X913779D03*
X1054330Y-9901D03*
X1047637D03*
X1110520Y33700D03*
X1107874Y27899D03*
X1104141Y33700D03*
X1101181Y27899D03*
X1147331Y-4100D03*
X1144685Y-9901D03*
X1140952Y-4100D03*
X1137992Y-9901D03*
X1124606Y27899D03*
X1147331Y33700D03*
X1144685Y27899D03*
X1140952Y33700D03*
X1137992Y27899D03*
X1144685Y17157D03*
X1147331Y12114D03*
X1137992Y17157D03*
X1141038Y12114D03*
X1131299Y27899D03*
X1124606Y-9901D03*
X1127952Y-3700D03*
X1131299Y-9901D03*
X1107874D03*
X1110520Y-4100D03*
X1134645Y-3700D03*
X1127952Y12114D03*
X1124606Y17157D03*
X1131299D03*
X1110520Y12114D03*
X1107874Y17157D03*
X1134645Y12114D03*
X1101181Y17157D03*
X1104227Y12114D03*
X1101181Y-9901D03*
X1104141Y-4100D03*
X1107874Y65699D03*
X1101181D03*
X1107874Y54957D03*
X1110520Y49914D03*
X1101181Y54957D03*
X1104227Y49564D03*
X1110520Y71500D03*
X1107874Y92757D03*
X1110520Y87714D03*
X1104227D03*
X1127952Y34100D03*
X1124606Y54957D03*
X1127952Y49914D03*
X1144685Y54957D03*
X1147331Y49914D03*
X1137992Y54957D03*
X1141038Y49914D03*
X1131299Y65699D03*
X1124606D03*
X1144685D03*
X1137992D03*
X1131299Y54957D03*
X1134645Y34100D03*
Y49914D03*
Y71900D03*
X1131299Y92757D03*
X1134645Y87714D03*
X1127952Y71900D03*
X1124606Y92757D03*
X1127952Y87714D03*
X1147331Y71500D03*
X1144685Y92757D03*
X1147331Y87714D03*
X1140952Y71500D03*
X1137992Y92757D03*
X1141038Y87714D03*
X1101181Y92757D03*
X1104141Y71500D03*
X1144535Y112357D03*
X1147331Y106964D03*
X1138242Y112357D03*
X1141038Y106964D03*
X1110520Y513114D03*
X1104227D03*
X1147331Y490894D03*
X1141038Y491144D03*
X1127952Y513114D03*
X1144685Y518157D03*
X1147331Y513114D03*
X1137992Y518157D03*
X1141038Y513114D03*
X1124606Y518157D03*
X1101181D03*
X1131299D03*
X1107874D03*
X1134645Y513114D03*
X1137992Y498487D03*
X1144385D03*
X1107874Y528899D03*
X1101181D03*
X1110520Y550914D03*
X1104227D03*
Y588714D03*
X1107874Y555957D03*
X1110520Y572500D03*
X1107874Y566699D03*
X1101181Y555957D03*
X1104141Y572500D03*
X1101181Y566699D03*
X1134645Y550914D03*
X1127952D03*
X1147331D03*
X1141038D03*
X1147331Y534700D03*
X1144685Y528899D03*
X1140952Y534700D03*
X1137992Y528899D03*
X1134645Y588714D03*
X1127952D03*
X1147331D03*
X1141038D03*
X1131299Y555957D03*
X1134645Y572900D03*
X1131299Y566699D03*
X1124606Y555957D03*
X1127952Y572900D03*
X1124606Y566699D03*
X1144685D03*
X1110520Y588714D03*
X1127952Y535100D03*
X1104141Y534700D03*
X1131299Y528899D03*
X1110520Y534700D03*
X1137992Y555957D03*
X1147331Y572500D03*
X1144685Y555957D03*
X1124606Y528899D03*
X1137992Y566699D03*
X1134645Y535100D03*
X1140952Y572500D03*
X1101181Y593757D03*
X1104141Y610300D03*
X1101181Y604499D03*
X1134645Y610700D03*
X1131299Y593757D03*
Y604499D03*
X1124606Y593757D03*
X1127952Y610700D03*
X1124606Y604499D03*
X1147700Y611200D03*
X1144685Y593757D03*
Y604499D03*
X1137992Y593757D03*
X1141332Y611668D03*
X1137992Y604499D03*
X1107874D03*
Y593757D03*
X1110520Y610300D03*
X1171456Y-3700D03*
X1168110Y-9901D03*
X1164763Y-3700D03*
X1161417Y-9901D03*
X1168110Y27899D03*
X1161417D03*
X1177763Y33700D03*
X1174803Y27899D03*
X1168110Y17157D03*
X1171456Y12114D03*
X1161417Y17157D03*
X1164763Y12114D03*
X1204921Y27899D03*
X1198228D03*
X1218307D03*
X1214574Y33700D03*
X1211614Y27899D03*
X1184142Y33700D03*
X1181496Y27899D03*
X1184142Y12114D03*
X1204921Y17157D03*
X1198228D03*
X1201574Y12114D03*
X1184142Y-4100D03*
X1204921Y-9901D03*
X1201574Y-3700D03*
X1198228Y-9901D03*
X1208267Y-3700D03*
X1218307Y-9901D03*
X1214574Y-4100D03*
X1211614Y-9901D03*
X1208267Y12114D03*
X1218307Y17157D03*
X1211614D03*
X1214660Y12114D03*
X1174803Y-9901D03*
X1177763Y-4100D03*
X1181496Y-9901D03*
X1177849Y12114D03*
X1174803Y17157D03*
X1181496D03*
X1171456Y34100D03*
X1168110Y54957D03*
X1171456Y49914D03*
X1161417Y54957D03*
X1164763Y34100D03*
Y49914D03*
X1174803Y54957D03*
X1177849Y49914D03*
X1168110Y65699D03*
X1161417D03*
X1174803D03*
X1171456Y71900D03*
X1168110Y92757D03*
X1171456Y87714D03*
X1164763Y71900D03*
X1161417Y92757D03*
X1164763Y87714D03*
X1177763Y71500D03*
X1174803Y92757D03*
X1177849Y87714D03*
X1204921Y54957D03*
X1208267Y34100D03*
Y49914D03*
X1198228Y54957D03*
X1201574Y34100D03*
Y49914D03*
X1218307Y54957D03*
X1211614D03*
X1214660Y49914D03*
X1181496Y92757D03*
X1184142Y71500D03*
Y87714D03*
X1208267Y71900D03*
X1204921Y92757D03*
X1208267Y87714D03*
X1201574Y71900D03*
X1198228Y92757D03*
X1201574Y87714D03*
X1218307Y92757D03*
X1214574Y71500D03*
X1211614Y92757D03*
X1214874Y87374D03*
X1181496Y65699D03*
X1204921D03*
X1198228D03*
X1218307D03*
X1211614D03*
X1181496Y54957D03*
X1184142Y49914D03*
X1167925Y112357D03*
X1170721Y106964D03*
X1161632Y112357D03*
X1164428Y106964D03*
X1174742Y112357D03*
X1177849Y107314D03*
X1181496Y112357D03*
X1184142Y106964D03*
X1204921Y112357D03*
X1208267Y107314D03*
X1198228Y112357D03*
X1201574Y107314D03*
X1161417Y518157D03*
X1174803D03*
X1177849Y513114D03*
X1170656Y493844D03*
X1164363Y493744D03*
X1177799Y493544D03*
X1168110Y518157D03*
X1171456Y513114D03*
X1184142Y493394D03*
X1200974Y493344D03*
X1208267Y496144D03*
X1181496Y518157D03*
X1184142Y513114D03*
X1204921Y518157D03*
X1208267Y513114D03*
X1198228Y518157D03*
X1201574Y513114D03*
X1211614Y518157D03*
X1214874Y512774D03*
X1204400Y498487D03*
X1198100Y498400D03*
X1180400Y498387D03*
X1174203D03*
X1161417Y498487D03*
X1167510D03*
X1218307Y518157D03*
X1164763Y513114D03*
Y535100D03*
X1177763Y534700D03*
X1174803Y528899D03*
X1171456Y550914D03*
X1164763D03*
X1177849D03*
X1171456Y535100D03*
X1168110Y528899D03*
X1161417Y566699D03*
X1174803D03*
X1171456Y588714D03*
X1164763D03*
X1177849D03*
X1184142Y550914D03*
X1208267D03*
X1201574D03*
X1214874Y550574D03*
X1184142Y534700D03*
X1181496Y528899D03*
X1208267Y535100D03*
X1204921Y528899D03*
X1201574Y535100D03*
X1198228Y528899D03*
X1218307D03*
X1214574Y534700D03*
X1211614Y528899D03*
X1201574Y588714D03*
X1214660D03*
X1181496Y566699D03*
X1204921D03*
X1198228D03*
X1218307Y555957D03*
Y566699D03*
X1211614Y555957D03*
X1214574Y572500D03*
X1211614Y566699D03*
X1184142Y588714D03*
X1208267D03*
X1204921Y555957D03*
X1198228D03*
X1184142Y572500D03*
X1201574Y572900D03*
X1208267D03*
X1181496Y555957D03*
X1174803D03*
X1161417D03*
X1171456Y572900D03*
X1168110Y555957D03*
Y566699D03*
X1177763Y572500D03*
X1164763Y572900D03*
X1161417Y528899D03*
X1168110Y593757D03*
X1171456Y610700D03*
X1168110Y604499D03*
X1161417Y593757D03*
Y604499D03*
X1174803Y593757D03*
X1177763Y610300D03*
X1174803Y604499D03*
X1204921D03*
X1198228Y593757D03*
X1201574Y610700D03*
X1198228Y604499D03*
X1218307Y593757D03*
Y604499D03*
X1211614Y593757D03*
X1214574Y610300D03*
X1211614Y604499D03*
X1181496Y593757D03*
X1184142Y610300D03*
X1181496Y604499D03*
X1208267Y610700D03*
X1204921Y593757D03*
X1164763Y610700D03*
X1241732Y27899D03*
X1220953Y33700D03*
X1235039Y27899D03*
X1220953Y-4100D03*
X1245078Y-3700D03*
X1241732Y-9901D03*
X1238385Y-3700D03*
X1235039Y-9901D03*
X1220953Y12114D03*
X1241732Y17157D03*
X1245078Y12114D03*
X1235039Y17157D03*
X1238385Y12114D03*
X1241732Y65699D03*
Y54957D03*
X1245078Y34100D03*
Y49914D03*
X1238385Y34100D03*
Y49914D03*
X1241732Y92757D03*
X1245078Y71900D03*
Y87714D03*
X1238385Y71900D03*
Y87714D03*
X1220953Y49914D03*
X1235039Y54957D03*
X1220953Y71500D03*
Y87714D03*
X1235039Y92757D03*
Y65699D03*
X1241732Y518157D03*
X1245078Y513114D03*
X1238385D03*
X1220953D03*
X1235039Y518157D03*
X1245078Y535100D03*
X1241732Y528899D03*
X1238385Y535100D03*
X1245078Y550914D03*
X1238385D03*
X1241732Y555957D03*
X1245078Y572900D03*
X1241732Y566699D03*
X1238385Y572900D03*
X1245078Y588714D03*
X1238385D03*
X1220953Y550914D03*
X1235039Y528899D03*
X1220953Y588714D03*
Y572500D03*
X1235039Y555957D03*
Y566699D03*
X1220953Y534700D03*
X1241732Y593757D03*
X1245078Y610700D03*
X1241732Y604499D03*
X1238385Y610700D03*
X1220953Y610300D03*
X1235039Y593757D03*
Y604499D03*
X1391900Y232118D03*
X1386400Y237900D03*
X1403037Y302046D03*
X1374300Y377885D03*
Y381485D03*
X1375961Y569473D03*
X1376000Y565700D03*
X1400216Y560128D03*
X1375961Y600673D03*
X1375861Y597073D03*
X1375961Y593473D03*
X1413720Y301983D03*
X1418341Y494423D03*
Y477323D03*
X1442141Y477623D03*
X1442041Y489223D03*
X1523450Y612900D03*
X1519850Y613000D03*
X1487912Y611632D03*
X1484312Y611732D03*
X1590154Y354762D03*
X1594280Y472370D03*
X1681586Y141438D03*
X1693586Y142438D03*
X1688207Y168972D03*
X1689785Y161180D03*
X1788290Y612006D03*
X1842250Y90750D03*
X1885000Y227500D03*
X1934256Y99459D03*
X1909421Y208805D03*
G54D65*
X1643803Y570630D03*
X1646756Y565118D03*
Y580079D03*
Y610000D03*
X1643803Y600551D03*
Y615512D03*
X1691047Y570630D03*
X1694000Y565118D03*
Y580079D03*
X1691047Y600551D03*
Y615512D03*
X1694000Y610000D03*
G54D57*
X50500Y205696D03*
X108174Y164127D03*
X85609Y385234D03*
X123624Y164600D03*
X195300Y229250D03*
X230800Y265200D03*
X224390Y258920D03*
X219500Y254500D03*
X224000Y330900D03*
X229100Y325900D03*
X219000Y335900D03*
X214000Y340900D03*
X234501Y270392D03*
X234000Y320900D03*
X378294Y292904D03*
X628589Y463649D03*
X629359Y469583D03*
X605176Y487581D03*
X641107Y471989D03*
X710800Y7100D03*
X705250Y8600D03*
X814849Y205001D03*
X792514Y201290D03*
X803134Y202969D03*
X808165Y203529D03*
X818960Y202230D03*
X845050Y229400D03*
X844400Y280500D03*
X844350Y344000D03*
X874586Y259278D03*
X869586Y254278D03*
X884586Y269278D03*
X879586Y264278D03*
X889586Y274278D03*
X862008Y341100D03*
X872008Y331100D03*
X867008Y336100D03*
X877008Y326100D03*
X1017083Y309910D03*
X1028136Y309815D03*
X1301240Y476228D03*
X1431664Y190213D03*
X1463369Y561763D03*
X1490821Y73750D03*
X1567425Y144373D03*
X1573121Y120649D03*
X1570020Y295340D03*
X1569926Y308064D03*
X1576074Y359600D03*
X1608099Y197125D03*
X1608280Y249234D03*
X1591865Y237407D03*
X1598028Y256422D03*
X1600552Y261281D03*
X1640001Y370790D03*
X1590530Y610620D03*
X1644856Y604930D03*
X1640921Y605334D03*
X1680139Y99073D03*
X1663566Y213009D03*
X1695734Y164676D03*
X1687741Y466988D03*
X1759093Y9310D03*
X1761872Y-7220D03*
X1734875Y9238D03*
X1723189Y176012D03*
X1758000Y250000D03*
X1758324Y232657D03*
X1789356Y38286D03*
X1777000Y115750D03*
X1778000Y120000D03*
X1780720Y153850D03*
X1784750Y124000D03*
X1828390Y165600D03*
X1832000Y165800D03*
X1836396Y481349D03*
X1847654Y164624D03*
X1852654D03*
X1847000Y198600D03*
X1954271Y80449D03*
X1908400Y101010D03*
X1949389Y152083D03*
X1944550Y176450D03*
X1950981Y168064D03*
X1966700Y152400D03*
X1963092Y167936D03*
X251213Y646784D03*
Y652784D03*
X261125Y646784D03*
Y652784D03*
X389473Y646508D03*
Y652508D03*
X379561Y646508D03*
Y652508D03*
X448593Y652514D03*
Y646514D03*
X438681D03*
Y652514D03*
X567029Y652238D03*
Y646238D03*
X576941D03*
Y652238D03*
X951795Y652234D03*
Y646234D03*
X941883D03*
Y652234D03*
X1196198Y652206D03*
Y646206D03*
X1206110D03*
Y652206D03*
X1265293Y652264D03*
Y646264D03*
X1255381D03*
Y652264D03*
X1509696Y652236D03*
Y646236D03*
X1519608D03*
Y652236D03*
G54D74*
X1912406Y518328D03*
X1904532D03*
G54D53*
X10512Y467244D03*
X20512D03*
X50512D03*
X1884100Y493000D03*
X1894100D03*
X1891086Y612105D03*
Y602105D03*
Y592105D03*
X1904100Y493000D03*
G54D68*
X1779504Y-15000D03*
G54D61*
X1392264Y23976D03*
X1513918D03*
G54D48*
X-10236Y116969D03*
X-4725D03*
X23228Y124843D03*
X17716D03*
X-10236Y132717D03*
X-4725D03*
X6299D03*
X11811D03*
X17716Y140591D03*
X23228D03*
X-10236Y373110D03*
X-4725D03*
X23228Y380984D03*
X17716D03*
X-10236Y388858D03*
X-4725D03*
X6299D03*
X11811D03*
X17716Y396732D03*
X23228D03*
G54D62*
X1527844Y80791D03*
X1724606Y235430D03*
G54D71*
X1892720Y525415D03*
X1894689Y518328D03*
X1900595Y525415D03*
X1908469D03*
X1916343D03*
X1924217D03*
G54D63*
X1627642Y-14488D03*
X1647327Y-315D03*
X1667012Y-14488D03*
X1969291Y486064D03*
Y497874D03*
G54D45*
X-19210Y162529D03*
X-17014Y455604D03*
X-14800Y526100D03*
X-17200Y510800D03*
X-17302Y506798D03*
X-19802Y476738D03*
X-19783Y481286D03*
X-18160Y522609D03*
X-16186Y519304D03*
X-14971Y540000D03*
X-17500Y574000D03*
X19964Y18793D03*
X16550Y18300D03*
X25827Y-16958D03*
X602Y30502D03*
X2871Y22791D03*
X-10850Y30800D03*
X8660Y27274D03*
X43960Y20572D03*
X2934Y26933D03*
X-1750Y43320D03*
X-1920Y47290D03*
X-1470Y63910D03*
X-3560Y34620D03*
X8988Y58267D03*
X39109Y154901D03*
X37037Y138425D03*
X5120Y276058D03*
X2269Y273532D03*
X1500Y295000D03*
X47100Y327000D03*
X2450Y460000D03*
X37550Y425400D03*
X40965Y429434D03*
X10365Y461602D03*
X2350Y469650D03*
X-6712Y515731D03*
X-6676Y501800D03*
X-9900Y486400D03*
X-13500D03*
X-6650Y487800D03*
X-2430Y524340D03*
X-4350Y482100D03*
X-900Y482300D03*
X22491Y500618D03*
X-9600Y526100D03*
X6748Y517021D03*
X3354Y517143D03*
X-5680Y524570D03*
X10932Y523601D03*
X14700Y517000D03*
X-7360Y512000D03*
X-2083Y513704D03*
X-6200Y505400D03*
X-10947Y544117D03*
X-4100Y554400D03*
X-9287Y531604D03*
X-8318Y542216D03*
X-3100Y533991D03*
X-8200Y578600D03*
X-2500Y569500D03*
X-12600Y578900D03*
X-4300Y558400D03*
X-9283Y571324D03*
X-6566Y568363D03*
X-9291Y535201D03*
X-4500Y594000D03*
X71172Y-18486D03*
X52389Y-14258D03*
X52744Y-4368D03*
X74386Y-18439D03*
X104500Y-1850D03*
X60035Y7508D03*
X106000Y17260D03*
X87091Y-16391D03*
X82300Y-16600D03*
X93500Y-18000D03*
X54307Y-8051D03*
X51090Y8080D03*
X53382Y-1173D03*
X82046Y90043D03*
X86600Y94000D03*
X76106Y89337D03*
X105898Y55194D03*
X79670Y132300D03*
X91913Y121318D03*
X77790Y121030D03*
X70980Y97166D03*
X104424Y110833D03*
X98420Y112198D03*
X87200Y152374D03*
X75660Y152380D03*
X78950Y152810D03*
X91306Y157194D03*
X102507Y211047D03*
X107700Y211040D03*
X76143Y183019D03*
X104820Y202100D03*
X90831Y184982D03*
X61800Y191600D03*
X99250Y160370D03*
X61356Y181000D03*
X61256Y186000D03*
X86731Y189148D03*
X99500Y223800D03*
X84000Y272500D03*
X79300Y272300D03*
X99758Y240300D03*
X97200Y265000D03*
X91600Y278700D03*
X69125Y310625D03*
X94360Y335210D03*
X53400Y298100D03*
X66300Y285850D03*
X88600Y302997D03*
X79410Y331636D03*
X84000Y324542D03*
X53100Y327000D03*
X82500Y341400D03*
X79400Y325400D03*
X49200Y340650D03*
X87400Y337200D03*
X53100Y315000D03*
X66900Y322000D03*
X58400Y314600D03*
X53000Y323500D03*
X52804Y333247D03*
X61300Y328600D03*
X70700Y330349D03*
X93500Y289000D03*
X93400Y296000D03*
X103500Y304700D03*
Y308500D03*
X102322Y295478D03*
X104600Y316602D03*
X103200Y330190D03*
X88840Y324740D03*
X53250Y302800D03*
X48550Y301650D03*
X64700Y310525D03*
X84300Y305700D03*
Y310700D03*
X72904Y284898D03*
X84300Y289000D03*
X82050Y283951D03*
X77103Y283900D03*
X84866Y294213D03*
X84300Y299000D03*
X93500Y285000D03*
X93712Y380507D03*
X87900Y347500D03*
X88000Y343900D03*
X61041Y351737D03*
X60400Y355750D03*
X90518Y388828D03*
X54900Y389400D03*
X74800Y383114D03*
X57395Y366795D03*
X55500Y371700D03*
X61914Y368731D03*
X79100Y347000D03*
X57800Y376100D03*
X60565Y380131D03*
X65000Y383000D03*
X74800Y379700D03*
X80200D03*
X62600Y375100D03*
X97472Y380934D03*
X47800Y487600D03*
X86100Y505200D03*
X59731Y480066D03*
X66016Y468350D03*
X106392Y527413D03*
X71050Y478670D03*
X105392Y566000D03*
X102236Y614167D03*
X106192Y604600D03*
X114680Y17320D03*
X116300Y-9460D03*
X116692Y-1800D03*
X114050Y21320D03*
X120273Y9157D03*
X119892Y84700D03*
X116070Y35780D03*
X115980Y73680D03*
X116200Y70387D03*
X120273Y46957D03*
X122542Y214019D03*
X124340Y197750D03*
X117600Y193805D03*
X162788Y200650D03*
X162800Y195600D03*
X150000Y199850D03*
Y194850D03*
X122203Y246675D03*
X122400Y278671D03*
X122493Y310633D03*
X122473Y374716D03*
X153392Y404000D03*
X122361Y342649D03*
X118220Y360500D03*
X109500Y370000D03*
X157862Y416012D03*
X110452Y407092D03*
X148409Y422239D03*
X151909Y413267D03*
X153392Y407500D03*
X167680Y408440D03*
X167640Y404842D03*
X150650Y409860D03*
X119892Y510100D03*
X116927Y517900D03*
X119892Y536983D03*
Y547900D03*
X115883Y548024D03*
X113692Y566000D03*
X119892Y574700D03*
Y585700D03*
X114509Y575658D03*
X114150Y585850D03*
X116927Y555700D03*
X119892Y612583D03*
X114792Y604600D03*
X116927Y593500D03*
X206600Y372400D03*
X267859Y209109D03*
X271239Y203260D03*
X277999Y218860D03*
X281379Y209109D03*
X288139Y201309D03*
Y209109D03*
X277999Y199360D03*
X274619Y201309D03*
Y209109D03*
Y205210D03*
X271239Y207159D03*
X281379Y216909D03*
X284759Y218860D03*
Y203260D03*
Y211060D03*
X281379Y205210D03*
X291519Y203260D03*
Y211060D03*
X288139Y213009D03*
Y205210D03*
X264092Y242260D03*
X271239D03*
X267859Y248109D03*
X264179Y261760D03*
X271239D03*
Y253960D03*
X288139Y228610D03*
X277999Y226660D03*
X288139Y220809D03*
X281379Y236409D03*
X284759Y250060D03*
X288139Y240309D03*
X281379Y244209D03*
X277999Y257860D03*
X288139Y267609D03*
Y259809D03*
X277999Y265660D03*
X274619Y271509D03*
X291519Y273460D03*
X277999D03*
X264179Y246160D03*
X271239D03*
Y250060D03*
X264179Y257860D03*
X271239D03*
X267859Y255909D03*
X271239Y277360D03*
X267392Y276000D03*
X267359Y279310D03*
X267859Y271509D03*
X264179Y273460D03*
X284759Y230559D03*
X277999Y222760D03*
X281379Y224709D03*
X284759Y222760D03*
X277999Y238360D03*
X288139Y248109D03*
X277999Y242260D03*
X284759Y238360D03*
X281379Y248109D03*
X288139Y244209D03*
X277999Y246160D03*
X284759Y242260D03*
X281379Y228610D03*
X288139Y224709D03*
X281379Y267609D03*
Y255909D03*
X284759Y269560D03*
X277999Y261760D03*
X284759Y257860D03*
Y261760D03*
X281379Y263709D03*
X288139Y279310D03*
X274619D03*
X281379D03*
X288139Y263709D03*
X239778Y274478D03*
X288139Y322209D03*
X281379D03*
X284759Y335860D03*
X277999D03*
X288139Y330009D03*
X281379Y341709D03*
Y330009D03*
X271239Y339760D03*
X291519Y320260D03*
X284759D03*
X291519Y324160D03*
X277999D03*
X264179Y331960D03*
X271239D03*
Y320260D03*
Y324160D03*
X270939Y316160D03*
X267359Y318309D03*
X267859Y326110D03*
X267392Y322000D03*
X270892Y304660D03*
Y311960D03*
Y300760D03*
Y308560D03*
Y292959D03*
Y289060D03*
X271239Y281260D03*
X270892Y285500D03*
Y296860D03*
X267359Y283209D03*
X281379Y302709D03*
X288139D03*
X291519Y304660D03*
X281379Y306609D03*
Y310509D03*
X288139Y306609D03*
Y310509D03*
X284759Y304660D03*
X281379Y287109D03*
X288139Y291009D03*
X284759Y289060D03*
Y281260D03*
X291519Y289060D03*
Y281260D03*
Y296860D03*
X288139Y298809D03*
X274619Y306609D03*
Y310509D03*
X277999Y304660D03*
X274619Y302709D03*
Y298809D03*
Y294909D03*
X277999Y289060D03*
Y281260D03*
X274619Y283209D03*
Y287109D03*
Y291009D03*
X277999Y296860D03*
X288139Y283209D03*
Y287109D03*
X281379Y298809D03*
Y294909D03*
X288139D03*
X284759Y296860D03*
X281379Y291009D03*
Y283209D03*
X291519Y312460D03*
X284759D03*
X277999D03*
X274619Y314409D03*
X281379D03*
X288139D03*
X274619Y318309D03*
X264179Y335860D03*
X288139Y337809D03*
X281379Y333909D03*
X277999Y331960D03*
X284759Y339760D03*
Y328060D03*
X277999Y339760D03*
X288139Y333909D03*
X267859Y337809D03*
X271239Y335860D03*
Y394359D03*
X267859Y392410D03*
X271239Y398260D03*
X284759Y355360D03*
X274619Y400209D03*
X281379D03*
X277999Y398260D03*
X274619Y396309D03*
X288139Y388509D03*
X291519Y394359D03*
X281379Y388509D03*
X284759Y394359D03*
X277999Y355360D03*
X284759Y347560D03*
X281379Y361209D03*
X284759Y374860D03*
X271239Y347560D03*
X264179D03*
X277999Y374860D03*
X288139Y369010D03*
X281379Y380709D03*
Y369010D03*
X267859Y345609D03*
X288139Y392410D03*
X281379Y353409D03*
X288139Y384609D03*
Y357309D03*
Y396309D03*
X277999Y351460D03*
X281379Y349509D03*
X288139Y353409D03*
X291519Y386560D03*
X281379Y392410D03*
X284759Y386560D03*
X277999Y359260D03*
X288139Y349509D03*
X284759Y359260D03*
X281379Y372909D03*
X288139Y376809D03*
X277999Y370959D03*
X271239Y343660D03*
Y351460D03*
X264179D03*
X284759Y378760D03*
Y367060D03*
X277999Y378760D03*
X288139Y372909D03*
X308418Y216909D03*
X294899D03*
X301659D03*
X294899Y205210D03*
Y197409D03*
X338838Y214960D03*
X298279D03*
X305039D03*
X301659Y213009D03*
X294899Y209109D03*
X338838Y218860D03*
X298279Y222760D03*
X305039D03*
X328698Y236409D03*
Y244209D03*
X321938Y240309D03*
X294899Y232509D03*
X301659Y244209D03*
Y232509D03*
X318558Y222760D03*
X311798Y234460D03*
X305039Y238360D03*
X294899Y240309D03*
X311798Y226660D03*
X318558Y230559D03*
X332078Y222760D03*
X328698Y224709D03*
Y228610D03*
X332078Y230560D03*
X311798Y242260D03*
X315178Y248109D03*
X308418D03*
X305039Y257860D03*
X328698Y255909D03*
X325318Y261760D03*
X294899Y252009D03*
X301659Y263709D03*
Y252009D03*
X294899Y259809D03*
X332078Y261760D03*
X315178Y271509D03*
X311798Y265660D03*
X321938Y271509D03*
X308418D03*
X318558Y265660D03*
X294899Y271509D03*
Y267609D03*
X332078Y273460D03*
X298279D03*
X328698Y275409D03*
X332078Y277360D03*
X325318D03*
X328698Y279310D03*
X321938D03*
X301659Y271509D03*
X328698D03*
X298279Y269560D03*
X335458Y220809D03*
Y228610D03*
X338838Y230560D03*
Y273460D03*
Y269560D03*
X335458Y275409D03*
X338838Y277360D03*
X335458Y279310D03*
Y271509D03*
X332078Y226660D03*
X315178Y244209D03*
X311798Y246160D03*
X321938Y252009D03*
X335458Y232510D03*
Y240309D03*
X338838Y261760D03*
X335458Y255909D03*
X352357Y253960D03*
X345598D03*
X355737Y255909D03*
X348978D03*
X345598Y261760D03*
X348978Y259809D03*
X345598Y257860D03*
X352357D03*
X342218Y252009D03*
X338838Y250060D03*
X308418Y220809D03*
X294899D03*
X301659Y224709D03*
X328698Y248109D03*
Y240309D03*
X301659Y220809D03*
X325318Y238360D03*
Y246160D03*
X321938Y244209D03*
X332078Y238360D03*
Y246160D03*
X298279Y230559D03*
X305039Y242260D03*
X294899Y236409D03*
X311798Y230559D03*
X318558Y234460D03*
X321938Y224709D03*
X315178Y236409D03*
Y224709D03*
X321938Y228610D03*
X298279Y250060D03*
Y242260D03*
X305039Y234460D03*
X321938Y232509D03*
X298279Y238360D03*
X315178Y228610D03*
X301659Y236409D03*
X318558Y250060D03*
X298279Y261760D03*
X328698Y263709D03*
X325318Y257860D03*
X305039Y261760D03*
X294899Y255909D03*
X305039Y253960D03*
X332078D03*
X315178Y263709D03*
X332078Y265660D03*
X315178Y275409D03*
X301659Y255909D03*
X332078Y257860D03*
X315178Y267609D03*
X298279Y257860D03*
X311798Y273460D03*
X321938Y267609D03*
X308418D03*
X318558Y273460D03*
X301659Y279310D03*
X308418D03*
X294899D03*
X338838Y222760D03*
X335458Y244209D03*
X338838Y257860D03*
X335458Y263709D03*
X348978Y267609D03*
X345598Y277360D03*
X348978Y279310D03*
Y275409D03*
Y271509D03*
X352357Y265660D03*
X355737Y263709D03*
X298279Y320260D03*
X294899Y330009D03*
X352357Y339760D03*
X355737Y341709D03*
X298279Y335860D03*
X321938Y326110D03*
X311798Y331960D03*
X325318D03*
X315178Y326110D03*
X318558Y331960D03*
X335458Y341709D03*
X301659D03*
X294899D03*
X305039Y335860D03*
X338838D03*
X328698Y341709D03*
X342218D03*
X332078Y335860D03*
X298279Y324160D03*
X294899Y326109D03*
X321938Y341709D03*
X335458Y322209D03*
X308418Y306609D03*
X301659Y310509D03*
Y306609D03*
X311798Y304660D03*
X305039D03*
X321938Y306609D03*
X325318Y304660D03*
Y308560D03*
X298279Y304660D03*
X294899Y302709D03*
X308418D03*
X301659D03*
X315178D03*
X321938D03*
X294899Y310509D03*
Y306609D03*
X318558Y304660D03*
Y308560D03*
X321938Y291009D03*
X318558Y296860D03*
X315178Y294909D03*
X321938D03*
X301659D03*
X325318Y285160D03*
Y289060D03*
Y296860D03*
X298279D03*
Y289060D03*
Y281260D03*
X308418Y298809D03*
X301659D03*
X308418Y283209D03*
X305039Y281260D03*
Y289060D03*
X308418Y291009D03*
Y287109D03*
X311798Y281260D03*
Y289060D03*
X308418Y294909D03*
X311798Y296860D03*
X305039D03*
X315178Y287109D03*
X318558Y285160D03*
X321938Y287109D03*
X301659Y283209D03*
Y287109D03*
Y291009D03*
X294899Y298809D03*
Y294909D03*
Y291009D03*
Y283209D03*
Y287109D03*
X315178Y298809D03*
X321938D03*
X318558Y289060D03*
X315178Y291009D03*
X332078Y308560D03*
Y304660D03*
X328698Y302709D03*
Y306609D03*
Y287109D03*
Y291009D03*
Y294909D03*
Y298809D03*
X332078Y296860D03*
Y285160D03*
Y289060D03*
X315178Y306609D03*
X308418Y310509D03*
X318558Y324160D03*
X311798Y312460D03*
X305039D03*
X298279D03*
X294899Y314409D03*
X308418D03*
X301659D03*
X328698D03*
X321938D03*
X332078Y328060D03*
X328698Y322209D03*
Y318309D03*
X332078Y324160D03*
Y320260D03*
Y316360D03*
X325318Y320260D03*
X305039D03*
X321938Y318309D03*
X315178D03*
X318558Y316360D03*
X301659Y322209D03*
X325318Y316360D03*
X305039Y324160D03*
X311798Y320260D03*
X308418Y322209D03*
X301659Y326110D03*
X335458Y298809D03*
X348978Y287109D03*
X345598Y285160D03*
Y281260D03*
X348978Y283209D03*
Y298809D03*
Y291009D03*
X345598Y289060D03*
Y292959D03*
Y296860D03*
X348978Y294909D03*
X345598Y300760D03*
X348978Y302709D03*
Y306609D03*
X345598Y304660D03*
Y308560D03*
X348978Y310509D03*
X342218Y302709D03*
Y306609D03*
Y291009D03*
Y287109D03*
Y294909D03*
Y298809D03*
X338838Y308560D03*
X335458Y302709D03*
X338838Y304660D03*
X335458Y306609D03*
Y287109D03*
X338838Y289060D03*
Y285160D03*
X335458Y291009D03*
X338838Y296860D03*
X335458Y294909D03*
X348978Y314409D03*
X345598Y312460D03*
X348978Y322209D03*
X355737Y333909D03*
X345598Y316360D03*
X348978Y318309D03*
Y330009D03*
X352357Y331960D03*
X348978Y326110D03*
X335458Y314409D03*
Y326110D03*
Y318309D03*
X338838Y320260D03*
Y324160D03*
Y328060D03*
X335458Y337809D03*
X348978Y341709D03*
Y337809D03*
X305039Y339760D03*
X321938Y333909D03*
X311798Y328060D03*
X325318D03*
X315178Y333909D03*
X335458D03*
X298279Y339760D03*
X318558Y335860D03*
Y328060D03*
X294899Y337809D03*
X301659Y333909D03*
X328698Y337809D03*
X342218D03*
X332078Y370959D03*
X328698Y369010D03*
X294899Y400209D03*
X315178Y384609D03*
Y380709D03*
X332078Y374860D03*
X328698Y372909D03*
X355737Y345609D03*
X335458Y369010D03*
X338838Y363160D03*
X352357Y343660D03*
X335458Y376809D03*
X301659Y361209D03*
X332078Y351460D03*
X321938Y357309D03*
X335458D03*
X325318Y351460D03*
X301659Y380709D03*
X328698Y361209D03*
X305039Y374860D03*
X294899Y380709D03*
X308418D03*
X298279Y374860D03*
X311798Y363160D03*
X318558Y374860D03*
Y363160D03*
X294899Y361209D03*
X305039Y355360D03*
X298279Y367060D03*
X342218Y369010D03*
Y357309D03*
X345598Y351460D03*
X294899Y388509D03*
X338838Y374860D03*
X315178Y369010D03*
X298279Y355360D03*
Y347560D03*
X321938Y369010D03*
X308418Y349509D03*
X332078Y367060D03*
X321938Y345609D03*
X342218Y349509D03*
X345598Y347560D03*
X335458Y365109D03*
X352357Y347560D03*
X315178Y349509D03*
Y353409D03*
X311798Y355360D03*
Y347560D03*
Y351460D03*
X301659Y376809D03*
X342218Y365109D03*
Y353409D03*
X338838Y367060D03*
Y382660D03*
X332078Y359260D03*
X321938Y353409D03*
X335458D03*
X325318Y359260D03*
X328698Y357309D03*
Y349509D03*
X301659Y372909D03*
Y384609D03*
X328698Y353409D03*
X305039Y382660D03*
X294899Y376809D03*
X308418D03*
X298279Y382660D03*
X315178Y361209D03*
X321938Y372909D03*
X311798Y367060D03*
X294899Y365109D03*
X301659Y353409D03*
Y365109D03*
X342218Y361209D03*
X294899Y392410D03*
X338838Y378760D03*
Y370959D03*
X342218Y372909D03*
X305039Y343660D03*
X298279Y359260D03*
X321938Y365109D03*
X305039Y363160D03*
X335458Y345609D03*
X311798Y370959D03*
X294899Y357309D03*
X318558Y367060D03*
X305039Y359260D03*
X301659Y345609D03*
X294899D03*
X338838Y343660D03*
X332078D03*
X315178Y372909D03*
X348978Y345609D03*
X415634Y216196D03*
Y243496D03*
Y231797D03*
X359117Y253960D03*
X372637D03*
X357057Y277360D03*
X368127Y264300D03*
X364747Y266300D03*
X362497Y259809D03*
X365877Y257860D03*
X369257Y255909D03*
X374887Y260300D03*
X359117Y261760D03*
X371507Y262300D03*
X415634Y239596D03*
Y220096D03*
Y227896D03*
X357057Y281260D03*
Y296860D03*
Y285160D03*
Y292959D03*
Y300760D03*
Y308560D03*
Y304660D03*
Y289060D03*
Y312460D03*
X364747Y331509D03*
X361367Y329560D03*
X357987Y327609D03*
X371507Y335409D03*
X362497Y337809D03*
X369257Y341709D03*
X368127Y333460D03*
X365877Y339760D03*
X374887Y337360D03*
X381647Y341260D03*
X378267Y339309D03*
X359117Y335860D03*
X357057Y320260D03*
Y324160D03*
Y316360D03*
X362497Y345609D03*
X359117Y343660D03*
Y347560D03*
X372637Y343660D03*
X365877Y347560D03*
X419214Y218147D03*
X439493D03*
X459773D03*
X436113Y235696D03*
Y220096D03*
Y227896D03*
X446253Y222047D03*
Y225947D03*
X432733Y222047D03*
Y225947D03*
X442873Y220096D03*
Y227896D03*
X453013Y225947D03*
X439493Y229847D03*
Y222047D03*
Y225947D03*
X425974Y222047D03*
X419214Y225947D03*
X442873Y235696D03*
X429354Y231797D03*
X449633D03*
Y239596D03*
X452865Y270081D03*
X453013Y253247D03*
X463153Y220096D03*
Y227896D03*
X473292Y222047D03*
Y225947D03*
X459773Y229847D03*
Y222047D03*
X466533Y241547D03*
X463153Y235696D03*
X473292Y241547D03*
X469913Y235696D03*
X456393D03*
Y247396D03*
X463153D03*
X476672D03*
X456393Y220096D03*
X466533Y225947D03*
Y253247D03*
X473292D03*
X459773D03*
X476672Y262996D03*
X469913Y266896D03*
X422594Y235696D03*
Y247396D03*
X429354Y239596D03*
X476672Y220096D03*
Y235696D03*
X425974Y233746D03*
Y241547D03*
X436113Y239596D03*
X422594D03*
X432733Y233746D03*
X419214Y245447D03*
X453013Y222047D03*
X425974Y225947D03*
X422594Y220096D03*
Y227896D03*
X419214Y222047D03*
Y229847D03*
X432733Y241547D03*
X446253Y233746D03*
Y241547D03*
X442873Y239596D03*
X453013Y233746D03*
Y241547D03*
Y249347D03*
X429354Y243496D03*
X449633D03*
X429354Y235696D03*
X449633D03*
X436113Y247396D03*
X446253Y249347D03*
X442873Y251296D03*
X439493Y249347D03*
X442873Y247396D03*
X439493Y245447D03*
X434983Y255497D03*
X438363Y257446D03*
X431604D03*
X448503Y263297D03*
X441743Y259397D03*
X446253Y253247D03*
X476672Y227896D03*
X459773Y225947D03*
X466533Y233746D03*
X476672Y239596D03*
X463153D03*
X473292Y233746D03*
X469913Y231797D03*
Y243496D03*
Y239596D03*
X456393D03*
X466533Y249347D03*
X473292D03*
X459773Y245447D03*
Y249347D03*
X456393Y227896D03*
X466533Y222047D03*
X456393Y255196D03*
X463153D03*
X476672D03*
X459773Y257147D03*
X465100Y280300D03*
X455263Y267197D03*
X466533Y261047D03*
X463153Y262996D03*
X477792Y276646D03*
Y280547D03*
X473292Y261047D03*
X469913Y259096D03*
X476672Y266896D03*
X473292Y268847D03*
Y264947D03*
X474413Y274696D03*
X469913Y278596D03*
X466533Y268847D03*
X469913Y262996D03*
X458400Y276400D03*
X459773Y264947D03*
X466734Y287074D03*
X466100Y300021D03*
X471033Y339047D03*
X442020Y339220D03*
X438240Y339380D03*
X469913Y298096D03*
Y301996D03*
X477792Y284447D03*
Y296147D03*
Y300047D03*
Y292247D03*
Y311747D03*
X469913Y309797D03*
X453400Y293686D03*
X469913Y282496D03*
Y294196D03*
Y290296D03*
X463671Y319386D03*
X474413Y329296D03*
X468783Y332897D03*
X474413Y333196D03*
Y325396D03*
X477792Y323446D03*
X456900Y333000D03*
X469913Y313696D03*
Y317596D03*
X477792Y331247D03*
Y335147D03*
Y339047D03*
X463800Y289500D03*
X430474Y358547D03*
X433854Y356596D03*
X467653Y379996D03*
X443993Y354647D03*
X460893Y368296D03*
X450753Y374146D03*
X464273D03*
X454133Y368296D03*
X423714Y366347D03*
Y358547D03*
X437233Y366347D03*
X477792Y374146D03*
X427094Y387796D03*
X471033Y374146D03*
X474413Y368296D03*
X430474Y381947D03*
X423714Y378047D03*
X433854Y387796D03*
X423714Y393647D03*
X467653Y387796D03*
X447373Y383896D03*
X460893D03*
X474413D03*
X450753Y389747D03*
X440613Y383896D03*
X454133D03*
X443993Y389747D03*
X467653Y360496D03*
X447373D03*
X457513Y374146D03*
X430474Y362447D03*
Y370247D03*
X471033Y354647D03*
X460893Y360496D03*
X474413D03*
X464273Y354647D03*
X450753D03*
X440613Y360496D03*
X454133D03*
X443993Y370247D03*
X437233Y378047D03*
X440613Y376096D03*
X443993Y374147D03*
X464273Y342947D03*
X457513Y350747D03*
X460893Y344896D03*
X474413D03*
X447373Y356596D03*
X451883Y342646D03*
X448503Y344597D03*
X438363Y346546D03*
X434983Y348497D03*
X428224D03*
X431604Y346546D03*
X423714Y381947D03*
X430474Y374146D03*
X464273Y346847D03*
X471033Y342947D03*
X477792Y346847D03*
Y350747D03*
X471033Y346847D03*
X454133Y356596D03*
X443993Y362447D03*
X460893Y376096D03*
X450753Y370247D03*
X464273D03*
X454133Y376096D03*
X433854Y372197D03*
Y364396D03*
X437233Y370247D03*
X423714D03*
X427094Y364396D03*
X477792Y366347D03*
X427094Y379996D03*
X477792Y378047D03*
X427094Y391696D03*
X477792Y370247D03*
X427094Y383896D03*
X471033Y370247D03*
X474413Y376096D03*
X430474Y389747D03*
X433854Y383896D03*
X423714Y389747D03*
X447373Y387796D03*
X467653Y383896D03*
X447373Y379996D03*
X467653Y391696D03*
X447373D03*
X471033Y389747D03*
Y381947D03*
X460893Y387796D03*
X474413D03*
X464273Y389747D03*
Y381947D03*
X450753D03*
X440613Y387796D03*
X454133D03*
X443993Y381947D03*
X467653Y352696D03*
X447373D03*
X457513Y366347D03*
X467653Y364396D03*
X447373D03*
X457513Y378047D03*
X467653Y356596D03*
X457513Y370247D03*
X430474Y366347D03*
X471033Y362447D03*
X460893Y356596D03*
X474413D03*
X464273Y362447D03*
X450753D03*
X440613Y356596D03*
X447735Y588394D03*
X447766Y612659D03*
X518352Y210345D03*
X528491Y212296D03*
X494692D03*
X501452Y216196D03*
X504832Y218147D03*
X511592Y214247D03*
X514972Y216196D03*
X518352Y214247D03*
X531871D03*
X514972Y212296D03*
Y208397D03*
X521731Y212296D03*
X525111Y210346D03*
X504832Y214247D03*
X498072D03*
X508212Y216196D03*
X535251Y212296D03*
X483432Y216196D03*
X480052Y210346D03*
X483432Y212296D03*
X531871Y202547D03*
X525111D03*
X480052Y218147D03*
X521731Y216196D03*
X531871Y218147D03*
X528491Y204496D03*
X538631Y202247D03*
X498072Y218147D03*
X494692Y216196D03*
X525111Y214247D03*
X531871Y210346D03*
X535251Y216196D03*
X538631Y218147D03*
X535251Y208397D03*
X483432Y247396D03*
X508212Y243496D03*
X486812Y253247D03*
X480052D03*
X491312Y272747D03*
X494692Y266896D03*
X528491Y259096D03*
X483432Y220096D03*
X480052Y222047D03*
X501452Y251296D03*
Y255196D03*
X491312Y280547D03*
X486812Y261047D03*
X483432Y262996D03*
X498072Y280547D03*
X511592Y272747D03*
X504832Y276647D03*
X498072D03*
X491312D03*
X511592D03*
X504832Y272747D03*
X498072Y253247D03*
Y257147D03*
X504832Y280547D03*
X511592D03*
X498072Y272747D03*
X501452Y262996D03*
X498072Y261047D03*
X494692Y259096D03*
X525111Y249347D03*
X528491Y251296D03*
X525111Y241547D03*
X528491Y239596D03*
X531871Y253247D03*
X521731Y262996D03*
X525111Y264947D03*
X528491Y266896D03*
X521731Y278596D03*
X518352Y280547D03*
Y276646D03*
X484552D03*
X504832Y249347D03*
X501452Y270796D03*
X518352Y268847D03*
X538631Y276646D03*
Y245447D03*
X535251Y274696D03*
X494692Y239596D03*
Y231797D03*
X504832Y237647D03*
X508212Y227896D03*
X525111Y233746D03*
X511592Y237647D03*
X538631Y268847D03*
Y264947D03*
X531871Y245447D03*
X501452Y243496D03*
X535251Y262996D03*
X538631Y253247D03*
X531871Y280547D03*
X538631Y241547D03*
X521731Y270796D03*
X504832Y257147D03*
X508212Y251296D03*
X518352Y225947D03*
X531871Y233746D03*
Y225947D03*
X538631Y233746D03*
X531871Y272747D03*
X501452Y227896D03*
X514972Y231797D03*
X525111Y225947D03*
X494692Y220096D03*
X535251D03*
X504832Y222047D03*
X538631Y272747D03*
X483432Y231797D03*
X480052Y225947D03*
X483432Y239596D03*
X494692Y274696D03*
X483432Y227896D03*
X480052Y229847D03*
X486812Y249347D03*
X480052Y245447D03*
Y249347D03*
X498072Y245447D03*
X494692Y223996D03*
X504832Y225947D03*
X511592Y222047D03*
X498072Y249347D03*
X511592Y268847D03*
X483432Y255196D03*
X480052Y257147D03*
X508212Y274696D03*
X504832Y268847D03*
X484552Y280547D03*
X511592Y253247D03*
X508212Y266896D03*
X513857Y260881D03*
X504832Y261047D03*
X501452Y278596D03*
X504832Y264947D03*
X487932Y270796D03*
X498072Y268847D03*
X491312D03*
X487932Y266896D03*
X491312Y264947D03*
X480052D03*
X481172Y270796D03*
X494692Y262996D03*
X514972Y220096D03*
X518352Y233746D03*
Y222047D03*
X531871Y241547D03*
Y249347D03*
X528491Y223996D03*
X531871Y237647D03*
X535251Y223996D03*
X518352Y245447D03*
Y241547D03*
Y237647D03*
X521731Y239596D03*
Y243496D03*
X525111Y245447D03*
X518352Y249347D03*
X514972Y255196D03*
X521731D03*
X514972Y274696D03*
X518352Y257147D03*
X528491Y270796D03*
Y278596D03*
X535251Y255196D03*
X531871Y264947D03*
X518352D03*
X531871Y257147D03*
X528491Y255196D03*
X525111Y268847D03*
X528491Y262996D03*
X525111Y276646D03*
X484552Y272747D03*
X525111D03*
X518352D03*
X514972Y251296D03*
X498072Y264947D03*
X518352Y261047D03*
X498072Y229847D03*
X501452Y239596D03*
Y231797D03*
X511592Y233746D03*
X525111Y229847D03*
X521731Y223996D03*
X525111Y222047D03*
X531871Y229847D03*
X535251Y227896D03*
Y231797D03*
X498072Y241547D03*
Y237647D03*
X501452Y235696D03*
X508212D03*
X511592Y225947D03*
Y229847D03*
X535251Y270796D03*
X538631Y261047D03*
X504832Y233746D03*
X501452Y220096D03*
X525111Y257147D03*
Y261047D03*
X521731Y251296D03*
X511592Y245447D03*
X514972Y243496D03*
X508212Y247396D03*
X521731Y227896D03*
X538631Y229847D03*
Y280547D03*
X535251Y243496D03*
X494692Y227896D03*
X528491Y231797D03*
X535251Y278596D03*
X487932Y305896D03*
X491312Y303947D03*
X501452Y305896D03*
X494692Y298096D03*
X498072Y307847D03*
X484552Y303947D03*
X487932Y294196D03*
X491312Y296147D03*
X494692Y301996D03*
X487932D03*
X501452Y309797D03*
X487932Y298096D03*
X511592Y311747D03*
Y303947D03*
X481172Y321496D03*
X487932Y313696D03*
X481172Y325396D03*
X491312Y315647D03*
X481172Y317596D03*
X518352Y311747D03*
X528491Y305896D03*
X484552Y311747D03*
X481172Y286396D03*
X491312Y288347D03*
Y284447D03*
X498072D03*
Y288347D03*
X501452Y286396D03*
X494692Y290296D03*
X498072Y292247D03*
X504832D03*
X508212Y282496D03*
X504832Y288347D03*
Y284447D03*
X494692Y282496D03*
X508212Y286396D03*
X511592Y292245D03*
X484552Y319546D03*
X481172Y333196D03*
X484552Y331247D03*
X514972Y282496D03*
X521731D03*
X518352Y284447D03*
X538631Y307847D03*
Y303947D03*
Y300047D03*
X535251Y298096D03*
Y305896D03*
X538631Y296147D03*
X531871D03*
X535251Y317596D03*
X531871Y315647D03*
X535251Y313696D03*
X538631Y315647D03*
X528491Y282496D03*
X535251Y286396D03*
Y282496D03*
X501452Y337096D03*
X538631Y331247D03*
Y327347D03*
X535251Y340996D03*
Y337096D03*
X528491Y340996D03*
X531871Y339047D03*
Y331247D03*
X538631Y323446D03*
X525111Y319547D03*
X518352Y335147D03*
X521731Y333196D03*
Y329296D03*
X525111Y331247D03*
X528491Y333196D03*
X521731Y340996D03*
X525111Y323446D03*
X528491Y325396D03*
Y329296D03*
Y321496D03*
X531871Y323446D03*
X525111Y327347D03*
X521731Y337096D03*
X504832Y300045D03*
Y303947D03*
Y311747D03*
X508212Y301996D03*
Y305896D03*
X487932Y286396D03*
X481172Y298096D03*
Y305896D03*
X487932Y290296D03*
X484552Y288347D03*
Y296147D03*
X481172Y294196D03*
X508212Y309797D03*
X511592Y300047D03*
Y288347D03*
X494692Y305896D03*
X491312Y311747D03*
X501452Y301996D03*
X491312Y307847D03*
X498072Y311747D03*
X511592Y296147D03*
X501452Y294196D03*
X498072Y296147D03*
X504832D03*
X508212Y298096D03*
X498072Y300047D03*
X484552Y307847D03*
X508212Y340996D03*
X498072Y339047D03*
X504832Y327347D03*
X508212Y321496D03*
X481172Y329296D03*
X491312Y323446D03*
X501452Y313696D03*
X494692D03*
X501452Y329296D03*
X487932Y340996D03*
Y329296D03*
X494692D03*
X491312Y327347D03*
X498072Y331247D03*
X484552Y335147D03*
X481172Y337096D03*
X501452Y321496D03*
X481172Y340996D03*
X484552Y339047D03*
X487932Y337096D03*
Y333196D03*
X491312Y335147D03*
X494692Y333196D03*
X498072Y335147D03*
X491312Y319547D03*
X494692Y321496D03*
X501452Y317596D03*
X498072Y315647D03*
Y323446D03*
X494692Y325396D03*
X501452D03*
X494692Y317596D03*
X487932Y321496D03*
X484552Y327347D03*
X487932Y325396D03*
X514972Y305896D03*
Y309797D03*
X528491Y301996D03*
Y309797D03*
X525111Y311747D03*
Y307847D03*
Y303947D03*
X521731Y305896D03*
Y309797D03*
X518352Y307847D03*
X514972Y298096D03*
X518352Y292245D03*
Y288347D03*
X521731Y286396D03*
Y290296D03*
Y298096D03*
X525111Y292245D03*
Y296147D03*
X528491Y290296D03*
X525111Y288347D03*
X521731Y294196D03*
X518352Y300047D03*
Y296147D03*
X514972Y313696D03*
X528491D03*
X521731D03*
X514972Y340996D03*
X518352Y331247D03*
X521731Y321496D03*
X525111Y339047D03*
X535251Y333196D03*
Y325396D03*
X484552Y315647D03*
X481172Y282496D03*
X518352Y303947D03*
X531871Y284447D03*
X484552D03*
Y342947D03*
X481172Y364396D03*
Y383896D03*
X535251Y376096D03*
X518352Y401447D03*
X504832Y385847D03*
Y393647D03*
X508212Y376096D03*
X498072Y370247D03*
X504832D03*
X501452Y372197D03*
X487932Y356596D03*
X491312Y342947D03*
Y354647D03*
X511592Y389747D03*
Y401447D03*
X508212Y383896D03*
X504832Y401446D03*
X535251Y348796D03*
Y344896D03*
X538631Y346847D03*
Y342947D03*
X535251Y360496D03*
X531871Y358547D03*
X535251Y364396D03*
Y368296D03*
X525111Y346847D03*
X528491Y348796D03*
X531871Y342947D03*
X528491Y344896D03*
Y352696D03*
X538631Y354647D03*
Y358547D03*
Y362447D03*
X531871D03*
Y366347D03*
X535251Y372197D03*
X538631Y350747D03*
X535251Y379996D03*
X538631Y374146D03*
X531871Y378047D03*
X514972Y376096D03*
X528491Y387796D03*
X521731D03*
Y391696D03*
X518352Y393647D03*
X514972Y395597D03*
X528491Y379996D03*
Y383896D03*
X525111Y385847D03*
X521731Y383896D03*
X525111Y389747D03*
X521731Y395597D03*
X514972Y391696D03*
Y387796D03*
X528491Y376096D03*
X531871Y381947D03*
X494692Y387796D03*
X514972Y364396D03*
X518352Y350747D03*
X504832Y374146D03*
X508212Y368296D03*
X514972Y360496D03*
X508212Y372197D03*
X511592Y354647D03*
X498072Y378047D03*
Y381947D03*
X518352Y354647D03*
X511592Y366347D03*
X494692Y379996D03*
X501452Y376096D03*
X511592Y362447D03*
X508212Y364396D03*
X514972Y368296D03*
X511592Y358547D03*
X498072Y374146D03*
X521731Y352696D03*
X494692Y383896D03*
X518352Y346847D03*
X484552Y374146D03*
X487932Y383896D03*
X491312Y393647D03*
X494692Y399496D03*
X484552Y389747D03*
X508212Y344896D03*
Y348796D03*
X511592Y346847D03*
Y350747D03*
Y342947D03*
X504832Y362447D03*
X494692Y368296D03*
Y352696D03*
X508212Y356596D03*
X504832Y350747D03*
X487932Y348796D03*
X481172Y356596D03*
X484552Y358547D03*
Y350747D03*
Y354647D03*
X487932Y352696D03*
Y344896D03*
X511592Y374146D03*
X501452Y383896D03*
X498072Y389747D03*
X494692Y376096D03*
X508212Y379996D03*
X521731Y368296D03*
X518352Y366347D03*
X514972Y348796D03*
Y344896D03*
Y352696D03*
X518352Y358547D03*
X521731Y344896D03*
X538631Y370247D03*
X525111Y350747D03*
Y370247D03*
X531871D03*
X525111Y362447D03*
X528491Y360496D03*
Y356596D03*
X525111Y366347D03*
X528491Y368296D03*
X521731Y364396D03*
X525111Y358547D03*
X531871Y354647D03*
X528491Y372197D03*
X525111Y378047D03*
Y374146D03*
X521731Y376096D03*
X514972Y399496D03*
X538631Y381947D03*
X531871Y385847D03*
X528491Y391696D03*
X525111Y397546D03*
X481172Y348796D03*
X535251Y395597D03*
Y387796D03*
Y391696D03*
Y352696D03*
X531871Y350747D03*
Y397546D03*
X528491Y399496D03*
X521731Y403396D03*
X538631Y385847D03*
Y389747D03*
X531871Y393647D03*
X535251Y399496D03*
X528491Y395597D03*
X525111Y401447D03*
X518352Y374146D03*
X521731Y379996D03*
X514972Y383896D03*
X511592Y381947D03*
X508212Y391696D03*
X504832Y389747D03*
X508212Y395597D03*
X518352Y378047D03*
Y381947D03*
Y385847D03*
X511592D03*
X501452Y387796D03*
X511592Y393647D03*
X504832Y397546D03*
X481172Y376096D03*
Y368296D03*
X487932Y387796D03*
Y391696D03*
Y379996D03*
X491312Y401447D03*
X481172Y387796D03*
X494692Y395597D03*
X484552Y381947D03*
X518352Y405347D03*
X531871D03*
X525111D03*
X602163Y-1743D03*
Y9157D03*
X598817Y17057D03*
X602163Y27899D03*
X598817Y54857D03*
X602163Y46957D03*
Y54799D03*
Y36057D03*
X598817Y92657D03*
X602163Y84757D03*
Y73857D03*
X545391Y214247D03*
Y218147D03*
X548771Y216196D03*
X542011Y212296D03*
X558911Y218147D03*
X542011Y208396D03*
X599773Y199596D03*
X600286Y202921D03*
X542011Y216196D03*
X552151Y237647D03*
X542011Y231797D03*
X548771D03*
X552151Y280547D03*
X548771Y274696D03*
Y220096D03*
X555531D03*
Y227896D03*
X542011Y278596D03*
Y262996D03*
X555531Y270796D03*
X552151Y264947D03*
X542011Y259096D03*
X545391Y257147D03*
Y249347D03*
X548771Y223996D03*
X542011Y243496D03*
X552151Y222047D03*
X562616Y223996D03*
X542011Y251296D03*
X545391Y245447D03*
X555531Y243496D03*
Y259096D03*
X552151Y253247D03*
X548771Y259096D03*
X562640Y231735D03*
X542011Y220096D03*
X555531Y231797D03*
X548771Y227896D03*
X552151Y245447D03*
X548771Y251296D03*
X542011Y223996D03*
X545391Y237647D03*
X548771Y270796D03*
Y262996D03*
X545391Y276646D03*
X542011Y270796D03*
Y227896D03*
X545391Y229847D03*
X558911Y253247D03*
X548771Y247396D03*
X545391Y241547D03*
X562630Y227896D03*
X555531Y223996D03*
X542011Y235696D03*
X552151Y272747D03*
X555531Y262996D03*
X558911Y225947D03*
X555531Y251296D03*
X558911Y241547D03*
X545391Y261047D03*
X555531Y255196D03*
X545391Y253247D03*
X558911Y268847D03*
Y249347D03*
X552151Y276646D03*
X555531Y266896D03*
X558911Y257147D03*
X555531Y278596D03*
X552151Y268847D03*
X542011Y255196D03*
Y266896D03*
X592300Y220500D03*
X548771Y305896D03*
X552151Y300047D03*
X548771Y301996D03*
X552151Y307847D03*
Y303947D03*
X555831Y301996D03*
X548771Y298096D03*
X542011Y317596D03*
Y309797D03*
X545391Y311747D03*
X542011Y305896D03*
Y301996D03*
X552151Y311747D03*
X542011Y313696D03*
X548771Y321496D03*
X545391Y323446D03*
X552151Y319547D03*
Y315647D03*
X559211Y331103D03*
X555531Y329296D03*
X559211Y323446D03*
X555531Y321496D03*
X548771Y317596D03*
X555831Y313696D03*
X559211Y327347D03*
X552151D03*
X555531Y325396D03*
X555831Y317446D03*
X552151Y292245D03*
X542011Y290296D03*
X560884D03*
X542011Y282496D03*
X552151Y331247D03*
Y335147D03*
X548771Y333196D03*
X552151Y339047D03*
X555531Y340996D03*
X542011D03*
Y337096D03*
X545391Y327347D03*
Y339047D03*
X542011Y333196D03*
Y329296D03*
Y325396D03*
X562591Y340996D03*
X558911Y339047D03*
X562591Y337096D03*
X555531D03*
X548771Y282496D03*
Y290296D03*
Y294196D03*
Y337096D03*
Y329296D03*
X545391Y284447D03*
X555531Y282496D03*
X555831Y294196D03*
X542011Y286396D03*
X545391Y389747D03*
X542011Y391696D03*
Y395597D03*
Y387796D03*
X545391Y393647D03*
X552151Y366347D03*
Y370247D03*
X563500Y360500D03*
X555531Y372197D03*
X548771Y364396D03*
X552151Y393647D03*
X559212Y389747D03*
X548990Y403670D03*
X555750Y399770D03*
X552151Y342947D03*
X548771Y344896D03*
X552151Y346847D03*
X542011Y344896D03*
Y356596D03*
X559211Y366347D03*
X558911Y354647D03*
X552151Y362447D03*
X545391Y350747D03*
X548771Y348796D03*
X555531Y352696D03*
Y348796D03*
X552151Y354647D03*
X558911Y350747D03*
X555531Y344896D03*
X548771Y387796D03*
X552151Y385847D03*
X555531Y379996D03*
X552151Y381947D03*
X562591Y348796D03*
X542011Y364396D03*
Y372197D03*
Y352696D03*
X545391Y342947D03*
X548771Y372196D03*
X545391Y362447D03*
Y378047D03*
X552151Y374146D03*
X548771Y376096D03*
X559212Y385847D03*
X542011Y383896D03*
X545391Y374146D03*
X548771Y360496D03*
Y356596D03*
X542011Y379996D03*
X548771Y383896D03*
X545391Y370247D03*
X552151Y358547D03*
X548771Y352696D03*
X545391Y381947D03*
X548771Y379996D03*
X592216Y445152D03*
X595070Y447970D03*
X598817Y518057D03*
X602163Y510157D03*
Y547957D03*
Y537057D03*
Y566699D03*
X598817Y555857D03*
X602163Y555799D03*
Y574857D03*
Y585757D03*
Y612657D03*
X598817Y593657D03*
X608856Y-9901D03*
X612203D03*
X608856Y-1743D03*
X612203D03*
X615549D03*
Y9157D03*
X608856D03*
X612203D03*
X615549Y-9901D03*
X612203Y16999D03*
X608856D03*
X612203Y27899D03*
X608856D03*
X615549D03*
Y16999D03*
X657250Y-2050D03*
X661494Y32946D03*
X659700Y22900D03*
X605510Y27899D03*
Y9157D03*
Y-1743D03*
Y-9901D03*
Y16999D03*
X659747Y-12132D03*
X612203Y54799D03*
X615549Y46957D03*
X608856Y54799D03*
X612203Y46957D03*
X608856D03*
X615549Y36057D03*
X608856D03*
X612203D03*
X608856Y65699D03*
X612203D03*
X615549D03*
Y54799D03*
X612203Y92599D03*
X608856D03*
X612203Y84757D03*
X608856D03*
X615549D03*
Y73857D03*
X608856D03*
X612203D03*
X615549Y92599D03*
X652718Y93881D03*
X662352Y89566D03*
X605510Y92599D03*
Y73857D03*
Y36057D03*
Y46957D03*
Y84757D03*
Y65699D03*
Y54799D03*
X618800Y100100D03*
X603163Y103971D03*
X608600Y103000D03*
X633800Y119000D03*
X609482Y124568D03*
X628673Y142718D03*
X632173Y142018D03*
X644055Y144493D03*
X642673Y139811D03*
X639173Y140618D03*
X654555Y142193D03*
X651055Y142893D03*
X647555Y143643D03*
X658055Y141493D03*
X635673Y141318D03*
X626040Y98281D03*
X613602Y118047D03*
Y109247D03*
X605028Y119000D03*
X604977Y110200D03*
X660600Y170000D03*
X609860Y201356D03*
X613082Y200676D03*
X613773Y196796D03*
X610273Y197496D03*
X603273Y198896D03*
X613648Y204494D03*
X608648D03*
X618648Y214494D03*
X611148Y206994D03*
X644750Y175650D03*
X660600Y175000D03*
X617235Y247735D03*
X614456Y244956D03*
X618648Y219494D03*
X651235Y249165D03*
X654950Y253446D03*
X639320Y268000D03*
X643500Y274868D03*
X643100Y253700D03*
X624500Y240500D03*
X627529Y280441D03*
X606148Y229494D03*
X633410Y269610D03*
Y274610D03*
X656100Y275500D03*
X649800Y252600D03*
X618279Y251393D03*
X662238Y296146D03*
X628950Y293550D03*
X654600Y296000D03*
X664267Y292668D03*
X646700Y308850D03*
X639622Y290210D03*
X643823Y289650D03*
X658500Y284500D03*
X648900Y336600D03*
X658900Y339150D03*
X637143Y322000D03*
X637561Y312000D03*
X637600Y307000D03*
X631250Y289650D03*
X628525Y287832D03*
X641665Y281139D03*
X637561Y317000D03*
X637600Y302000D03*
X632869Y293720D03*
X646520Y297400D03*
X637681Y337390D03*
X649600Y391200D03*
X664194Y351206D03*
X654194D03*
X659694D03*
X649194D03*
X609191Y451454D03*
X615300Y457900D03*
X640300Y437600D03*
X608800Y463475D03*
X618430Y491550D03*
X623400Y476300D03*
X629300Y490000D03*
X612515Y498752D03*
X612203Y510157D03*
X608856D03*
X615549D03*
X612203Y517999D03*
X608856D03*
X615549D03*
X623600Y521700D03*
X648500Y477400D03*
X639197Y490367D03*
X658900Y509300D03*
X653800Y496600D03*
X641150Y484300D03*
X611250Y476750D03*
X605510Y517999D03*
Y510157D03*
X609284Y480055D03*
X618800Y474500D03*
X639120Y475620D03*
X608800Y468475D03*
X636500Y493924D03*
X627000Y478300D03*
X608856Y547957D03*
X615549D03*
X612203D03*
X608856Y528899D03*
X612203D03*
X608856Y537057D03*
X615549D03*
X612203D03*
X615549Y528899D03*
X608856Y566699D03*
X612203D03*
Y555799D03*
X608856D03*
X615549Y574857D03*
X612203D03*
X615549Y585757D03*
X612203D03*
X608856Y574857D03*
Y585757D03*
X615549Y555799D03*
Y566699D03*
X662640Y528330D03*
X660217Y576734D03*
X662000Y589000D03*
X605510Y566699D03*
Y528899D03*
Y555799D03*
Y585757D03*
Y574857D03*
Y537057D03*
Y547957D03*
X608856Y612657D03*
X615549D03*
X612203D03*
X631741Y615759D03*
X612203Y604499D03*
X608856D03*
X612203Y593599D03*
X608856D03*
X615549Y604499D03*
Y593599D03*
X605510Y604499D03*
Y612657D03*
Y593599D03*
X692500Y15300D03*
X679936Y18406D03*
X670400Y26100D03*
X701100Y8100D03*
X704450Y4950D03*
X723715Y23462D03*
X708000Y26600D03*
X700500D03*
X719400Y14300D03*
X665396Y23000D03*
X680200Y13100D03*
X714300Y-1900D03*
X724837Y13852D03*
X689500Y37900D03*
X675235Y36797D03*
X685000Y46650D03*
X670227Y34277D03*
X664471Y86061D03*
X694600Y85000D03*
X715130Y79574D03*
X697200Y79500D03*
X697100Y90600D03*
X716894Y84047D03*
X701500Y85500D03*
X698300Y85300D03*
X709560Y84648D03*
X670795Y89189D03*
X720572Y88700D03*
X670600Y144900D03*
Y150000D03*
X670503Y115884D03*
X709341Y190507D03*
X701956Y195294D03*
X705292Y195729D03*
X701129Y192106D03*
X690130Y277380D03*
X689960Y260500D03*
X725725Y241560D03*
X710500Y224500D03*
X710900Y231660D03*
X700000Y233700D03*
X704500Y252500D03*
X700800Y261300D03*
X715200Y258900D03*
X704090Y256080D03*
X710675Y263425D03*
X697255Y267098D03*
X700400Y257200D03*
X679300Y261700D03*
X677800Y254100D03*
X667700Y275600D03*
X710700Y260200D03*
X674469Y287375D03*
X695000Y289500D03*
X670800Y292600D03*
X688100Y308600D03*
X686600Y335600D03*
X674700Y339200D03*
X706800Y281900D03*
X711900Y327700D03*
X712400Y324400D03*
X704404Y310875D03*
X697521Y320500D03*
X697120Y305349D03*
X688924Y288147D03*
X704404Y315875D03*
X686140Y298260D03*
X667900Y339000D03*
X710272Y281911D03*
X724000Y291700D03*
X705800Y301600D03*
X697521Y325500D03*
X697352Y335500D03*
Y330500D03*
X697120Y300349D03*
X674194Y358467D03*
X683417Y364972D03*
X695700Y346300D03*
X683100Y392200D03*
X686619Y392600D03*
X691240Y390039D03*
X669194Y351206D03*
X674194D03*
X679194D03*
X684194D03*
X676900Y381800D03*
X687427Y384926D03*
X680200Y432100D03*
X680370Y427770D03*
X687400Y411200D03*
X718546Y500283D03*
X674300Y489500D03*
X669300Y504000D03*
X690500Y523300D03*
X675500Y521900D03*
X708500Y512500D03*
X700500Y512850D03*
X726040Y506080D03*
X721894Y501346D03*
X696000Y496800D03*
X679700Y489400D03*
X686200Y511700D03*
X680000Y511800D03*
X680910Y582000D03*
X693200Y575900D03*
X696600Y581400D03*
X722200Y571300D03*
X680029Y577503D03*
X718200Y581000D03*
X665000Y598500D03*
X717612Y598554D03*
X722406Y598950D03*
X755000Y17255D03*
X729500Y23500D03*
X729600Y17991D03*
X734256D03*
X766300Y-1800D03*
X765400Y-9800D03*
X764100Y17100D03*
X760100Y17255D03*
X763500Y23940D03*
X756176Y-4300D03*
X769881Y9157D03*
X751600Y41000D03*
X755500Y55200D03*
X753100Y92111D03*
X764100Y55100D03*
X763500Y59700D03*
X765900Y35800D03*
X769881Y46957D03*
X752900Y101000D03*
X766500Y102900D03*
X771232Y214033D03*
X770300Y204930D03*
X769044Y191348D03*
X731662Y247716D03*
X761580Y220160D03*
X771650Y246451D03*
Y278451D03*
X748700Y257500D03*
X759700Y232000D03*
X739500Y247500D03*
X749126Y220843D03*
X739400Y253400D03*
X730000Y254675D03*
X736000Y303400D03*
X741250Y298856D03*
X741512Y315538D03*
X771600Y310600D03*
X757956Y328095D03*
X729405Y290725D03*
X743600Y304100D03*
X737750Y298894D03*
X737912Y315500D03*
X732000Y380000D03*
X771700Y342501D03*
X765007Y348363D03*
X771400Y374400D03*
X760500Y359800D03*
X739933Y447401D03*
X763706Y514250D03*
X743483Y492937D03*
X756000Y525950D03*
X769500Y510100D03*
X766535Y517900D03*
X738648Y492050D03*
X763544Y522236D03*
X755000Y566000D03*
X732600Y573950D03*
X764400Y528600D03*
X769500Y536983D03*
X765100Y537110D03*
X763300Y566000D03*
X769500Y585700D03*
X764117Y575658D03*
X766535Y555700D03*
X763450Y585200D03*
X765900Y587300D03*
X769500Y547900D03*
Y574700D03*
X733032Y604000D03*
X769500Y612583D03*
X739307Y598850D03*
X755800Y604600D03*
X764400D03*
X766535Y593500D03*
X799300Y195600D03*
X813700D03*
X799620Y186547D03*
X798337Y181216D03*
X813700Y198900D03*
X804470Y186814D03*
X805600Y403900D03*
X824000Y402863D03*
X840871Y391380D03*
X837272Y391420D03*
X827800Y402863D03*
X832300D03*
X797000Y404700D03*
X805367Y407400D03*
X797780Y423484D03*
X882008Y321100D03*
X851430Y367468D03*
X930987Y209109D03*
X937747Y201309D03*
Y209109D03*
X927607Y199360D03*
X924227Y201309D03*
Y209109D03*
Y205210D03*
X930987Y216909D03*
X934367Y203260D03*
Y211060D03*
X958026Y216909D03*
X944507D03*
X951267Y213009D03*
Y216909D03*
X944507Y197409D03*
Y205210D03*
Y209109D03*
X937747Y213009D03*
Y205210D03*
X917467Y209109D03*
X920847Y203260D03*
Y207159D03*
X927607Y218860D03*
X934367D03*
X930987Y205210D03*
X947887Y214960D03*
X954647D03*
X941127Y203260D03*
Y211060D03*
X930987Y248109D03*
X937747Y244209D03*
X927607Y246160D03*
X934367Y242260D03*
X930987Y228610D03*
X937747D03*
X927607Y222760D03*
X913700Y242260D03*
X920847D03*
Y250060D03*
X927607Y226660D03*
X917467Y248109D03*
X934367Y222760D03*
X927607Y238360D03*
X934367Y250060D03*
Y238360D03*
X917467Y271509D03*
X927607Y273460D03*
X924227Y271509D03*
X913787Y257860D03*
X920847Y261760D03*
Y253960D03*
X930987Y255909D03*
X934367Y269560D03*
X937747Y267609D03*
X927607Y261760D03*
X937747Y259809D03*
X934367Y261760D03*
X930987Y263709D03*
X947887Y222760D03*
X954647D03*
X951267Y220809D03*
X971546Y240309D03*
Y244209D03*
X961406Y242260D03*
X964786Y244209D03*
X961406Y246160D03*
X964786Y248109D03*
X958026D03*
X968166Y250060D03*
X971546Y279310D03*
X944507Y271509D03*
X964786Y263709D03*
Y275409D03*
X961406Y265660D03*
X971546Y271509D03*
X958026D03*
X968166Y265660D03*
Y273460D03*
X944507Y267609D03*
X947887Y269560D03*
X951267Y271509D03*
X947887Y273460D03*
X941127D03*
X944507Y232509D03*
X971546Y228610D03*
X968166Y222760D03*
X951267Y232509D03*
Y252009D03*
Y244209D03*
X947887Y257860D03*
X968166Y230559D03*
X964786Y228610D03*
X944507Y259809D03*
X954647Y234460D03*
X961406Y226660D03*
X944507Y240309D03*
X954647Y253960D03*
Y238360D03*
Y261760D03*
X951267Y263709D03*
X947887Y250060D03*
X944507Y252009D03*
X964786Y236409D03*
X961406Y234460D03*
X954647Y257860D03*
X968166Y234460D03*
X971546Y252009D03*
X937747Y240309D03*
X930987Y244209D03*
X937747Y224709D03*
X934367Y230559D03*
X913787Y246160D03*
X920847D03*
X937747Y220809D03*
X930987Y224709D03*
Y236409D03*
X937747Y248109D03*
X927607Y242260D03*
X937747Y279310D03*
X917000Y276000D03*
X920847Y277360D03*
X924227Y279310D03*
X913787Y273460D03*
X920847Y257860D03*
X913787Y261760D03*
X917467Y255909D03*
X930987Y267609D03*
X937747Y263709D03*
X927607Y257860D03*
X934367D03*
X927607Y265660D03*
X916967Y279310D03*
X930987D03*
X958026Y220809D03*
X944507D03*
X951267Y224709D03*
X944507Y279310D03*
X964786Y267609D03*
Y271509D03*
X961406Y273460D03*
X971546Y267609D03*
X958026D03*
Y279310D03*
X951267D03*
X947887Y230559D03*
X971546Y224709D03*
X944507Y236409D03*
X954647Y242260D03*
X947887Y261760D03*
X951267Y236409D03*
X947887Y238360D03*
X951267Y255909D03*
X971546Y232509D03*
X947887Y242260D03*
X944507Y255909D03*
X964786Y224709D03*
X961406Y230559D03*
X913787Y335860D03*
X920847Y331960D03*
Y339760D03*
X930987Y330009D03*
Y341709D03*
X937747Y330009D03*
X927607Y335860D03*
X934367D03*
Y320260D03*
X927607Y324160D03*
X947887Y335860D03*
X954647D03*
X944507Y341709D03*
X951267D03*
X968166Y331960D03*
X964786Y326110D03*
X947887Y320260D03*
X941127D03*
X944507Y330009D03*
X961406Y331960D03*
X971546Y326110D03*
Y341709D03*
X944507Y326110D03*
X937747Y322209D03*
X930987D03*
X947887Y324160D03*
X941127D03*
X937747Y287109D03*
X920500Y304660D03*
Y300760D03*
X930987Y302709D03*
X924227D03*
X920500Y311960D03*
X927607Y304660D03*
X924227Y306609D03*
X930987D03*
Y310509D03*
X934367Y304660D03*
X924227Y310509D03*
X920500Y308560D03*
Y289060D03*
X934367Y296860D03*
X930987Y294909D03*
X920500Y296860D03*
Y292959D03*
X927607Y296860D03*
X924227Y298809D03*
X930987D03*
X924227Y283209D03*
X927607Y281260D03*
X920500Y285500D03*
X924227Y287109D03*
X920847Y281260D03*
X930987Y287109D03*
X934367Y289060D03*
Y281260D03*
X930987Y283209D03*
X924227Y291009D03*
X930987D03*
X927607Y289060D03*
X937747Y302709D03*
Y306609D03*
Y310509D03*
Y283209D03*
Y291009D03*
Y294909D03*
Y298809D03*
X920847Y335860D03*
X913787Y331960D03*
X917467Y337809D03*
X937747Y333909D03*
X927607Y339760D03*
X934367Y328060D03*
Y339760D03*
X927607Y331960D03*
X930987Y333909D03*
X937747Y337809D03*
Y314409D03*
X924227D03*
X930987D03*
X934367Y312460D03*
X927607D03*
X920847Y324160D03*
X924227Y318309D03*
X920547Y316160D03*
X917167Y318309D03*
Y322209D03*
X917467Y326110D03*
X920847Y320260D03*
X971546Y294909D03*
X944507Y283209D03*
X964786Y291009D03*
X954647Y281260D03*
X958026Y283209D03*
X951267Y287109D03*
X958026D03*
X951267Y283209D03*
X961406Y281260D03*
Y296860D03*
X964786Y298809D03*
Y302709D03*
X971546D03*
X961406Y304660D03*
X958026Y302709D03*
X951267D03*
X968166Y308560D03*
X964786Y306609D03*
X968166Y304660D03*
X971546Y306609D03*
X951267Y310509D03*
X954647Y304660D03*
X958026Y306609D03*
Y310509D03*
X951267Y306609D03*
X944507Y302709D03*
Y306609D03*
Y310509D03*
X941127Y304660D03*
X947887D03*
X944507Y294909D03*
Y287109D03*
X971546Y298809D03*
X968166Y285160D03*
X964786Y287109D03*
X944507Y291009D03*
X941127Y281260D03*
Y289060D03*
Y296860D03*
X944507Y298809D03*
X947887Y289060D03*
Y296860D03*
Y281260D03*
X968166Y296860D03*
X964786Y294909D03*
X971546Y291009D03*
Y287109D03*
X968166Y289060D03*
X961406D03*
X958026Y298809D03*
X951267D03*
Y291009D03*
X958026D03*
X954647Y289060D03*
Y296860D03*
X958026Y294909D03*
X951267D03*
X954647Y339760D03*
X951267Y333909D03*
X944507Y337809D03*
X968166Y335860D03*
X947887Y339760D03*
X944507Y314409D03*
X951267D03*
X958026D03*
X961406Y312460D03*
X954647D03*
X941127D03*
X947887D03*
X971546Y314409D03*
Y318309D03*
X964786D03*
X951267Y322209D03*
X954647Y324160D03*
X961406Y320260D03*
X954647D03*
X958026Y322209D03*
X951267Y326110D03*
X968166Y316360D03*
Y328060D03*
Y324160D03*
X964786Y333909D03*
X961406Y328060D03*
X971546Y333909D03*
X934367Y367060D03*
X913787Y351460D03*
X920847D03*
X927607Y370959D03*
X917467Y345609D03*
X934367Y347560D03*
X927607Y359260D03*
X934367Y355360D03*
X927607Y351460D03*
X937747Y372909D03*
X927607Y378760D03*
X934367D03*
Y386560D03*
X930987Y392410D03*
X937747Y396309D03*
X930987Y400209D03*
X917467Y392410D03*
X924227Y396309D03*
X971546Y357309D03*
X951267Y365109D03*
Y353409D03*
X944507Y365109D03*
X961406Y367060D03*
X964786Y361209D03*
X947887Y347560D03*
X954647Y359260D03*
X971546Y345609D03*
X944507Y357309D03*
X971546Y365109D03*
X958026Y349509D03*
X947887Y382660D03*
X958026Y376809D03*
X944507D03*
X954647Y382660D03*
X951267Y372909D03*
X944507Y392410D03*
X941127Y386560D03*
X971546Y372909D03*
X964786D03*
X944507Y400209D03*
X964786Y384609D03*
Y380709D03*
X930987Y369010D03*
X937747D03*
X913787Y347560D03*
X920847Y343660D03*
X934367Y359260D03*
X930987Y361209D03*
X937747Y349509D03*
X927607Y355360D03*
X937747Y353409D03*
X930987Y349509D03*
X937747Y357309D03*
X930987Y353409D03*
X920847Y347560D03*
X930987Y380709D03*
X927607Y374860D03*
X934367D03*
X937747Y376809D03*
X930987Y372909D03*
X934367Y394359D03*
X930987Y388509D03*
X937747D03*
Y384609D03*
Y392410D03*
X924227Y400209D03*
X920847Y394359D03*
Y398260D03*
X927607D03*
X971546Y353409D03*
X947887Y367060D03*
X954647Y355360D03*
X944507Y361209D03*
X968166Y363160D03*
X961406D03*
X971546Y369010D03*
X944507Y345609D03*
X951267D03*
X947887Y355360D03*
X951267Y361209D03*
X968166Y367060D03*
X961406Y370959D03*
X954647Y363160D03*
X947887Y359260D03*
X964786Y369010D03*
X954647Y343660D03*
X964786Y349509D03*
Y353409D03*
X961406Y355360D03*
Y347560D03*
Y351460D03*
X958026Y380709D03*
X954647Y374860D03*
X951267Y376809D03*
Y384609D03*
Y380709D03*
X944507Y388509D03*
X941127Y394359D03*
X968166Y374860D03*
X947887D03*
X944507Y380709D03*
X988446Y214960D03*
Y218860D03*
X978306Y236409D03*
Y240309D03*
Y244209D03*
X974926Y246160D03*
X985066Y240309D03*
X981686Y246160D03*
X988446Y222760D03*
X985066Y220809D03*
X981686Y222760D03*
X978306Y224709D03*
X981686Y226660D03*
X985066Y228610D03*
X978306D03*
X981686Y230559D03*
X985066Y232509D03*
X995206Y253960D03*
X998586Y255909D03*
X995206Y257860D03*
X998586Y259809D03*
X995206Y261760D03*
X988446Y269560D03*
X985066Y271509D03*
X978306D03*
X988446Y273460D03*
X981686D03*
X985066Y275409D03*
X978306D03*
X988446Y277360D03*
X981686D03*
X974926D03*
X985066Y279310D03*
X978306D03*
X1008725Y253960D03*
X1001965D03*
X1005345Y255909D03*
X1001965Y257860D03*
X985066Y263709D03*
X988446Y257860D03*
X981686D03*
Y265660D03*
Y253960D03*
X974926Y261760D03*
Y257860D03*
X978306Y263709D03*
X988446Y250060D03*
Y230560D03*
X978306Y248109D03*
X974926Y238360D03*
X985066Y244209D03*
X981686Y238360D03*
X991826Y252009D03*
X995206Y277360D03*
X998586Y267609D03*
Y271509D03*
Y275409D03*
Y279310D03*
X1022245Y253960D03*
X1017735Y264300D03*
X1014355Y266300D03*
X1021115Y262300D03*
X1024495Y260300D03*
X1005345Y263709D03*
X1001965Y265660D03*
X1008725Y261760D03*
X1006665Y277360D03*
X1015485Y257860D03*
X1018865Y255909D03*
X1012105Y259809D03*
X988446Y261760D03*
X981686D03*
X985066Y255909D03*
X978306D03*
X998586Y337809D03*
X991826D03*
X978306D03*
X985066Y333909D03*
X974926Y331960D03*
X1001965Y339760D03*
X1005345Y341709D03*
X998586D03*
X995206Y296860D03*
X985066Y294909D03*
Y287109D03*
X988446Y285160D03*
X991826Y287109D03*
X995206Y281260D03*
X978306Y298809D03*
Y287109D03*
X981686Y285160D03*
X978306Y294909D03*
X981686Y296860D03*
Y289060D03*
X978306Y291009D03*
X998586Y302709D03*
Y306609D03*
Y310509D03*
Y287109D03*
Y294909D03*
Y291009D03*
Y298809D03*
Y283209D03*
X985066Y302709D03*
X978306D03*
X988446Y304660D03*
Y308560D03*
X985066Y306609D03*
X995206Y304660D03*
Y308560D03*
X991826Y306609D03*
X978306D03*
X981686Y308560D03*
Y304660D03*
X974926D03*
Y308560D03*
X995206Y300760D03*
X991826Y302709D03*
X974926Y285160D03*
Y296860D03*
Y289060D03*
X995206Y292959D03*
X988446Y296860D03*
X991826Y294909D03*
X995206Y289060D03*
X988446D03*
X991826Y291009D03*
X985066D03*
X995206Y285160D03*
X985066Y298809D03*
X991826D03*
X981686Y335860D03*
X978306Y341709D03*
X985066Y337809D03*
Y341709D03*
X974926Y328060D03*
X998586Y314409D03*
X995206Y312460D03*
X998586Y318309D03*
Y322209D03*
Y326110D03*
Y330009D03*
X995206Y316360D03*
X985066Y314409D03*
X978306D03*
Y318309D03*
Y322209D03*
X981686Y320260D03*
X974926Y316360D03*
Y320260D03*
X985066Y326110D03*
X981686Y328060D03*
X988446D03*
Y324160D03*
X985066Y318309D03*
Y322209D03*
X988446Y320260D03*
X981686Y324160D03*
Y316360D03*
X1006665Y300760D03*
Y304660D03*
Y308560D03*
Y285160D03*
Y296860D03*
Y289060D03*
Y281260D03*
Y292959D03*
X1008725Y335860D03*
X1005345Y333909D03*
X1001965Y331960D03*
X1007595Y327609D03*
X1021115Y335409D03*
X1018865Y341709D03*
X1017735Y333460D03*
X1015485Y339760D03*
X1024495Y337360D03*
X1012105Y337809D03*
X1006665Y312460D03*
X1014355Y331509D03*
X1010975Y329560D03*
X1006665Y324160D03*
Y316360D03*
Y320260D03*
X991826Y341709D03*
X988446Y335860D03*
X978306Y361209D03*
X974926Y351460D03*
X981686D03*
X988446Y370959D03*
X981686Y343660D03*
X991826Y349509D03*
X995206Y347560D03*
X981686Y370959D03*
X978306Y369010D03*
X985066D03*
Y365109D03*
X988446Y363160D03*
Y378760D03*
X985066Y376809D03*
X981686Y374860D03*
X1012105Y345609D03*
X988446Y343660D03*
X991826Y361209D03*
X985066Y357309D03*
X998586Y345609D03*
X981686Y367060D03*
X978306Y372909D03*
X1001965Y343660D03*
X978306Y353409D03*
Y349509D03*
Y357309D03*
X974926Y359260D03*
X981686D03*
X988446Y367060D03*
X991826Y365109D03*
Y353409D03*
Y372909D03*
X988446Y374860D03*
Y382660D03*
X1005345Y345609D03*
X1008725Y343660D03*
X985066Y345609D03*
X991826Y369010D03*
Y357309D03*
X985066Y353409D03*
X1061023Y-9786D03*
X1067716Y-9901D03*
X1089101Y218147D03*
X1065242Y216196D03*
X1068822Y218147D03*
X1092481Y220096D03*
Y227896D03*
X1089101Y229847D03*
X1075582Y222047D03*
X1065242Y227896D03*
Y231797D03*
X1072202Y220096D03*
Y227896D03*
X1068822Y225947D03*
Y222047D03*
X1095861Y241547D03*
X1092481Y235696D03*
Y239596D03*
X1072202Y247396D03*
X1065242Y243496D03*
X1085721Y220096D03*
X1095861Y225947D03*
X1082341D03*
X1078962Y231797D03*
X1082341Y241547D03*
X1085721Y235696D03*
X1075582Y241547D03*
X1072202Y235696D03*
X1078962D03*
Y243496D03*
X1089101Y222047D03*
Y225947D03*
X1065242Y220096D03*
X1075582Y225947D03*
X1068822Y229847D03*
X1095861Y233746D03*
X1092481Y247396D03*
X1089101Y245447D03*
X1085721Y247396D03*
X1089101Y249347D03*
X1092481Y251296D03*
X1095861Y249347D03*
X1065242Y239596D03*
X1068822Y245447D03*
X1085721Y227896D03*
X1095861Y222047D03*
X1082341D03*
X1087971Y257800D03*
X1091351Y259600D03*
X1094731Y261500D03*
X1084591Y255497D03*
X1081212Y257600D03*
X1095861Y253247D03*
X1078962Y239596D03*
X1082341Y233746D03*
X1085721Y239596D03*
X1075582Y233746D03*
X1072202Y239596D03*
X1083462Y356596D03*
X1086841Y370247D03*
X1073322Y358547D03*
X1083462Y364396D03*
X1093601Y354647D03*
X1090221Y360496D03*
X1080082Y358547D03*
X1093601Y381947D03*
X1090221Y387796D03*
X1073322Y393647D03*
X1083462Y383896D03*
X1073322Y378047D03*
X1080082Y389747D03*
X1086841Y378047D03*
X1090221Y376096D03*
X1093601Y374146D03*
X1064371Y367060D03*
X1076702Y364396D03*
X1073322Y370247D03*
X1080082Y374146D03*
X1076702Y383896D03*
X1093601Y370247D03*
X1076435Y343595D03*
X1086841Y366347D03*
X1073322D03*
X1083462Y372197D03*
X1093601Y362447D03*
X1090221Y356596D03*
X1080082Y366347D03*
Y362447D03*
X1087971Y346546D03*
X1081212D03*
X1077832Y348497D03*
X1084591D03*
X1093601Y389747D03*
X1090221Y383896D03*
X1073322Y389747D03*
X1083462Y387796D03*
X1073322Y381947D03*
X1080082D03*
X1076702Y391696D03*
Y387796D03*
X1080082Y370247D03*
X1076702Y379996D03*
X1109381Y218147D03*
X1133040Y216196D03*
X1129660Y218147D03*
X1133040Y212296D03*
X1129660Y210346D03*
X1144300Y212296D03*
X1147680Y214247D03*
X1144300Y216196D03*
X1147680Y218147D03*
X1154440D03*
X1157820Y216196D03*
X1151060D03*
X1154440Y214247D03*
X1106001Y220096D03*
X1116141Y225947D03*
X1102621Y222047D03*
Y225947D03*
X1112761Y220096D03*
Y227896D03*
X1109381Y229847D03*
X1116141Y241547D03*
X1112761Y235696D03*
X1119521Y243496D03*
Y235696D03*
X1106001D03*
X1102621Y241547D03*
X1099241Y231797D03*
Y243496D03*
Y235696D03*
X1107600Y271900D03*
X1114340Y280560D03*
X1151060Y251296D03*
X1126280Y220096D03*
X1133040Y231797D03*
X1122900Y222047D03*
Y225947D03*
X1133040Y220096D03*
X1129660Y229847D03*
X1126280Y235696D03*
X1122900Y241547D03*
X1157820Y243496D03*
X1133040Y239596D03*
X1136420Y261047D03*
X1133040Y262996D03*
X1151060Y255196D03*
X1147680Y261047D03*
X1144300Y259096D03*
X1151060Y262996D03*
X1147680Y253247D03*
Y257147D03*
X1134160Y272747D03*
X1109381Y264947D03*
X1129660Y249347D03*
X1109381D03*
X1126280Y247396D03*
X1102621Y249347D03*
X1116141D03*
X1129660Y257147D03*
X1122900Y253247D03*
X1133040Y247396D03*
Y255196D03*
X1136420Y253247D03*
X1140920Y280547D03*
X1157820Y274696D03*
X1154440Y268847D03*
X1140920Y272747D03*
X1154440Y280547D03*
Y276647D03*
X1147680D03*
X1140920D03*
X1154440Y272747D03*
X1147680D03*
X1151060Y270796D03*
X1144300Y220096D03*
X1154440Y237647D03*
X1147680Y241547D03*
X1157820Y227896D03*
X1147680Y229847D03*
X1109381Y257147D03*
X1112761Y255196D03*
X1102621Y253247D03*
X1106001Y255196D03*
X1144300Y274696D03*
X1106001Y227896D03*
X1116141Y222047D03*
X1109381D03*
Y225947D03*
X1116141Y233746D03*
X1112761Y239596D03*
X1119521Y231797D03*
Y239596D03*
X1106001D03*
X1102621Y233746D03*
X1099241Y239596D03*
X1102336Y274819D03*
X1101491Y265400D03*
X1104871Y267300D03*
X1098111Y263400D03*
X1116141Y268847D03*
X1112761Y262996D03*
X1116141Y261047D03*
X1119521Y278596D03*
X1126280Y227896D03*
X1133040D03*
X1129660Y225947D03*
Y222047D03*
X1126280Y239596D03*
X1122900Y233746D03*
X1144300Y223996D03*
X1154440Y225947D03*
X1147680Y245447D03*
Y249347D03*
Y280547D03*
X1137540Y266896D03*
X1147680Y268847D03*
X1137540Y270796D03*
X1140920Y268847D03*
Y264947D03*
X1144300Y262996D03*
X1126280Y266896D03*
X1129660Y264947D03*
X1122900D03*
Y268847D03*
X1126280Y262996D03*
X1154440Y261047D03*
X1127400Y280547D03*
Y276646D03*
X1134160Y280547D03*
X1157820Y266896D03*
X1151060Y278596D03*
X1154440Y264947D03*
X1119521Y266896D03*
Y262996D03*
X1134160Y276646D03*
X1157820Y247396D03*
X1154440Y249347D03*
X1151060Y220096D03*
X1154440Y233746D03*
X1144300Y227896D03*
X1151060Y235696D03*
X1144300Y239596D03*
X1151060Y243496D03*
Y239596D03*
X1144300Y266896D03*
X1108125Y276799D03*
X1157820Y251296D03*
X1154440Y257147D03*
X1122900Y261047D03*
X1119521Y259096D03*
X1147680Y264947D03*
X1154440Y222047D03*
X1147680Y237647D03*
X1144300Y231797D03*
X1129660Y245447D03*
X1109381D03*
X1122900Y249347D03*
X1112761Y247396D03*
X1106001D03*
X1129660Y253247D03*
X1109381D03*
X1126280Y255196D03*
X1116141Y253247D03*
X1136420Y249347D03*
X1157820Y235696D03*
X1151060Y227896D03*
Y231797D03*
X1114839Y320075D03*
X1157820Y309797D03*
X1134160Y303947D03*
X1130780Y321496D03*
X1137540Y313696D03*
X1130780Y325396D03*
X1140920Y315647D03*
X1134160Y319547D03*
X1130780Y317596D03*
Y333196D03*
X1134160Y331247D03*
X1144300Y290296D03*
X1147680Y292247D03*
X1154440D03*
X1157820Y282496D03*
X1154440Y288347D03*
Y284447D03*
X1144300Y282496D03*
X1157820Y286396D03*
X1137540D03*
X1140920Y288347D03*
Y284447D03*
X1147680D03*
Y288347D03*
X1151060Y286396D03*
X1137540Y301996D03*
X1151060Y337096D03*
X1120641Y339047D03*
X1154440Y311747D03*
X1157820Y305896D03*
X1154440Y303947D03*
X1157820Y301996D03*
X1154440Y300047D03*
X1119521Y282496D03*
Y301996D03*
X1113132Y291702D03*
X1119521Y298096D03*
Y294196D03*
Y290296D03*
Y309797D03*
X1113500Y323400D03*
X1119521Y313696D03*
Y317596D03*
X1109200Y325100D03*
X1118391Y332897D03*
X1134160Y307847D03*
X1151060Y294196D03*
X1147680Y300047D03*
Y296147D03*
X1140920Y307847D03*
Y311747D03*
X1151060Y301996D03*
X1144300Y305896D03*
X1147680Y311747D03*
X1157820Y298096D03*
X1127400Y284447D03*
Y300047D03*
X1130780Y294196D03*
X1127400Y296147D03*
Y292247D03*
X1130780Y298096D03*
Y305896D03*
X1137540Y290296D03*
X1134160Y296147D03*
Y288347D03*
X1147680Y307847D03*
X1151060Y309797D03*
Y305896D03*
X1144300Y301996D03*
Y298096D03*
X1137540D03*
X1140920Y303947D03*
X1137540Y305896D03*
X1140920Y296147D03*
X1137540Y294196D03*
X1127400Y311747D03*
X1154440Y296147D03*
X1134160Y335147D03*
Y339047D03*
X1140920Y319547D03*
X1144300Y317596D03*
X1137540Y321496D03*
X1134160Y327347D03*
X1137540Y325396D03*
X1124021D03*
X1127400Y323446D03*
X1124021Y329296D03*
Y333196D03*
X1154440Y327347D03*
X1147680Y339047D03*
X1157820Y321496D03*
X1130780Y329296D03*
X1140920Y323446D03*
X1144300Y313696D03*
X1151060D03*
X1144300Y325396D03*
Y321496D03*
X1151060Y329296D03*
X1147680Y335147D03*
Y331247D03*
X1140920Y335147D03*
X1144300Y333196D03*
X1151060Y325396D03*
Y321496D03*
X1147680Y323446D03*
X1137540Y329296D03*
X1144300D03*
X1140920Y327347D03*
X1130780Y340996D03*
Y337096D03*
X1127400Y331247D03*
Y335147D03*
Y339047D03*
X1147680Y315647D03*
X1151060Y317596D03*
X1137540Y337096D03*
Y340996D03*
Y333196D03*
X1130780Y282496D03*
Y286396D03*
X1134160Y311747D03*
Y315647D03*
Y284447D03*
X1113881Y370247D03*
X1100361D03*
X1103741Y360496D03*
X1100361Y354647D03*
Y362447D03*
X1113881Y354647D03*
X1110501Y356596D03*
Y360496D03*
X1096981Y356596D03*
X1117261D03*
X1096981Y364396D03*
X1117261D03*
X1107121Y366347D03*
X1103741Y387796D03*
X1100361Y381947D03*
X1113881Y389747D03*
X1110501Y383896D03*
X1117261Y379996D03*
X1096981Y391696D03*
X1117261Y383896D03*
Y387796D03*
X1103741Y376096D03*
X1110501D03*
X1124021Y368296D03*
X1130780Y364396D03*
X1124021Y360496D03*
X1120641Y354647D03*
Y362447D03*
X1140920Y354647D03*
X1137540Y356596D03*
X1124021Y383896D03*
X1120641Y389747D03*
X1144300Y399496D03*
X1130780Y383896D03*
Y387796D03*
X1140920Y393647D03*
X1137540Y379996D03*
Y383896D03*
Y387796D03*
X1134160Y374146D03*
X1120641D03*
X1127400D03*
X1157820Y383896D03*
X1156699Y401447D03*
X1127400Y370247D03*
X1147680D03*
X1157820Y364396D03*
X1110501Y344896D03*
X1107121Y350747D03*
X1113881Y342947D03*
X1154440Y370246D03*
X1151060Y372196D03*
X1157820D03*
X1140920Y342947D03*
Y401447D03*
X1154440Y374146D03*
X1147680D03*
X1124021Y344896D03*
X1127400Y350747D03*
X1120641Y346847D03*
X1151060Y376096D03*
X1157820Y368296D03*
X1144300Y379996D03*
Y387796D03*
X1157820Y376096D03*
X1144300Y383896D03*
X1147680Y381947D03*
Y378047D03*
X1103741Y368296D03*
X1110501D03*
X1103741Y356596D03*
X1113881Y362447D03*
X1107121Y370247D03*
X1096981Y352696D03*
X1117261D03*
X1096981Y360496D03*
X1117261D03*
X1101491Y342646D03*
X1098111Y344597D03*
X1113881Y346847D03*
X1103741Y383896D03*
X1113881Y381947D03*
X1110501Y387796D03*
X1096981Y383896D03*
X1117261Y391696D03*
X1096981Y379996D03*
Y387796D03*
X1113881Y374146D03*
X1100361D03*
X1107121Y378047D03*
Y374146D03*
X1134160Y358547D03*
X1120641Y370247D03*
X1130780Y368296D03*
X1127400Y366347D03*
X1124021Y356596D03*
X1157820D03*
X1144300Y352696D03*
X1154440Y350747D03*
Y362447D03*
X1144300Y368296D03*
X1120641Y342947D03*
X1137540Y352696D03*
X1130780Y356596D03*
X1134160Y342947D03*
Y354647D03*
Y350747D03*
X1137540Y348796D03*
Y344896D03*
X1124021Y387796D03*
X1120641Y381947D03*
X1134160Y389747D03*
X1144300Y395597D03*
X1137540Y391696D03*
X1124021Y376096D03*
X1130780D03*
X1127400Y378047D03*
X1157820Y379996D03*
X1147680Y389747D03*
X1144300Y376096D03*
X1151060Y383896D03*
X1130780Y348796D03*
X1127400Y346847D03*
X1154440Y397546D03*
Y385847D03*
X1157820Y391696D03*
X1154440Y389747D03*
X1157820Y395597D03*
X1151060Y387796D03*
X1154440Y393647D03*
X1134160Y381947D03*
X1100361Y389747D03*
X1097343Y588394D03*
X1097374Y612659D03*
X1208519Y218147D03*
X1191619Y212296D03*
X1167960Y214247D03*
X1164580Y208397D03*
X1181479Y214247D03*
X1194999Y218147D03*
X1174719Y214247D03*
X1161200D03*
X1171339Y216196D03*
X1178099Y204496D03*
X1174719Y202547D03*
X1209033Y183907D03*
X1181479Y218147D03*
X1191619Y208397D03*
X1188239Y202247D03*
X1181479Y202547D03*
X1198379Y216196D03*
X1188239Y218147D03*
X1184859Y212296D03*
X1181479Y210346D03*
X1184859Y216196D03*
X1174719Y210346D03*
X1164580Y212296D03*
X1184859Y208397D03*
X1178099Y212296D03*
X1194999Y214247D03*
X1191619Y216196D03*
X1171339Y212296D03*
X1167960Y210346D03*
X1164580Y216196D03*
X1178099Y223996D03*
X1174719Y241547D03*
X1178099Y239596D03*
X1174719Y245447D03*
X1178099Y251296D03*
X1171339Y270796D03*
X1178099Y266896D03*
Y262996D03*
X1191619Y223996D03*
X1181479Y253247D03*
X1164580Y243496D03*
Y274696D03*
X1167960Y280547D03*
X1171339Y262996D03*
X1174719Y264947D03*
X1171339Y278596D03*
X1161200Y276646D03*
Y280547D03*
X1167960Y268847D03*
X1188239D03*
X1205139Y278596D03*
X1184859Y227896D03*
X1198379Y223996D03*
X1188239Y245447D03*
X1194999Y229847D03*
X1178099Y231797D03*
X1171339Y227896D03*
X1174719Y222047D03*
X1208519Y253247D03*
X1205139Y262996D03*
X1181479Y280547D03*
X1191619Y235696D03*
X1164580Y231797D03*
X1205139Y270796D03*
X1198379Y274696D03*
X1201759Y253247D03*
X1194999Y261047D03*
X1188239Y253247D03*
X1181479Y245447D03*
X1212199Y227896D03*
X1184859Y220096D03*
X1205139Y223996D03*
X1161200Y237647D03*
X1205139Y243496D03*
Y235696D03*
Y255196D03*
X1208519Y229847D03*
X1171339Y251296D03*
X1167960Y222047D03*
X1164580Y220096D03*
X1167960Y233746D03*
X1161200Y222047D03*
X1167960Y249347D03*
Y241547D03*
Y245447D03*
Y237647D03*
X1171339Y239596D03*
Y243496D03*
X1174719Y249347D03*
X1167960Y257147D03*
X1161200Y268847D03*
X1164580Y255196D03*
X1161200Y272747D03*
X1178099Y270796D03*
Y278596D03*
X1162300Y264947D03*
X1178099Y255196D03*
X1161200Y253247D03*
X1174719Y268847D03*
Y276646D03*
X1167960D03*
Y264947D03*
X1181479Y249347D03*
Y237647D03*
Y241547D03*
X1184859Y223996D03*
X1201759Y237647D03*
X1198379Y227896D03*
X1205139Y231797D03*
X1201759Y245447D03*
X1194999Y237647D03*
X1198379Y251296D03*
X1181479Y264947D03*
X1184859Y255196D03*
X1191619Y270796D03*
X1198379Y262996D03*
X1194999Y276646D03*
X1198379Y270796D03*
X1181479Y257147D03*
X1174719Y272747D03*
X1164580Y251296D03*
X1167960Y261047D03*
X1161200Y225947D03*
X1181479D03*
Y233746D03*
Y229847D03*
X1184859Y270796D03*
X1191619Y278596D03*
X1205139Y259096D03*
X1212199Y223996D03*
Y231797D03*
X1205139Y239596D03*
X1208519Y237647D03*
X1205139Y220096D03*
X1191619D03*
X1184859Y243496D03*
X1194999Y241547D03*
Y245447D03*
Y253247D03*
X1191619Y251296D03*
Y231797D03*
X1188239Y233746D03*
Y229847D03*
X1174719Y225947D03*
X1171339Y223996D03*
X1161200Y229847D03*
X1201759Y222047D03*
X1198379Y220096D03*
X1174719Y233746D03*
X1167960Y225947D03*
X1174719Y229847D03*
X1188239Y264947D03*
Y272747D03*
X1208519Y241547D03*
X1205139Y251296D03*
X1208519Y257147D03*
X1201759Y264947D03*
X1191619Y255196D03*
X1198379Y259096D03*
X1191619Y262996D03*
X1188239Y261047D03*
X1191619Y266896D03*
X1184859Y274696D03*
X1205139Y266896D03*
X1208519Y268847D03*
X1201759D03*
Y276646D03*
X1184859Y231797D03*
X1208519Y225947D03*
X1191619Y227896D03*
X1174719Y257147D03*
X1178099Y259096D03*
X1161200Y245447D03*
X1174719Y261047D03*
X1167960Y272747D03*
X1171339Y255196D03*
X1181479Y272747D03*
X1201759D03*
Y280547D03*
X1208519Y249347D03*
X1194999Y257147D03*
X1198379Y247396D03*
X1184859Y278596D03*
X1188239Y276646D03*
Y280547D03*
X1198379Y231797D03*
X1205139Y227896D03*
X1191619Y259096D03*
X1194999Y249347D03*
X1184859Y262996D03*
X1161200Y233746D03*
X1191619Y243496D03*
X1188239Y241547D03*
X1212199Y239596D03*
X1181479Y331247D03*
X1198379Y321496D03*
X1194999Y323446D03*
X1181479Y315647D03*
X1191619Y337096D03*
X1181479Y323446D03*
X1171339Y337096D03*
X1174719Y331247D03*
X1178099Y321496D03*
X1174719Y327347D03*
X1167960Y335147D03*
X1171339Y329296D03*
X1178099Y333196D03*
Y325396D03*
X1171339Y333196D03*
X1178099Y329296D03*
X1174719Y319547D03*
X1171339Y282496D03*
X1167960Y284447D03*
X1164580Y282496D03*
X1184859Y298096D03*
X1191619Y313696D03*
X1188239Y300047D03*
X1191619Y340996D03*
X1188239Y331247D03*
Y327347D03*
X1194999Y311747D03*
X1184859Y305896D03*
X1188239Y296147D03*
X1181479D03*
X1191619Y325396D03*
X1188239Y307847D03*
X1208819Y284447D03*
X1174719Y323446D03*
X1161200Y288347D03*
Y292247D03*
X1201759D03*
X1171339Y340996D03*
X1174719Y292247D03*
Y288347D03*
X1171339Y286396D03*
Y290296D03*
X1167960Y300047D03*
X1164580Y298096D03*
X1167960Y296147D03*
Y292247D03*
Y288347D03*
X1161200Y296147D03*
X1178099Y290296D03*
X1161200Y311747D03*
Y300047D03*
Y303947D03*
X1174719D03*
X1167960D03*
X1178099Y309797D03*
X1171339Y305896D03*
X1164580Y309797D03*
Y305896D03*
X1167960Y307847D03*
Y311747D03*
X1171339Y309797D03*
X1178099Y301996D03*
X1174719Y311747D03*
Y307847D03*
X1178099Y305896D03*
X1171339Y298096D03*
Y294196D03*
X1174719Y296147D03*
Y339047D03*
X1164580Y340996D03*
X1167960Y331247D03*
X1171339Y321496D03*
X1178099Y313696D03*
X1171339D03*
X1164580D03*
X1198379Y282496D03*
X1184859Y325396D03*
Y333196D03*
X1198379Y337096D03*
Y329296D03*
X1181479Y339047D03*
X1178099Y340996D03*
X1205139D03*
X1201759Y339047D03*
X1198379Y333196D03*
X1201759Y335147D03*
Y331247D03*
X1184859Y337096D03*
X1191619Y309797D03*
X1188239Y303947D03*
X1194999Y327347D03*
X1184859Y317596D03*
X1191619D03*
Y305896D03*
Y301996D03*
X1184859Y340996D03*
X1194999Y339047D03*
X1191619Y333196D03*
Y329296D03*
X1188239Y323446D03*
X1184859Y313696D03*
X1188239Y315647D03*
X1198379Y290296D03*
Y294196D03*
X1205439Y286596D03*
X1181479Y284447D03*
X1205439Y294196D03*
X1191619Y282496D03*
Y290296D03*
X1205439D03*
X1191619Y286396D03*
X1178099Y282496D03*
X1205139D03*
X1184859D03*
X1194999Y284447D03*
X1184859Y286396D03*
X1161201Y401447D03*
X1178099Y368296D03*
X1164580Y391696D03*
X1171339Y352696D03*
X1164580Y364396D03*
X1167960Y350747D03*
X1161200Y362447D03*
Y358547D03*
X1178099Y352696D03*
X1164580Y376096D03*
X1194999Y350747D03*
X1198379Y348796D03*
X1184859Y379996D03*
X1188239Y350747D03*
X1191619Y356596D03*
X1184859Y372197D03*
X1181479Y366347D03*
Y362447D03*
X1188239D03*
Y358547D03*
Y354647D03*
X1198379Y383896D03*
X1191619Y379996D03*
X1184859Y376096D03*
X1198379D03*
X1171339Y391696D03*
X1191619Y344896D03*
X1178099Y376096D03*
X1171339Y395596D03*
X1174719Y389747D03*
X1171339Y383896D03*
X1161200Y389747D03*
X1164580Y395597D03*
X1178099Y387796D03*
X1167960Y346847D03*
X1164580Y360496D03*
X1161200Y366347D03*
X1167960Y354647D03*
X1161200D03*
X1164580Y368296D03*
X1181479Y378047D03*
X1188239Y374146D03*
X1184859Y368296D03*
Y364396D03*
X1181479Y358547D03*
X1184859Y360496D03*
X1174719Y346847D03*
X1178099Y348796D03*
Y344896D03*
X1167960Y358547D03*
X1171339Y344896D03*
X1174719Y350747D03*
X1167960Y366347D03*
X1171339Y368296D03*
X1161200Y374146D03*
X1178099Y391696D03*
X1174719Y397546D03*
X1164580Y399496D03*
X1188239Y370247D03*
X1191619Y372197D03*
Y364396D03*
Y352696D03*
X1194999Y342947D03*
X1181479Y385847D03*
X1188239Y381947D03*
X1208819Y385847D03*
X1181479Y393647D03*
X1184859Y399496D03*
X1178099Y395596D03*
X1174719Y401447D03*
X1198379Y356596D03*
Y360496D03*
X1181479Y370247D03*
X1174719D03*
X1178099Y360496D03*
X1191619Y383896D03*
X1167960Y381947D03*
X1181479Y342947D03*
X1201759Y346847D03*
X1198379Y344896D03*
X1201759Y342947D03*
X1184859Y387796D03*
X1188239Y385847D03*
Y389747D03*
X1194999Y370247D03*
X1184859Y391696D03*
Y395596D03*
X1181479Y397546D03*
X1178099Y399496D03*
X1171339Y403396D03*
X1198379Y352696D03*
X1201759Y358547D03*
X1194999Y362447D03*
X1198379Y372197D03*
Y364396D03*
X1167960Y401447D03*
X1194999Y374146D03*
X1171339Y364396D03*
X1201759Y374146D03*
X1194999Y378047D03*
X1178099Y372197D03*
X1171339Y376096D03*
X1167960Y374146D03*
X1171339Y379996D03*
X1164580Y383896D03*
X1161200Y381947D03*
X1181479Y350747D03*
Y354647D03*
X1174719Y358547D03*
Y362447D03*
Y366347D03*
X1178099Y356596D03*
X1184859Y348796D03*
X1174719Y374146D03*
Y378047D03*
X1167960D03*
X1188239Y346847D03*
Y342947D03*
X1181479Y381947D03*
X1167960Y385847D03*
X1161200D03*
X1164580Y387796D03*
X1174719Y385847D03*
X1178099Y383896D03*
Y379996D03*
X1161200Y393647D03*
X1184859Y352696D03*
X1198379Y379996D03*
X1194999Y381947D03*
X1167960Y393647D03*
X1184859Y344896D03*
X1171339Y387796D03*
X1181479Y405347D03*
X1174719D03*
X1167960D03*
X1251771Y27899D03*
X1248425Y17057D03*
X1258464Y27899D03*
X1261811D03*
Y16999D03*
X1258464D03*
X1265157Y27899D03*
Y16999D03*
Y9157D03*
X1251771D03*
Y-1743D03*
X1261811Y-9901D03*
X1258464D03*
X1261811Y-1743D03*
X1265157D03*
X1258464D03*
X1265157Y-9901D03*
X1276346Y-10250D03*
X1255118Y-9901D03*
Y-1743D03*
Y27899D03*
Y16999D03*
Y9157D03*
X1251771Y36057D03*
Y54799D03*
X1248425Y54857D03*
X1251771Y46957D03*
X1258464D03*
Y36057D03*
Y54799D03*
X1261811Y46957D03*
Y54799D03*
X1265157Y36057D03*
X1261811D03*
Y65699D03*
X1258464D03*
X1265157D03*
X1268111Y58040D03*
X1251771Y84757D03*
X1248425Y92657D03*
X1265157Y73857D03*
X1261811D03*
X1258464D03*
X1261811Y84757D03*
X1258464D03*
X1265157D03*
X1251771Y73857D03*
X1261811Y92599D03*
X1258464D03*
X1255118Y65699D03*
Y54799D03*
Y36057D03*
Y46957D03*
X1265157Y54799D03*
X1255118Y92599D03*
Y84757D03*
Y73857D03*
X1265157Y92599D03*
X1243948Y154916D03*
X1251344Y127925D03*
X1277100Y122670D03*
X1264550Y114670D03*
X1277100Y114800D03*
X1261030Y105350D03*
X1270350Y98300D03*
X1277600Y106200D03*
X1268576Y117788D03*
X1275470Y99390D03*
X1237704Y148423D03*
X1269810Y154398D03*
X1249025Y130460D03*
X1272100Y141603D03*
X1255400Y108000D03*
X1259950Y144650D03*
X1240000Y129500D03*
X1248616Y133817D03*
X1262569Y147201D03*
X1252000Y145300D03*
X1252437Y140192D03*
X1251980Y106960D03*
X1250200Y122900D03*
X1257800Y120800D03*
X1221767Y175858D03*
X1233902Y173337D03*
X1240309Y161900D03*
X1267050Y169800D03*
X1241381Y172040D03*
X1246655Y176395D03*
X1263300Y169450D03*
X1259200Y168350D03*
X1267800Y161800D03*
X1271400Y161900D03*
X1220580Y179810D03*
X1268404Y246304D03*
X1277504Y250346D03*
X1272761Y240220D03*
X1270478Y243490D03*
X1279393Y247602D03*
X1249230Y402022D03*
X1262700Y461804D03*
X1277978Y491571D03*
X1258140Y474540D03*
X1271571Y479000D03*
X1271662Y487326D03*
X1271640Y474420D03*
X1271647Y482500D03*
X1265157Y510157D03*
X1261811Y517999D03*
X1258464Y510157D03*
Y517999D03*
X1261811Y510157D03*
X1248425Y518057D03*
X1251771Y510157D03*
X1262843Y497553D03*
X1278573Y519596D03*
X1274576Y510235D03*
X1271105Y498516D03*
X1271300Y510600D03*
X1255120Y510158D03*
Y518000D03*
X1265157Y517999D03*
X1262900Y466504D03*
X1256320Y490660D03*
X1258126Y469540D03*
X1256350Y486080D03*
X1255120Y574834D03*
X1265157Y547957D03*
X1261811D03*
X1258464D03*
X1251771D03*
X1265157Y537057D03*
X1261811D03*
X1258464Y528899D03*
X1251771Y537057D03*
X1258464D03*
X1261811Y528899D03*
X1265157Y528876D03*
X1277200Y539100D03*
X1265157Y585757D03*
X1261811D03*
X1258464D03*
X1251771D03*
X1261811Y555799D03*
X1258464D03*
X1251771D03*
X1248425Y555857D03*
X1251771Y566699D03*
Y574857D03*
X1265157D03*
X1261811D03*
X1258464D03*
X1261811Y566699D03*
X1258464D03*
X1273200Y582200D03*
X1265157Y566676D03*
Y555799D03*
X1255120Y537034D03*
Y555144D03*
X1265157Y604476D03*
Y593599D03*
X1270400Y593600D03*
X1258464Y593599D03*
X1261811D03*
X1248425Y593657D03*
X1251771Y612657D03*
X1258464Y604499D03*
X1261811D03*
X1265157Y612657D03*
X1261811D03*
X1258464D03*
X1255120Y612634D03*
Y593600D03*
X1303774Y-18842D03*
X1287700Y-16700D03*
X1292692Y1008D03*
X1293600Y-17000D03*
X1293816Y-13533D03*
X1336500Y81100D03*
X1327168Y61483D03*
X1296935Y51335D03*
X1296908Y36900D03*
X1298422Y74000D03*
X1298754Y83233D03*
X1301219Y89141D03*
X1304500Y40066D03*
X1324127Y50827D03*
X1327452Y55544D03*
X1327500Y51547D03*
X1309700Y83300D03*
X1304685Y78827D03*
X1336850Y76450D03*
X1330300Y83500D03*
X1308400Y79600D03*
X1323000Y83000D03*
X1335120Y94450D03*
X1337400Y72000D03*
X1328500Y92500D03*
X1336900Y61600D03*
X1325100Y145000D03*
X1327900Y142918D03*
X1310175Y154696D03*
X1293700Y121800D03*
X1287790Y156575D03*
X1295700Y144450D03*
X1338500Y96000D03*
X1325125Y100001D03*
X1301770Y101300D03*
X1310098Y150040D03*
X1306900Y131744D03*
X1301900Y124400D03*
X1320500Y145000D03*
X1315180Y169950D03*
X1315130Y164870D03*
X1295500Y159970D03*
X1299907Y159808D03*
X1330100Y165000D03*
Y170000D03*
X1340100Y165000D03*
Y170000D03*
X1335100D03*
Y165000D03*
X1320100D03*
X1325100D03*
X1320100Y170000D03*
X1325100D03*
X1310061Y165235D03*
X1305171Y164767D03*
X1323030Y216531D03*
X1338224Y209051D03*
X1326474Y216500D03*
X1300300Y169900D03*
X1281799Y193190D03*
X1283720Y223870D03*
X1288800Y233900D03*
X1300444Y267919D03*
X1336900Y232118D03*
X1325900D03*
X1314900D03*
X1342400D03*
X1331400D03*
X1320400D03*
X1309462Y240229D03*
X1315100Y237645D03*
X1325900Y237900D03*
X1342400D03*
X1331400D03*
X1320289Y237671D03*
X1336900Y237900D03*
X1319310Y300795D03*
X1335400Y284900D03*
X1336240Y301243D03*
X1341740D03*
X1323688Y290205D03*
X1306290Y298255D03*
X1302768Y296942D03*
X1338700Y284700D03*
X1302203Y314439D03*
X1331720Y334810D03*
X1326300Y341309D03*
X1320900Y321300D03*
X1323750Y319750D03*
X1331650Y317250D03*
X1336240Y306760D03*
X1341740D03*
X1319888Y290205D03*
X1341375Y314675D03*
Y319675D03*
X1308887Y285015D03*
X1316600Y305500D03*
X1336336Y333825D03*
X1326014Y347732D03*
X1342570Y368220D03*
X1315496Y361190D03*
X1335250Y344250D03*
X1335100Y427500D03*
X1329419Y464337D03*
X1318054Y460507D03*
X1296468Y437500D03*
X1300438Y433001D03*
X1300315Y427902D03*
X1340100Y432500D03*
X1335100D03*
X1325100Y457500D03*
Y452500D03*
X1320100Y457500D03*
Y452500D03*
X1315100D03*
X1310100D03*
X1315100Y457500D03*
X1305100D03*
Y452500D03*
X1310100Y457500D03*
X1330100D03*
Y452500D03*
X1304200Y462030D03*
X1322360Y472592D03*
X1322260Y477492D03*
X1299450Y484950D03*
X1304200Y466600D03*
X1320300Y498300D03*
X1341050Y498275D03*
X1340986Y511187D03*
X1309870Y499254D03*
X1329419Y469337D03*
X1287770Y501897D03*
X1308500Y540784D03*
X1305500Y542500D03*
X1318500Y539900D03*
X1327956Y545655D03*
X1324707Y545493D03*
X1316100Y543400D03*
X1296295Y615596D03*
X1301384Y618119D03*
X1376094Y4406D03*
X1380678Y-422D03*
X1380950Y30232D03*
X1400616Y13795D03*
X1379025Y-9799D03*
X1371500Y63200D03*
X1347000Y87500D03*
X1343500D03*
X1360700Y86550D03*
X1351500Y83000D03*
X1377009Y39753D03*
X1367700Y86450D03*
X1359500Y83000D03*
X1355500D03*
X1370975Y67225D03*
X1343260Y53770D03*
X1351488Y74000D03*
X1358500Y74500D03*
X1347500Y83000D03*
X1357000Y86640D03*
X1383171Y57549D03*
X1371910Y48800D03*
X1370849Y59349D03*
X1372300Y86400D03*
X1363500Y77400D03*
X1404200Y119200D03*
X1371500Y101000D03*
X1388100Y108500D03*
X1381359Y108496D03*
X1384600Y108500D03*
X1401300Y149600D03*
X1402500Y116300D03*
X1345257Y100000D03*
X1348615Y96239D03*
X1353500Y96959D03*
X1380100Y165000D03*
X1350100Y170000D03*
X1355100D03*
X1360100D03*
X1355100Y165000D03*
X1360100D03*
X1345100D03*
X1350100D03*
X1345100Y170000D03*
X1344462Y209272D03*
X1365100Y170000D03*
Y165000D03*
X1370100D03*
X1375100Y170000D03*
X1370100D03*
X1375100Y165000D03*
X1380100Y170000D03*
X1402020Y165561D03*
X1399100Y166900D03*
X1384671Y214832D03*
X1367789Y209216D03*
X1396933Y215763D03*
X1353569Y208960D03*
X1348569D03*
X1399852Y252353D03*
X1358900Y232118D03*
X1347900D03*
X1353400D03*
X1345050Y272350D03*
X1380900Y232118D03*
X1369900D03*
X1375400D03*
X1364400D03*
X1375400Y237900D03*
X1364400D03*
X1353400D03*
X1391900D03*
X1380900D03*
X1369900D03*
X1358900D03*
X1347900D03*
X1347892Y299741D03*
X1369320Y301219D03*
X1358514Y300815D03*
X1392135Y302051D03*
X1380601Y301465D03*
X1364260Y331619D03*
X1388450Y331250D03*
X1392400Y330800D03*
X1400400Y335400D03*
X1353672Y299605D03*
X1345700Y285300D03*
X1355300Y321675D03*
X1359200Y322200D03*
X1397635Y302051D03*
X1386101Y301465D03*
X1374820Y301219D03*
X1364014Y300815D03*
X1368200Y284000D03*
X1365246Y285931D03*
X1352400Y285000D03*
X1367200Y321600D03*
X1363700D03*
X1400558Y316357D03*
X1403037Y307630D03*
X1360294Y315025D03*
X1371090Y315395D03*
X1380904Y315947D03*
X1392226Y315658D03*
X1349134Y321145D03*
X1392135Y307630D03*
X1380548Y307310D03*
X1369340Y307130D03*
X1358544Y306690D03*
X1347642Y306760D03*
X1397635Y307630D03*
X1386048Y307310D03*
X1374840Y307130D03*
X1364044Y306690D03*
X1353142Y306760D03*
X1392226Y319458D03*
X1349134Y317436D03*
X1400558Y320157D03*
X1380904Y319747D03*
X1371090Y319195D03*
X1360294Y318825D03*
X1396470Y330014D03*
X1381431Y284259D03*
X1394370Y384230D03*
X1394260Y351170D03*
X1389500Y360500D03*
X1388300Y346200D03*
X1380900Y383164D03*
X1371600Y368700D03*
X1378200Y346900D03*
X1378207Y394568D03*
X1391845Y348325D03*
X1388900Y387800D03*
X1380872Y378098D03*
X1390100Y432500D03*
X1377028Y458125D03*
X1375100Y447500D03*
X1390100Y452500D03*
X1372028Y458125D03*
X1385100Y427500D03*
Y442500D03*
Y437500D03*
Y452500D03*
Y447500D03*
X1389900Y427400D03*
X1385100Y432500D03*
X1395100Y427500D03*
Y432500D03*
X1389900Y447400D03*
X1349800Y458200D03*
X1350100Y447500D03*
Y452500D03*
X1360100Y447500D03*
Y452500D03*
Y457500D03*
X1362560Y463478D03*
X1365100Y432500D03*
Y427500D03*
X1370100Y447500D03*
X1365100Y437500D03*
X1380100Y442500D03*
Y437500D03*
X1370100D03*
X1375100D03*
Y452500D03*
X1370100D03*
X1390100Y457500D03*
X1395100Y447500D03*
X1403027Y520231D03*
X1395242Y520301D03*
X1396035Y514863D03*
X1386241Y487323D03*
Y482623D03*
X1388719Y498745D03*
X1383263Y493673D03*
X1347546Y476897D03*
X1350500Y475100D03*
X1354462Y474141D03*
X1347196Y472941D03*
X1355800Y508500D03*
X1344761Y498282D03*
X1368441Y497523D03*
X1366309Y486618D03*
X1366341Y481823D03*
X1360741Y486523D03*
X1381041Y482575D03*
X1362841Y492823D03*
X1380741Y487489D03*
X1388741Y493623D03*
X1383241Y498595D03*
X1368441Y492723D03*
X1362880Y497556D03*
X1360863Y481673D03*
X1347081Y507919D03*
X1396158Y537595D03*
X1399721Y537509D03*
X1390595Y549328D03*
X1379053Y581864D03*
X1386921Y620689D03*
X1390851D03*
X1380890Y615820D03*
X1375600Y589700D03*
X1382100Y592800D03*
X1382000Y589500D03*
X1410600Y9100D03*
X1407422Y13139D03*
X1420337Y45477D03*
X1416837D03*
X1411546Y43116D03*
X1406546D03*
X1425081Y48412D03*
X1453700Y83750D03*
X1457000Y82000D03*
X1451021Y151626D03*
X1438348Y155908D03*
X1422196Y218052D03*
X1446331Y197285D03*
X1458569Y192143D03*
X1408247Y206270D03*
X1451366Y165296D03*
X1447999Y205645D03*
X1458908Y187699D03*
X1444850Y242730D03*
X1426658Y274252D03*
X1455600Y254826D03*
X1441750Y236800D03*
X1464150Y235550D03*
X1407274Y245652D03*
X1461348Y244350D03*
X1466006Y265300D03*
X1447154Y251710D03*
X1422281Y221479D03*
X1452200Y254500D03*
X1452728Y243306D03*
X1458318Y243000D03*
X1426905Y267045D03*
X1448500Y257700D03*
X1430365Y262624D03*
X1433057Y257388D03*
X1459548Y221731D03*
X1461400Y264700D03*
X1408250Y333000D03*
X1443500Y327900D03*
X1444311Y324366D03*
X1419220Y301983D03*
X1408537Y302046D03*
X1419333Y307598D03*
X1413387Y316233D03*
X1413720Y307634D03*
X1408537Y307630D03*
X1413387Y320033D03*
X1463610Y321329D03*
X1462776Y318200D03*
X1440910Y316693D03*
X1458400Y318500D03*
X1463870Y367869D03*
X1453900Y353350D03*
X1413400Y361300D03*
X1456000Y360700D03*
X1464400Y390800D03*
X1450400Y354300D03*
X1460400Y353000D03*
X1459111Y356353D03*
X1453251Y356676D03*
X1452699Y404060D03*
X1444400Y371600D03*
X1420515Y373585D03*
Y368585D03*
X1457300Y373600D03*
X1420075Y378375D03*
Y393402D03*
Y383375D03*
Y388402D03*
X1413735Y396302D03*
Y391302D03*
X1458300Y442675D03*
X1414107Y447267D03*
X1448000Y431500D03*
X1431900Y453500D03*
X1447500Y448000D03*
X1431900Y442600D03*
X1448000Y437000D03*
X1431900Y448000D03*
X1447700Y442500D03*
X1431900Y437100D03*
X1460661Y484891D03*
X1461267Y489790D03*
X1418241Y489523D03*
X1418441Y482523D03*
X1441842Y482924D03*
X1442041Y494423D03*
X1431690Y521530D03*
X1458060Y495020D03*
X1428500Y521000D03*
X1436396Y477691D03*
X1413041Y477423D03*
X1412941Y489523D03*
X1464553Y508872D03*
X1436441Y489323D03*
X1412741Y494223D03*
X1436541Y494423D03*
X1436600Y482900D03*
X1413193Y482532D03*
X1410486Y529792D03*
X1441252Y548631D03*
X1451150Y569900D03*
Y573200D03*
X1436160Y561200D03*
X1441409Y561117D03*
X1425243Y562260D03*
X1451533Y527867D03*
X1413600Y531300D03*
X1432560Y561160D03*
X1428791Y535512D03*
X1419600Y531500D03*
X1453533Y532667D03*
X1426870Y530800D03*
X1423800Y534800D03*
X1421560Y563455D03*
X1439822Y537382D03*
X1428281Y546119D03*
X1429026Y541026D03*
X1460200Y606200D03*
X1410950Y589670D03*
X1506300Y-6600D03*
X1477100Y2400D03*
X1504400Y20300D03*
X1513700Y7082D03*
X1520700Y7100D03*
X1481600Y5300D03*
X1522600Y-6500D03*
X1485242Y4589D03*
X1501900Y-9124D03*
X1521092Y21665D03*
X1470862Y38209D03*
X1524557Y88336D03*
X1519599Y86117D03*
X1524744Y133656D03*
X1482455Y124222D03*
X1474717Y110370D03*
X1475200Y142600D03*
X1476761Y152725D03*
X1524284Y112773D03*
X1518514Y130991D03*
X1518438Y100926D03*
X1490178Y112315D03*
X1518376Y111499D03*
X1502000Y147500D03*
X1513136Y157081D03*
X1500643Y154819D03*
X1496038Y154229D03*
X1503466Y142486D03*
X1510184Y142614D03*
X1505673Y146346D03*
X1496658Y115088D03*
X1514425Y134180D03*
X1524900Y139100D03*
X1484113Y128513D03*
X1500700Y127250D03*
X1483366Y120746D03*
X1473354Y153246D03*
X1485210Y134837D03*
X1490674Y98787D03*
X1496726Y120588D03*
X1526310Y142190D03*
X1485755Y131671D03*
X1500806Y133339D03*
X1483366Y115902D03*
X1520150Y127600D03*
X1500703Y158233D03*
X1507524Y218600D03*
X1510800Y193330D03*
X1512500Y199837D03*
X1492136Y199125D03*
X1512700Y205100D03*
X1497237Y217281D03*
X1519243Y191627D03*
X1513900Y218000D03*
X1478089Y182650D03*
X1511100Y186275D03*
X1515060Y192443D03*
X1487716Y218650D03*
X1470382Y188372D03*
X1472758Y216495D03*
X1510638Y166240D03*
X1468700Y163100D03*
X1476761Y157400D03*
X1496713Y174853D03*
X1493200Y162700D03*
X1488300Y161700D03*
X1497493Y162078D03*
X1494939Y159500D03*
X1488900Y172576D03*
X1512525Y208944D03*
X1516872Y208863D03*
X1504706Y164871D03*
X1488300Y158300D03*
X1477388Y172988D03*
X1474883Y182275D03*
X1492597Y172636D03*
X1527657Y278700D03*
X1467040Y260357D03*
X1470556Y256900D03*
X1472200Y243000D03*
X1498022Y221900D03*
X1484000Y257500D03*
X1496812Y273718D03*
X1491265Y226492D03*
X1519300Y245196D03*
X1491438Y221137D03*
X1523580Y237960D03*
X1503842Y245678D03*
X1499070Y255934D03*
X1504772Y259229D03*
X1507003Y272249D03*
X1504461Y274426D03*
X1521962Y278650D03*
X1526150Y234300D03*
X1479700Y224801D03*
X1482004Y222483D03*
X1497082Y277987D03*
X1474096Y256706D03*
X1483457Y244568D03*
X1484700Y251800D03*
X1487500Y244500D03*
X1492697Y267303D03*
X1475004Y246287D03*
X1492753Y273724D03*
X1499681Y279910D03*
X1512790Y240099D03*
X1516549Y234278D03*
X1486926Y247834D03*
X1470950Y229669D03*
X1516613Y240656D03*
X1520413Y239498D03*
X1482400Y248000D03*
X1474520Y251740D03*
X1525650Y248700D03*
X1505946Y254432D03*
X1469829Y266909D03*
X1489546Y279902D03*
X1486574Y267127D03*
X1496030Y267665D03*
X1500840Y319870D03*
X1517115Y330005D03*
X1470276Y330774D03*
X1468399Y324930D03*
X1470257Y321929D03*
X1466970Y320235D03*
X1526936Y307015D03*
X1473231Y320250D03*
X1484100Y330115D03*
X1499829Y341250D03*
X1482550Y333600D03*
X1520766Y341000D03*
X1505000Y340990D03*
X1510851Y340113D03*
X1504370Y330970D03*
X1518060Y317520D03*
X1525677Y311835D03*
X1510584Y330640D03*
X1483506Y326061D03*
X1514100Y321792D03*
X1514067Y315626D03*
X1493290Y287984D03*
X1526900Y292866D03*
X1496900Y293900D03*
X1493268Y293943D03*
X1508650Y287500D03*
X1496628Y288440D03*
X1499987Y288487D03*
X1518006Y286706D03*
X1501550Y293750D03*
X1471562Y325531D03*
X1487000Y333300D03*
X1523935Y318901D03*
X1497179Y306372D03*
X1499723Y300106D03*
X1508455Y313041D03*
X1503538Y318068D03*
X1512182Y293317D03*
X1493400Y300800D03*
X1497509Y303120D03*
X1495300Y297300D03*
X1478524Y318900D03*
X1493500Y304400D03*
X1524575Y387654D03*
X1503878Y364717D03*
X1487525Y384274D03*
X1505075Y394414D03*
X1501175Y387654D03*
X1505075Y401174D03*
X1501175D03*
X1522625Y391034D03*
X1495325Y397794D03*
X1499225D03*
X1493375Y401174D03*
X1489475D03*
X1507025Y384274D03*
X1501175Y380894D03*
X1522625Y397794D03*
X1507025Y377514D03*
X1518725Y384274D03*
X1510925Y397794D03*
X1483868Y390233D03*
X1516775Y394414D03*
X1510925Y377514D03*
X1512875Y380894D03*
X1518725Y377514D03*
X1522625Y384274D03*
X1510925Y391034D03*
X1512875Y387654D03*
X1510925Y384274D03*
X1489475Y380894D03*
X1493375D03*
X1487525Y397794D03*
Y377514D03*
X1505075Y387654D03*
X1499225Y377514D03*
X1473255Y372654D03*
X1502970Y350610D03*
X1520675Y394414D03*
X1472940Y384030D03*
X1467597Y363000D03*
X1469000Y345850D03*
X1489475Y387654D03*
X1514265Y355542D03*
X1495325Y391034D03*
X1493375Y387654D03*
X1495325Y377514D03*
X1524575Y394414D03*
X1525561Y350253D03*
X1511000Y350627D03*
X1481000Y350000D03*
X1516775Y380894D03*
X1526659Y397500D03*
X1524575Y380894D03*
X1522476Y361907D03*
X1522625Y377514D03*
X1518725Y397794D03*
Y391034D03*
X1512875Y401174D03*
Y394414D03*
X1514925Y358844D03*
X1484600Y394100D03*
X1495325Y384274D03*
X1483664Y362914D03*
X1520675Y401174D03*
X1516775D03*
X1515328Y363389D03*
X1516775Y387654D03*
X1478163Y354940D03*
X1507025Y391034D03*
X1501175Y394414D03*
X1499225Y391034D03*
Y384274D03*
X1493375Y394414D03*
X1489475D03*
X1496000Y350000D03*
X1505075Y380894D03*
X1517367Y349964D03*
X1505075Y463826D03*
X1507025Y404554D03*
X1499225D03*
Y440166D03*
X1522625Y404554D03*
X1499225Y446926D03*
Y453686D03*
X1520675Y463826D03*
X1512875D03*
X1508975D03*
X1495325Y418074D03*
X1493375Y443546D03*
X1489475Y414694D03*
X1493375D03*
X1489475Y407934D03*
X1493375D03*
Y421454D03*
X1489475D03*
X1493375Y428214D03*
Y436786D03*
X1499225Y460446D03*
X1489475Y457066D03*
X1487525Y460446D03*
X1524575Y463826D03*
X1491425Y411314D03*
X1487525D03*
X1516775Y457066D03*
X1524575Y407624D03*
X1499225Y411314D03*
X1501175Y407934D03*
X1521800Y419900D03*
X1501200Y450600D03*
X1501175Y443546D03*
X1505075Y457066D03*
X1524575D03*
X1485250Y408017D03*
X1497200Y421200D03*
X1505715Y441368D03*
X1491425Y446926D03*
X1505075Y407934D03*
X1497273Y407610D03*
X1485300Y443484D03*
X1483375Y458375D03*
X1516700Y409900D03*
X1501175Y428214D03*
X1499225Y424834D03*
X1516775Y463826D03*
X1487525Y440166D03*
X1491425D03*
X1489475Y443546D03*
X1487500Y424600D03*
X1491400D03*
X1493375Y450306D03*
X1489475Y428214D03*
Y436786D03*
X1491425Y460446D03*
X1489475Y450306D03*
X1491425Y453686D03*
X1493375Y457066D03*
X1495325Y460446D03*
X1497275Y463826D03*
X1485030Y463690D03*
X1489475Y463826D03*
X1508975Y457066D03*
X1487525Y480726D03*
X1520675Y470586D03*
X1510925Y467206D03*
X1507025D03*
X1520675Y477346D03*
X1514825Y467206D03*
X1512875Y470586D03*
X1491425Y480726D03*
X1495325Y473966D03*
X1491425Y487486D03*
X1499225Y467206D03*
X1520675Y484106D03*
X1524575Y477346D03*
X1512875D03*
X1526525Y480726D03*
X1524575Y484106D03*
X1522625Y480726D03*
X1516775Y477346D03*
X1470643Y495299D03*
X1482200Y477800D03*
X1482958Y486118D03*
X1485100Y469900D03*
X1524575Y470586D03*
X1472250Y485100D03*
X1472500Y509810D03*
X1501175Y477346D03*
X1493375D03*
X1505075Y484106D03*
X1501175D03*
X1497275Y470586D03*
X1495325Y467206D03*
X1507025Y480726D03*
X1495325D03*
X1503125D03*
X1508975Y484106D03*
X1507025Y473966D03*
X1503125D03*
X1493375Y470586D03*
X1499225Y487486D03*
X1497275Y484106D03*
X1493375D03*
X1499225Y473966D03*
X1495325Y487486D03*
X1512875Y484106D03*
X1510925Y487486D03*
X1497275Y477346D03*
X1489475D03*
X1491425Y467206D03*
X1505075Y477346D03*
X1474400Y517200D03*
X1503400Y524663D03*
X1478700Y533700D03*
X1500445Y619956D03*
X1538520Y11911D03*
X1581947Y-6702D03*
X1580398Y5400D03*
Y-600D03*
X1589623Y24528D03*
X1545111Y24172D03*
X1540000Y3400D03*
X1544882Y-6900D03*
X1549600Y-10800D03*
X1571500Y-1406D03*
X1543500Y3400D03*
X1587359Y84348D03*
X1583374Y81319D03*
X1575018Y71213D03*
X1579100Y69000D03*
X1574780Y90992D03*
X1535300Y78490D03*
X1556810Y71760D03*
X1545572Y38188D03*
X1546370Y84180D03*
X1545250Y88360D03*
X1556200Y94800D03*
X1577269Y95344D03*
X1557981Y141470D03*
X1572395Y110754D03*
X1576506Y143416D03*
X1574197Y127915D03*
X1588000Y100500D03*
X1588500Y106788D03*
X1576606Y104392D03*
X1573153Y103721D03*
X1589622Y112876D03*
X1577700Y140149D03*
X1567520Y133354D03*
X1589200Y121800D03*
X1582500Y109900D03*
X1580275Y101041D03*
X1553500Y157000D03*
X1552171Y133000D03*
X1549000Y115571D03*
X1542000Y126246D03*
X1549187Y104713D03*
X1541421Y106742D03*
X1541413Y155259D03*
X1541434Y139871D03*
X1541390Y136498D03*
X1558136Y100877D03*
X1554627D03*
X1531726Y123800D03*
X1563108Y126423D03*
X1558100Y138025D03*
Y133526D03*
Y128926D03*
X1542685Y133321D03*
X1541765Y114000D03*
X1588176Y157600D03*
X1566486Y181270D03*
X1583874Y217746D03*
X1582249Y191716D03*
X1587549Y192000D03*
X1566858Y175192D03*
X1570294Y167384D03*
X1572817Y169910D03*
X1568488Y164058D03*
X1571501Y180031D03*
X1553500Y165400D03*
X1557787Y192236D03*
X1561925Y192675D03*
X1558000Y205100D03*
X1557979Y188844D03*
X1535000Y207200D03*
X1535425Y188016D03*
X1552063Y202031D03*
X1549693Y196707D03*
X1548178Y190880D03*
X1543100Y184128D03*
X1535065Y164300D03*
X1561538Y174649D03*
X1545023Y161675D03*
X1562150Y160700D03*
X1552051Y172053D03*
X1558042Y172448D03*
X1567000Y259560D03*
X1568120Y251710D03*
X1571876Y255800D03*
X1568365Y247761D03*
X1582699Y252646D03*
X1579867Y265445D03*
X1531935Y224160D03*
X1533596Y273504D03*
X1532237Y247801D03*
X1537972Y236000D03*
X1542690Y236050D03*
X1541325Y245090D03*
X1542751Y240477D03*
X1563157Y258164D03*
X1561104Y234255D03*
X1558700Y252000D03*
X1545802Y233529D03*
X1584568Y281339D03*
X1578790Y290920D03*
X1565000Y290500D03*
X1577486Y307621D03*
X1587800Y308200D03*
X1581940Y295820D03*
X1588551Y341410D03*
X1581834Y318591D03*
X1573950Y338050D03*
X1585479Y316610D03*
X1570574Y341776D03*
X1533228Y325000D03*
X1529734Y319714D03*
X1532850Y303950D03*
X1530500Y287700D03*
X1537500Y292800D03*
X1554932Y332171D03*
X1548334Y325497D03*
X1548273Y313227D03*
X1543864Y311399D03*
X1551250Y320303D03*
X1554775Y295328D03*
X1534833Y309798D03*
X1551404Y309376D03*
X1550619Y303087D03*
X1534400Y296029D03*
X1538450Y314300D03*
X1548024Y322145D03*
X1559500Y290300D03*
X1559800Y285300D03*
X1552900Y281700D03*
X1548100Y342200D03*
X1538406Y330157D03*
X1550800Y296200D03*
X1575645Y320664D03*
X1582800Y312100D03*
X1540175Y387654D03*
X1551875D03*
X1565525Y397794D03*
X1528475Y401174D03*
Y387654D03*
Y394414D03*
X1530425Y377514D03*
X1534325Y384274D03*
Y397794D03*
Y377514D03*
X1542300Y376717D03*
X1551875Y394414D03*
X1540175Y380894D03*
Y401174D03*
X1536275D03*
X1540175Y394414D03*
X1563575Y387654D03*
X1551875Y401174D03*
X1559675Y380894D03*
X1563575D03*
X1565525Y384274D03*
X1571375Y394414D03*
X1565525Y377514D03*
X1567121Y363217D03*
X1566922Y359681D03*
X1567475Y401174D03*
X1582600Y389300D03*
X1571450Y359650D03*
X1565525Y391034D03*
X1586500Y354900D03*
X1569425Y391034D03*
Y397794D03*
X1571375Y387654D03*
X1569584Y378002D03*
X1581822Y365770D03*
X1530425Y384274D03*
X1528475Y380894D03*
X1529829Y362655D03*
X1530425Y391034D03*
Y397794D03*
X1532375Y401174D03*
X1533589Y366361D03*
X1532367Y356530D03*
X1553825Y391034D03*
X1546025D03*
X1563575Y394414D03*
X1557725Y397794D03*
X1550639Y350200D03*
X1563575Y401174D03*
X1553825Y397794D03*
X1546025D03*
X1552500Y358500D03*
X1557725Y377514D03*
X1559675Y401174D03*
X1542125Y397794D03*
X1547975Y394414D03*
X1542932Y355740D03*
X1547975Y387654D03*
X1536275D03*
Y380894D03*
X1534325Y391034D03*
X1559675Y387654D03*
Y394414D03*
X1551875Y380894D03*
X1557725Y391034D03*
X1536275Y394414D03*
X1560500Y350000D03*
X1557534Y353400D03*
X1553825Y377514D03*
X1546182Y355446D03*
X1550417Y362607D03*
X1587684Y362653D03*
X1565525Y460446D03*
X1567475Y443546D03*
Y463826D03*
X1565525Y453686D03*
Y418074D03*
Y424834D03*
Y446926D03*
X1528475Y463826D03*
X1542125Y460446D03*
X1536275Y463826D03*
X1555775Y407934D03*
X1561625Y411314D03*
Y440166D03*
X1551875Y443546D03*
X1557725Y460446D03*
X1553825D03*
X1563575Y450306D03*
X1546025Y460446D03*
X1563575Y463826D03*
X1557725Y440166D03*
X1569425D03*
X1567475Y436786D03*
X1571375Y443546D03*
X1587550Y456550D03*
X1587573Y445300D03*
X1571375Y436786D03*
X1583208Y404941D03*
X1569425Y446926D03*
X1565525Y411314D03*
X1583773Y436137D03*
X1585560Y421324D03*
X1569425Y453686D03*
Y424834D03*
X1582300Y446100D03*
X1583208Y416752D03*
X1532375Y463826D03*
Y407934D03*
X1532349Y455200D03*
X1528475Y407934D03*
X1538225Y460446D03*
X1559675Y407934D03*
X1561625Y446926D03*
X1551875Y450306D03*
X1549950Y404490D03*
X1544075Y463826D03*
X1536275Y407934D03*
X1540175D03*
X1543850Y451400D03*
X1549926Y411312D03*
X1553825Y411314D03*
X1544150Y409900D03*
X1553825Y446926D03*
Y440166D03*
X1555775Y414694D03*
X1561625Y418074D03*
X1553825Y453686D03*
X1547000Y435650D03*
X1549925Y440166D03*
X1551875Y436786D03*
X1540653Y454588D03*
X1549925Y460446D03*
X1559595Y450631D03*
X1557725Y404554D03*
X1559675Y457066D03*
X1536300Y455200D03*
X1567475Y477346D03*
X1565525Y473966D03*
X1569425Y467206D03*
X1565525D03*
X1571375Y477346D03*
X1530425Y467206D03*
X1561625D03*
X1563575Y470586D03*
X1561625Y473966D03*
X1551875Y470586D03*
X1549925Y467206D03*
X1559675Y470586D03*
X1557725Y467206D03*
X1547975Y484106D03*
X1551875D03*
X1549925Y480726D03*
X1559675Y477346D03*
X1563575Y484106D03*
X1561625Y480726D03*
X1536275Y477346D03*
X1559675Y484106D03*
X1530425Y480726D03*
Y487486D03*
X1557725D03*
X1561625D03*
X1534325Y473966D03*
X1584970Y472370D03*
X1567475Y484106D03*
X1565525Y487486D03*
X1533595Y505530D03*
X1534325Y467206D03*
X1538225D03*
X1542125D03*
X1540175Y470586D03*
X1544075Y484106D03*
X1542125Y480726D03*
X1538225Y487486D03*
X1546025D03*
X1540175Y484106D03*
X1542125Y487486D03*
X1551875Y477346D03*
X1563575D03*
X1538225Y480726D03*
X1534325D03*
X1528475Y484106D03*
X1532375D03*
Y477346D03*
X1547975D03*
X1546025Y473966D03*
X1565389Y585721D03*
X1581730Y537170D03*
X1587610Y579550D03*
X1550990Y586588D03*
X1554358Y587258D03*
X1585155Y538574D03*
X1586700Y620100D03*
X1579900Y606050D03*
X1572950Y593950D03*
X1573500Y619500D03*
X1546075Y618145D03*
X1544050Y615296D03*
X1534968Y597268D03*
X1535565Y591658D03*
X1540477Y620308D03*
X1540700Y613700D03*
X1541384Y601262D03*
X1577000Y619500D03*
X1579680Y610279D03*
X1545407Y598393D03*
X1598602Y3437D03*
X1623900Y4600D03*
X1592829Y24460D03*
X1597800Y24300D03*
X1637482Y21623D03*
X1638550Y7200D03*
X1617500Y-14500D03*
X1601650Y24160D03*
X1590431Y-6702D03*
X1592715Y70817D03*
X1640900Y66900D03*
X1649900Y78600D03*
X1635337Y73500D03*
X1619000Y38500D03*
X1599000Y61500D03*
X1620900Y81300D03*
X1632000Y73500D03*
X1627489Y74960D03*
X1599500Y75000D03*
X1606579Y86726D03*
X1614169Y95004D03*
X1617347Y94581D03*
X1597867Y93900D03*
X1614997Y84403D03*
X1596050Y75400D03*
X1625075Y80182D03*
X1632006Y94500D03*
X1643500Y80400D03*
X1621100Y69600D03*
X1597987Y79500D03*
X1630826Y88087D03*
X1604000Y93925D03*
X1593241Y134295D03*
X1628788Y97800D03*
X1593756Y129048D03*
X1590949Y97850D03*
X1648000Y100597D03*
X1598449Y120760D03*
X1598300Y116477D03*
X1632020Y97871D03*
X1600000Y104243D03*
X1594452Y111377D03*
X1635750Y128240D03*
X1642087Y143837D03*
X1590569Y152464D03*
X1637363Y149484D03*
X1642087Y153286D03*
X1604292Y150137D03*
X1600148Y142262D03*
X1632639Y124940D03*
X1607441Y106042D03*
X1608000Y99400D03*
X1600900Y131900D03*
X1616900Y143880D03*
X1604169Y156407D03*
X1593218Y191776D03*
X1595291Y166423D03*
X1591800Y164900D03*
X1598006Y192421D03*
X1651000Y178628D03*
X1645700Y214050D03*
X1650600Y186300D03*
X1648349Y182276D03*
X1644290Y196383D03*
X1627326Y182759D03*
X1615362Y213507D03*
X1602185Y180709D03*
X1635351Y185444D03*
X1603300Y185100D03*
X1647852Y197374D03*
X1635621Y208259D03*
X1648320Y172690D03*
X1591950Y158250D03*
X1600490Y158010D03*
X1596427Y157975D03*
X1608731Y180819D03*
X1622217Y177809D03*
X1600490Y167459D03*
X1643662Y172609D03*
X1604222Y268107D03*
X1637281Y254322D03*
X1627024Y253387D03*
X1627043Y256900D03*
X1638216Y246021D03*
X1637269Y264421D03*
X1637281Y260922D03*
X1636914Y270900D03*
X1643106Y233913D03*
X1596300Y250320D03*
X1601870Y270470D03*
X1600810Y266006D03*
X1631300Y280400D03*
X1597201Y238188D03*
X1617498Y273433D03*
X1610290Y265352D03*
X1643775Y246137D03*
X1632128Y225472D03*
X1622000Y279495D03*
X1590176Y331844D03*
X1590212Y315425D03*
X1636800Y287956D03*
X1639040Y316343D03*
X1638086Y319664D03*
X1631015Y328350D03*
X1635355Y324228D03*
X1609172Y339630D03*
X1602776Y331304D03*
X1625846Y286154D03*
X1638063Y326504D03*
X1636684Y283141D03*
X1620159Y332004D03*
X1625400Y327667D03*
X1608764Y322440D03*
X1622100Y400600D03*
X1638991Y352037D03*
X1629300Y385400D03*
X1630400Y391800D03*
X1621727Y395374D03*
X1609271Y348166D03*
X1608850Y343835D03*
X1613452Y387098D03*
X1610140Y358350D03*
X1602215Y363981D03*
X1621800Y386300D03*
Y381500D03*
X1630120Y418887D03*
X1595800Y405900D03*
X1595200Y412700D03*
X1617900Y409900D03*
X1630750Y404800D03*
X1591430Y409440D03*
X1591350Y445300D03*
X1593400Y432200D03*
X1640625Y429460D03*
X1630150Y427663D03*
X1611642Y461877D03*
X1630219Y446000D03*
X1621000Y440500D03*
X1621044Y433364D03*
X1611418Y422971D03*
X1621182Y427091D03*
X1621347Y415297D03*
X1603719Y412000D03*
X1611638Y454809D03*
X1612100Y446000D03*
X1630386Y413942D03*
X1634400Y412900D03*
X1639750Y445477D03*
X1646480Y443880D03*
X1639774Y439486D03*
X1639822Y453140D03*
X1647200Y430450D03*
X1612825Y405438D03*
X1596500Y455500D03*
X1615061Y463157D03*
X1603000Y422971D03*
X1621226Y445026D03*
X1639391Y513065D03*
X1642670Y514939D03*
X1649336Y511502D03*
X1641470Y506403D03*
X1644651Y505500D03*
X1649545Y515215D03*
X1645969Y514870D03*
X1617700Y475957D03*
X1614000Y475970D03*
X1623705Y467855D03*
X1617300Y519000D03*
X1600780Y495416D03*
X1597380D03*
X1629778Y507294D03*
X1621783Y498617D03*
X1625485Y494188D03*
X1627622Y524928D03*
X1620030Y525066D03*
X1623551Y525015D03*
X1590580Y472370D03*
X1629500Y491500D03*
X1639271Y491135D03*
X1626518Y528029D03*
X1631975Y527700D03*
X1601540Y588793D03*
X1594110Y611510D03*
X1592934Y592396D03*
X1617600Y619800D03*
X1619700Y617300D03*
X1622330Y592325D03*
X1653100Y11500D03*
X1680033Y-16711D03*
X1666500Y10500D03*
X1680034Y2863D03*
X1693900Y73300D03*
X1697300Y73296D03*
X1690500Y73950D03*
X1653000Y77600D03*
X1669000Y92000D03*
X1659000Y88000D03*
X1661900Y92400D03*
X1708610Y85121D03*
X1709184Y88811D03*
X1707268Y77668D03*
X1692300Y56900D03*
X1684248Y56746D03*
X1658600Y44700D03*
X1704824Y90049D03*
X1678627Y54616D03*
X1712600Y46100D03*
X1711000Y55525D03*
X1696870Y86093D03*
X1689250Y86000D03*
X1667000Y88000D03*
X1696907Y99077D03*
X1664500Y99000D03*
X1672200Y112200D03*
X1674800Y103100D03*
X1678400Y103000D03*
X1667348Y156500D03*
X1653111Y102240D03*
X1674019Y175990D03*
X1654015Y217239D03*
X1655978Y207827D03*
X1663400Y179475D03*
X1681352Y196092D03*
X1708350Y175050D03*
X1688046Y174447D03*
X1667356Y213096D03*
X1660440Y200789D03*
X1702400Y193450D03*
X1664321Y195244D03*
X1658082Y195298D03*
X1673800Y201070D03*
X1660800Y181900D03*
X1687550Y213751D03*
X1713000Y185000D03*
X1705666Y198055D03*
X1676750Y206050D03*
X1667140Y182300D03*
X1674912Y183000D03*
X1669849Y193067D03*
X1673530Y209974D03*
X1691439Y174354D03*
X1664390Y201163D03*
X1659643Y213505D03*
X1671688Y182925D03*
X1665063Y172608D03*
X1681116Y238614D03*
X1657498Y279900D03*
Y274700D03*
Y269700D03*
X1657567Y264600D03*
X1657500Y259700D03*
X1652991Y321341D03*
X1657498Y284900D03*
X1657494Y292816D03*
X1664453Y308557D03*
X1660972Y401447D03*
X1660890Y397300D03*
X1668100Y418700D03*
X1678303Y442765D03*
X1667946Y412987D03*
X1673550Y442696D03*
X1667588Y434149D03*
X1679145Y461950D03*
X1673074Y453185D03*
X1675120Y439731D03*
X1660834Y404934D03*
X1655790Y476593D03*
X1671050Y490850D03*
X1705767Y482434D03*
X1698354Y486873D03*
X1681500Y482000D03*
X1710594Y519900D03*
X1681650Y510673D03*
X1687606Y500938D03*
X1672265Y473600D03*
X1671050Y487000D03*
X1681115Y525218D03*
X1651754Y488025D03*
X1672159Y494042D03*
X1701617Y482706D03*
X1676800Y483800D03*
X1680133Y535489D03*
X1699600Y578100D03*
X1710389Y577787D03*
X1710000Y604500D03*
Y600000D03*
X1701291Y602268D03*
X1741544Y9151D03*
X1744900Y9100D03*
X1749085Y9177D03*
X1731350Y92140D03*
X1713900Y87900D03*
X1750400Y47400D03*
X1757772Y90174D03*
X1720500Y52440D03*
X1757998Y73637D03*
X1775000Y53500D03*
X1720100Y46100D03*
X1746328Y59011D03*
X1725474Y69250D03*
X1760016Y65774D03*
X1771707Y86500D03*
X1767250Y94500D03*
Y89500D03*
X1766333Y59116D03*
X1715100Y70500D03*
X1748425Y119190D03*
X1765015Y119100D03*
X1768886Y156173D03*
X1717014Y97550D03*
Y111150D03*
Y133200D03*
X1745364Y117450D03*
X1745363Y108004D03*
X1746189Y153250D03*
X1745500Y104500D03*
X1720164Y117451D03*
X1745768Y111743D03*
X1742214Y114300D03*
X1731789Y139450D03*
X1717014Y142650D03*
X1726464Y111150D03*
X1734989Y142750D03*
X1728789Y136250D03*
X1735989Y149050D03*
X1726539Y139450D03*
X1735989Y133250D03*
X1713596Y175795D03*
X1719000Y190500D03*
X1715837Y246178D03*
X1727896Y246175D03*
X1720651Y246141D03*
X1718820Y249032D03*
X1715078Y250231D03*
X1724181Y246159D03*
X1719080Y232852D03*
Y236152D03*
X1722251Y250532D03*
X1751900Y249700D03*
X1746900Y249804D03*
X1749462Y232955D03*
X1737150Y450850D03*
X1730996Y442804D03*
X1714530Y519900D03*
X1716490Y506970D03*
X1719089Y472104D03*
X1728700Y470200D03*
X1766100Y521124D03*
X1722347Y471811D03*
X1750800Y516100D03*
X1762715Y521085D03*
X1719560Y501770D03*
X1767500Y559800D03*
X1724250Y588250D03*
X1756578Y586743D03*
X1767141Y555500D03*
X1730759Y548162D03*
X1733000Y557000D03*
X1722500Y562000D03*
X1742200Y552863D03*
X1754897Y578750D03*
X1764300Y570900D03*
X1753807Y548183D03*
X1757478Y548192D03*
X1738498Y554255D03*
X1767529Y566200D03*
X1743000Y574500D03*
X1724899Y584748D03*
X1742381Y588530D03*
X1735000Y621002D03*
X1764912Y618718D03*
X1725133Y614896D03*
X1770600Y600800D03*
X1766400Y599400D03*
X1728341Y614851D03*
X1750399Y603201D03*
X1764823Y613600D03*
X1716950Y603450D03*
X1739714Y604967D03*
X1835600Y3900D03*
X1804800Y-1500D03*
X1831000Y-16300D03*
X1836700Y-18900D03*
X1819800Y2100D03*
X1813913Y2287D03*
X1816723Y9781D03*
X1823600Y8800D03*
X1795078Y11900D03*
X1790078Y11860D03*
X1804462Y8830D03*
X1799462D03*
X1808100Y21800D03*
X1815150Y26650D03*
X1797700Y21018D03*
X1791500Y26918D03*
X1813795Y12165D03*
X1828874Y-13520D03*
X1819837Y21700D03*
X1786865Y22375D03*
X1826414Y35486D03*
X1827100Y81600D03*
X1798454Y82256D03*
X1788216Y59197D03*
X1779750Y36530D03*
X1820457Y39128D03*
X1829580Y38620D03*
X1824240Y83680D03*
X1802119Y56581D03*
X1799438Y44328D03*
X1827000Y94550D03*
X1808363Y40033D03*
X1803300Y39900D03*
X1812352Y36949D03*
X1797700Y36804D03*
X1792700Y36871D03*
X1776828Y155211D03*
X1815883Y133277D03*
X1813118Y127976D03*
X1807509Y128500D03*
X1807166Y147401D03*
X1783252Y109044D03*
X1803058Y143733D03*
X1815348Y143437D03*
X1796500Y120000D03*
X1827150Y97800D03*
X1830316Y102163D03*
X1824990Y103620D03*
X1787373Y120188D03*
X1815026Y121478D03*
X1808226Y136171D03*
X1803509Y128500D03*
X1800792Y122691D03*
X1821350Y98270D03*
X1810100Y114700D03*
X1814900Y116900D03*
X1816418Y127976D03*
X1788000Y129000D03*
X1808313Y111705D03*
X1800420Y148240D03*
X1807818Y124179D03*
X1827500Y144900D03*
X1809810Y155858D03*
X1833629Y170807D03*
X1821261Y170012D03*
X1824200Y176900D03*
X1787000Y175500D03*
X1834103Y176021D03*
X1778900Y165800D03*
X1785500Y164000D03*
Y168000D03*
X1834400Y216900D03*
X1830415Y196567D03*
X1816125Y169492D03*
X1836100Y179700D03*
X1784440Y232938D03*
X1831700Y252272D03*
X1804388Y249904D03*
X1826662Y232191D03*
X1822638Y232106D03*
X1826085Y236034D03*
X1822877Y235852D03*
X1834100Y523900D03*
X1814852Y519901D03*
X1809700Y506875D03*
X1820400Y501100D03*
X1810200Y513300D03*
X1815200Y501500D03*
X1794100Y521900D03*
X1803900Y491500D03*
X1836600Y521600D03*
X1833700Y497300D03*
X1795200Y525700D03*
X1810350Y525650D03*
X1813500Y526500D03*
X1825900Y523500D03*
X1829000Y536315D03*
X1783700Y576400D03*
X1798250Y529200D03*
X1810863Y560637D03*
X1816175Y567669D03*
X1785050Y584550D03*
X1792100Y566900D03*
X1816100Y576200D03*
X1816330Y545260D03*
X1809309Y555713D03*
X1831500Y548000D03*
X1780394Y561076D03*
X1782300Y555900D03*
X1781300Y537800D03*
X1816584Y530542D03*
X1793660Y560570D03*
X1829300Y572900D03*
X1792805Y574675D03*
X1811100Y586800D03*
X1816458Y587480D03*
X1829176Y584287D03*
X1831600Y529000D03*
X1832500Y539500D03*
X1788300Y585100D03*
X1791349Y589122D03*
X1832200Y567760D03*
X1831500Y544500D03*
X1831800Y552300D03*
X1809600Y582800D03*
X1793100Y578500D03*
X1816020Y571448D03*
X1812802Y578693D03*
X1795000Y599600D03*
X1791323Y594030D03*
X1805000Y606500D03*
X1787500Y600500D03*
X1778675Y592224D03*
X1784200Y593924D03*
X1794500Y612500D03*
X1791500Y606500D03*
X1782700Y610900D03*
X1829051Y591299D03*
X1838850Y13160D03*
X1883041Y15814D03*
X1882999Y7383D03*
X1876792Y18461D03*
X1893094Y-12642D03*
X1858600Y74300D03*
X1837500Y35700D03*
X1841060Y35540D03*
X1883200Y76600D03*
X1850600Y41348D03*
X1889218Y56030D03*
Y61030D03*
Y46030D03*
Y51030D03*
X1878000Y73950D03*
X1848208Y49427D03*
X1842250Y84000D03*
X1849426Y90700D03*
Y95500D03*
X1838500Y40400D03*
X1864904Y114735D03*
X1872254Y138618D03*
X1839667Y151994D03*
X1837090Y149830D03*
X1843107Y97988D03*
X1857110Y113600D03*
X1890974Y105600D03*
X1898102Y107325D03*
X1897536Y120510D03*
Y114600D03*
X1885700Y141200D03*
X1867280Y135406D03*
X1871521Y153593D03*
X1881324Y153250D03*
X1875600Y156300D03*
X1895673Y151800D03*
X1878753Y139893D03*
X1866606Y109967D03*
X1872400Y144619D03*
X1857919Y156123D03*
X1895060Y136099D03*
X1857849Y148079D03*
X1894855Y142122D03*
X1893640Y147042D03*
X1888639D03*
X1887497Y105444D03*
X1881165Y105561D03*
X1885102Y101134D03*
X1861932Y146431D03*
X1869668Y146750D03*
X1897507Y124450D03*
X1864637Y201861D03*
X1868843Y207920D03*
X1836932Y170486D03*
X1877517Y217988D03*
X1876700Y207600D03*
X1875700Y184800D03*
X1882452Y195888D03*
X1877880Y203780D03*
X1863650Y189750D03*
X1893238Y208042D03*
X1886200Y161000D03*
X1862000Y177500D03*
X1884340Y217866D03*
X1874236Y213800D03*
X1864464Y198466D03*
X1878789Y213663D03*
X1864000Y184900D03*
X1858500Y200100D03*
X1861243Y183100D03*
X1872100Y207900D03*
X1884400Y183700D03*
X1891880Y204370D03*
X1836900Y165800D03*
X1889400Y191200D03*
X1896710Y194380D03*
X1847200Y202050D03*
X1840900Y179700D03*
X1845700D03*
X1858686Y180377D03*
X1885465Y166285D03*
X1855000Y167100D03*
X1884000Y188100D03*
X1865100Y174600D03*
X1850723Y219250D03*
X1843449Y244425D03*
X1856874Y219443D03*
X1896529Y235080D03*
X1854374Y248790D03*
X1844444Y224035D03*
X1850220Y253500D03*
X1840149Y244425D03*
X1892274Y235080D03*
X1846517Y253500D03*
X1854720Y253700D03*
X1858633Y452803D03*
X1878100Y450200D03*
X1859059Y448076D03*
X1875900Y453600D03*
X1863137Y452710D03*
X1867500Y447900D03*
X1837300Y472276D03*
X1837200Y525700D03*
X1866688Y517128D03*
X1859530Y516430D03*
X1842400Y516800D03*
X1864339Y509560D03*
X1841900Y498800D03*
X1852719Y487575D03*
Y492575D03*
X1847000Y487500D03*
X1860000Y495500D03*
X1869914Y517225D03*
X1857450Y473654D03*
X1837857Y468630D03*
X1842857D03*
X1868167Y467855D03*
X1863000Y480000D03*
X1859600Y476200D03*
X1876945Y471316D03*
X1877407Y479046D03*
X1855206Y471112D03*
X1842764Y528136D03*
X1837475Y573835D03*
X1837534Y579322D03*
X1838224Y586650D03*
X1870100Y561150D03*
X1858528Y544528D03*
X1875850Y567200D03*
X1840690Y557190D03*
X1878500Y553500D03*
X1858500Y540000D03*
X1852250Y547900D03*
X1858681Y568087D03*
X1879862Y581862D03*
X1896899Y557790D03*
X1845407Y533178D03*
X1868110Y536000D03*
X1878736Y533040D03*
X1864580Y537060D03*
X1869800Y557100D03*
X1878875Y565475D03*
X1882300Y565550D03*
X1885100Y584300D03*
X1873510Y541710D03*
X1840700Y563800D03*
X1854530Y533132D03*
X1856573Y576534D03*
X1857812Y557245D03*
X1895523Y586365D03*
X1844018Y586482D03*
X1866800Y588000D03*
X1875600Y588500D03*
X1837000Y534900D03*
X1839126Y583354D03*
X1847070Y537610D03*
X1896358Y595255D03*
X1868200Y590939D03*
X1848900Y590750D03*
X1845000Y590800D03*
X1900256Y-14760D03*
X1916078Y-16368D03*
X1918352Y89300D03*
X1923300Y94300D03*
X1920300Y68300D03*
X1917600Y66000D03*
X1948472Y80362D03*
X1946500Y104974D03*
X1940700Y136300D03*
X1904215Y142812D03*
X1937900Y153600D03*
X1921264Y153000D03*
X1943752Y137548D03*
X1947078Y139300D03*
X1927000Y152200D03*
X1926952Y156049D03*
X1952726Y102950D03*
X1914500Y113300D03*
X1932998Y119438D03*
X1923329Y99475D03*
X1947000Y142600D03*
X1923837Y118800D03*
X1937728Y99441D03*
X1925358Y140685D03*
X1934544Y127957D03*
X1933914Y96040D03*
X1899855Y142122D03*
X1909216Y142812D03*
X1908327Y149353D03*
X1923800Y151000D03*
X1934100Y193400D03*
X1927064Y207564D03*
X1938400Y178200D03*
X1932837Y186700D03*
X1918489Y212513D03*
X1903917Y201472D03*
X1935600Y198700D03*
X1950981Y191218D03*
X1939200Y194300D03*
X1930500Y209464D03*
X1943500Y209500D03*
X1925000Y192000D03*
X1904042Y204895D03*
X1931483Y199350D03*
X1901100Y194200D03*
X1921500Y193600D03*
X1917024D03*
X1917568Y201215D03*
X1910123Y217349D03*
X1957334Y201269D03*
X1939300Y204300D03*
X1939550Y165600D03*
X1940647Y161600D03*
X1903150Y217250D03*
X1952717Y198614D03*
X1935600Y176300D03*
X1943217Y217645D03*
X1940500Y157600D03*
X1925400Y196300D03*
X1909438Y204307D03*
X1929700Y163400D03*
X1940240Y169970D03*
X1929000Y158600D03*
X1939400Y198400D03*
X1929090Y193190D03*
X1918143Y219848D03*
X1899816Y235035D03*
X1943217Y221154D03*
X1942000Y440500D03*
X1904724Y447930D03*
X1901574Y454422D03*
X1939845Y445055D03*
X1937430Y464785D03*
X1957212Y479521D03*
X1928620Y482710D03*
X1919230Y483430D03*
X1945000Y474000D03*
X1947550Y485350D03*
X1956500Y507470D03*
X1938300Y486250D03*
X1957250Y512050D03*
X1937300Y508900D03*
X1919510Y475100D03*
Y479200D03*
X1939000Y476600D03*
X1956300Y515900D03*
X1908300Y514500D03*
X1942328Y508712D03*
X1956606Y526671D03*
X1919000Y487210D03*
X1959300Y518000D03*
X1957063Y474769D03*
X1948200Y474300D03*
X1900890Y477200D03*
X1907200Y551600D03*
X1951900Y534900D03*
X1900250Y533700D03*
X1926600Y559500D03*
X1923600Y565100D03*
X1923000Y568700D03*
X1959120Y547050D03*
X1958940Y538890D03*
X1956191Y548700D03*
X1958500Y535000D03*
X1907500Y545600D03*
X1921244Y533750D03*
X1900729Y569557D03*
X1934200Y573700D03*
X1935400Y583000D03*
X1940800Y537300D03*
X1945900Y549900D03*
X1923500Y579500D03*
X1948100Y538700D03*
X1923400Y583000D03*
X1923600Y575500D03*
X1918880Y586460D03*
X1932390Y590100D03*
X1938130Y601480D03*
X1923504Y592500D03*
X1911750Y592800D03*
X1927000Y614500D03*
X1914700Y594600D03*
X1959400Y601100D03*
X1934350Y609250D03*
X1963400Y141100D03*
X1967580Y104721D03*
X1963300Y191000D03*
X1967200Y521600D03*
X1964270Y511410D03*
X1968375Y509375D03*
X1964890Y534940D03*
X1963000Y573000D03*
X1963097Y551000D03*
X1962950Y566600D03*
X1961715Y555639D03*
X1962500Y578500D03*
X1965400Y619500D03*
X1961771Y591744D03*
X1963300Y612800D03*
G54D70*
X1854501Y195587D03*
X1859854Y501441D03*
X1952756Y589960D03*
X1944882Y582086D03*
X1952756D03*
X1944882Y574212D03*
X1952756D03*
X1944882Y566338D03*
X1952756D03*
X1944882Y558464D03*
Y589960D03*
X1952756Y558464D03*
X1944882Y605708D03*
X1952756D03*
X1944882Y597834D03*
X1952756D03*
G54D64*
X1638131Y475946D03*
G54D52*
X-4488Y425472D03*
X99980Y136909D03*
X1462000Y-5000D03*
Y-15000D03*
X1452000Y-5000D03*
Y-15000D03*
X1442000Y-5000D03*
Y-15000D03*
X1525000D03*
X1515000D03*
X1482000D03*
X1472000Y-5000D03*
Y-15000D03*
X1492000Y-5000D03*
Y-15000D03*
X1482000Y-5000D03*
X1505000Y-15000D03*
X1575000D03*
X1565000D03*
X1555000D03*
X1545000D03*
X1535000D03*
X1713503Y-5000D03*
Y-15000D03*
X1703503Y-5000D03*
Y-15000D03*
X1743503D03*
X1733503Y-5000D03*
Y-15000D03*
X1743503Y-5000D03*
X1769504D03*
Y-15000D03*
X1809504D03*
X1799504Y-5000D03*
Y-15000D03*
X1789504Y-5000D03*
Y-15000D03*
X1779504Y-5000D03*
X1819504D03*
Y-15000D03*
X1809504Y-5000D03*
G54D36*
X40500Y-42250D03*
Y-52250D03*
X60500Y-42250D03*
X80500D03*
X100500D03*
X60500Y-52250D03*
X80500D03*
X100500D03*
X120500Y-42250D03*
X140500D03*
X120500Y-52250D03*
X140500D03*
X467246Y-52301D03*
Y-42301D03*
X487246Y-52301D03*
Y-42301D03*
X507246Y-52301D03*
Y-42301D03*
X527246Y-52301D03*
Y-42301D03*
X547246Y-52301D03*
Y-42301D03*
X567246Y-52301D03*
Y-42301D03*
X798984Y-52057D03*
Y-42057D03*
X818984Y-52057D03*
Y-42057D03*
X838984Y-52057D03*
Y-42057D03*
X858984Y-52057D03*
Y-42057D03*
X878984Y-52057D03*
Y-42057D03*
X898984Y-52057D03*
Y-42057D03*
X1135583Y-52285D03*
Y-42285D03*
X1155583Y-52285D03*
Y-42285D03*
X1392258Y-52257D03*
Y-42257D03*
X1412258Y-52257D03*
Y-42257D03*
X1432258Y-52257D03*
Y-42257D03*
X1452258Y-52257D03*
Y-42257D03*
G54D73*
X1922248Y518328D03*
G54D67*
X1724807Y451179D03*
X1851250Y584622D03*
Y576748D03*
Y568874D03*
Y561000D03*
G54D66*
X1674921Y528523D03*
X1773347D03*
Y545059D03*
G54D59*
X638541Y171945D03*
Y454425D03*
X752641Y159945D03*
X1288068Y171945D03*
Y454425D03*
X1402168Y159945D03*
Y442425D03*
G54D51*
X40512Y458744D03*
G54D44*
X-15748Y116969D03*
Y132717D03*
X787D03*
X28740Y124843D03*
Y140591D03*
G54D54*
X30512Y467244D03*
X40512D03*
G54D69*
X1809665Y618663D03*
X1819665D03*
X1829665D03*
G54D56*
X63093Y202300D03*
X72936D03*
X82779D03*
X1914911Y495775D03*
X1934597D03*
X1924754D03*
G54D46*
X-14488Y434094D03*
X-4488D03*
X5512D03*
X15512D03*
X89980Y145531D03*
X99980D03*
X109980D03*
X119980D03*
G54D60*
X1401516Y23976D03*
G54D75*
X1526871Y23968D03*
G54D41*
X1466694Y375787D03*
G54D43*
X1705772Y567874D03*
G54D55*
X94683Y31978D03*
Y13078D03*
Y69778D03*
Y50878D03*
Y514079D03*
Y532955D03*
Y570755D03*
Y589679D03*
Y551879D03*
Y608555D03*
X637793Y-5822D03*
Y13078D03*
Y69778D03*
Y50878D03*
Y88678D03*
Y514079D03*
Y532955D03*
Y570755D03*
Y589679D03*
Y551879D03*
Y608555D03*
X744293Y-5822D03*
Y31978D03*
Y13078D03*
Y69778D03*
Y88678D03*
Y50878D03*
Y514079D03*
Y570755D03*
Y532955D03*
Y589679D03*
Y551879D03*
Y608555D03*
X1287403Y-5822D03*
Y31978D03*
Y13078D03*
Y69778D03*
Y88678D03*
Y50878D03*
Y514079D03*
Y532955D03*
Y551879D03*
Y608555D03*
G54D49*
X-7874Y216181D03*
Y325315D03*
G54D50*
X18228Y178386D03*
X-1969D03*
G54D38*
X1866923Y235400D03*
G54D35*
X-3937Y-43307D03*
X1956693D03*
X-13780Y598560D03*
X-3937Y646063D03*
X1956693D03*
G54D42*
X1611283Y615236D03*
G54D37*
X1955506Y454297D03*
X1699600D03*
Y235400D03*
G54D39*
X133563Y183126D03*
Y419626D03*
X783171Y183126D03*
Y419626D03*
G54D40*
X1454685Y338189D03*
X1600355Y527165D03*
G54D58*
X224410Y301378D03*
X326772Y163582D03*
Y439173D03*
X500000Y163582D03*
Y439173D03*
X602362Y214764D03*
Y387992D03*
X874016Y301378D03*
X976378Y163582D03*
Y439173D03*
X1149606Y163582D03*
Y439173D03*
X1251969Y214764D03*
Y387992D03*
%LPD*%
G75*
G36*
G01X13233Y197003D02*
X12300Y197936D01*
Y232700D01*
X9032Y235968D01*
Y264332D01*
X13989Y269289D01*
Y336889D01*
X16300Y339200D01*
X38600D01*
X39500Y338300D01*
Y199600D01*
X36903Y197003D01*
X13233D01*
G37*
G36*
G01X53000Y223300D02*
X51800Y224500D01*
Y258900D01*
X59984Y267084D01*
X72912D01*
X74529Y265467D01*
Y265408D01*
X74988Y264949D01*
Y224634D01*
X73654Y223300D01*
X53000D01*
G37*
G36*
G01X402440Y-12830D02*
X399533Y-9923D01*
X399530Y-9844D01*
G03X398086Y-8400I-1501J-57D01*
G01X398007Y-8397D01*
X397420Y-7810D01*
X395132D01*
X394591Y-8351D01*
X394512Y-8335D01*
G03X393655Y-8405I-320J-1365D01*
G03X392905Y-9143I536J-1295D01*
G01X392861Y-9240D01*
X392148D01*
G02X391751Y-8792I0J400D01*
G03X391788Y-8272I-3564J515D01*
G01Y-3372D01*
G03X384586I-3601J0D01*
G01Y-8272D01*
G03X384619Y-8764I3601J-6D01*
G02X384221Y-9200I-398J-36D01*
G01X373392D01*
X373220Y-9372D01*
G02X372569Y-9247I-283J283D01*
G03X369856Y-9791I-1312J-496D01*
G03X369995Y-10409I1402J-9D01*
G02X369597Y-10842I-398J-33D01*
G01X366350D01*
G02X365975Y-10304I0J400D01*
G03X363243Y-9072I-1410J518D01*
G02X362540I-351J190D01*
G03X359808Y-10304I-1322J-714D01*
G02X359433Y-10842I-375J-138D01*
G01X353002D01*
G02X352618Y-10332I0J400D01*
G03X349740I-1439J431D01*
G02X349356Y-10842I-384J-110D01*
G01X346271D01*
G02X345896Y-10304I0J400D01*
G03X343076I-1410J518D01*
G02X342701Y-10842I-375J-138D01*
G01X332885D01*
G02X332510Y-10304I0J400D01*
G03X329690I-1410J518D01*
G02X329315Y-10842I-375J-138D01*
G01X326230D01*
G02X325846Y-10332I0J400D01*
G03X322968I-1439J431D01*
G02X322584Y-10842I-384J-110D01*
G01X309250D01*
X309013Y-10606D01*
X307874Y-9468D01*
Y-8978D01*
G02X308232Y-8580I400J0D01*
G03Y-5780I-75J1400D01*
G02X307874Y-5382I42J398D01*
G01Y-3240D01*
X308024Y-3201D01*
G03X309036Y-2181I-349J1358D01*
G03X308772Y-970I-1361J338D01*
G03X308342Y-610I-1097J-873D01*
G01Y8067D01*
G03Y10533I-667J1233D01*
G01Y11835D01*
X308473Y11883D01*
G03X309339Y13589I-481J1317D01*
G03X307346Y14444I-1347J-389D01*
G01X307216Y14376D01*
X306492Y15100D01*
Y15491D01*
G02X306897Y15891I400J0D01*
G03Y18223I778J1166D01*
G02X306492Y18623I-5J400D01*
G01Y26500D01*
X306857Y26865D01*
X306989Y26791D01*
G03X308292Y29273I686J1223D01*
G01Y30703D01*
X308442Y30742D01*
G03Y33458I-350J1358D01*
G01X308292Y33497D01*
Y34698D01*
G03Y37216I-617J1259D01*
G01Y49362D01*
X308391Y49398D01*
G03X308419Y52050I-441J1331D01*
G01X308377Y52065D01*
X307742Y52700D01*
Y53446D01*
X307909Y53475D01*
G03X308070Y56202I-234J1382D01*
G02X308089Y56747I302J262D01*
G01X308092Y56750D01*
Y66401D01*
X308247Y66437D01*
G03X308793Y68905I-319J1365D01*
G02X308897Y69329I378J132D01*
G03X309334Y69995I-905J1070D01*
G03X308218Y71784I-1342J405D01*
G01X308092Y71808D01*
Y72484D01*
X308205Y72539D01*
G03X308492Y74875I-613J1261D01*
G01Y86023D01*
X308586Y86056D01*
G03X308626Y88718I-420J1338D01*
G01X308492Y88765D01*
Y90850D01*
X308436Y90906D01*
G02X308487Y91514I283J282D01*
G03X308640Y91640I-812J1142D01*
G03X307873Y94045I-965J1017D01*
G01X307742Y94068D01*
Y99200D01*
X309013Y100471D01*
Y105381D01*
X338884Y135252D01*
Y200942D01*
X340542Y202600D01*
Y203938D01*
G02X341225Y204220I400J0D01*
G03Y206200I993J990D01*
G02X340542Y206482I-283J282D01*
G01Y207837D01*
G02X341225Y208119I400J0D01*
G03X341835Y207760I993J990D01*
G03X343611Y208955I383J1349D01*
G03X340926Y209655I-1394J154D01*
G01X340875Y209533D01*
X340542D01*
Y210158D01*
X341763Y211379D01*
X342821D01*
X343792Y212350D01*
Y248700D01*
X344102Y249010D01*
G02X344654Y249023I283J-283D01*
G03X346941Y249657I944J1037D01*
G01X346984Y249800D01*
X347721D01*
G02X348012Y249125I0J-400D01*
G03X349944I966J-1016D01*
G02X350235Y249800I291J275D01*
G01X350971D01*
X351014Y249657D01*
G03X353700I1343J403D01*
G01X353743Y249800D01*
X354480D01*
G02X354771Y249125I0J-400D01*
G03X356703I966J-1016D01*
G02X356994Y249800I291J275D01*
G01X357731D01*
X357774Y249657D01*
G03X360460I1343J403D01*
G01X360503Y249800D01*
X361240D01*
G02X361531Y249125I0J-400D01*
G03X361196Y248632I966J-1016D01*
G03X362835Y246748I1301J-523D01*
G03X363010Y249414I-337J1361D01*
G01X362883Y249464D01*
Y249800D01*
X363437D01*
X363537Y249700D01*
X364515D01*
X364563Y249570D01*
G03X367191I1314J490D01*
G01X367239Y249700D01*
X367905D01*
G02X368068Y249665I-1J-400D01*
G01X368604D01*
Y249355D01*
X368511Y249296D01*
G03X370657Y248192I746J-1187D01*
G02X371339Y248498I399J23D01*
G01X371419Y248418D01*
X373726D01*
X374162Y248854D01*
Y250922D01*
X374363Y251123D01*
G02X374950Y251099I282J-283D01*
G03X376927Y253076I1067J910D01*
G02X376903Y253663I259J305D01*
G01X379593Y256353D01*
G02X380269Y256143I283J-283D01*
G03X381904Y257778I1378J257D01*
G02X381694Y258454I73J393D01*
G01X389810Y266570D01*
X417470D01*
X417472Y266568D01*
X426848D01*
X427756Y265660D01*
Y263600D01*
X426956Y262800D01*
X423400D01*
X423200Y262600D01*
Y258490D01*
X421605Y256895D01*
X421517Y256898D01*
G03X420063Y255444I-53J-1401D01*
G01X420066Y255356D01*
X419167Y254457D01*
X419026Y254585D01*
G03X417045Y252604I-942J-1039D01*
G01X417173Y252463D01*
X411271Y246561D01*
Y200649D01*
X416384Y195536D01*
Y142374D01*
X448292Y110466D01*
Y91250D01*
X448167Y91200D01*
G03Y88600I525J-1300D01*
G01X448292Y88550D01*
Y86669D01*
X448157Y86623D01*
G03Y83969I453J-1327D01*
G01X448292Y83923D01*
Y74965D01*
X448155Y74919D01*
G03X447688Y72523I444J-1330D01*
G02X447699Y71926I-260J-303D01*
G03X447562Y70013I952J-1030D01*
G03X447768Y69807I1089J883D01*
G02Y69198I-260J-305D01*
G03X447727Y69165I858J-1108D01*
G03X447226Y68025I900J-1075D01*
G03X448159Y66768I1401J65D01*
G01X448292Y66721D01*
Y56108D01*
G03Y53658I681J-1225D01*
G01Y52397D01*
X448142Y52358D01*
G03Y49642I350J-1358D01*
G01X448292Y49603D01*
Y48367D01*
X448145Y48327D01*
G03Y45623I372J-1352D01*
G01X448292Y45583D01*
Y37167D01*
X448132Y37134D01*
G03X447161Y36390I282J-1373D01*
G03X447307Y34900I1253J-629D01*
G03X447822Y34490I1106J861D01*
G02X447936Y33844I-168J-363D01*
G01X446592Y32500D01*
Y29257D01*
G02X445901Y28983I-400J0D01*
G03X443493Y27817I-1021J-961D01*
G03X443606Y27438I1386J207D01*
G03X446203Y27559I1274J584D01*
G01X446250Y27693D01*
X446592D01*
Y27000D01*
X448292Y25300D01*
Y20000D01*
X446392Y18100D01*
Y17778D01*
X446088D01*
X446028Y17863D01*
G03X445760Y15968I-1148J-804D01*
G02X446392Y15642I232J-326D01*
G01Y10539D01*
G02X445760Y10213I-400J0D01*
G03X444064Y7982I-880J-1091D01*
G03X446279Y9221I817J1140D01*
G02X446960Y9532I399J28D01*
G01X448292Y8200D01*
Y-4808D01*
X447222Y-5878D01*
X447187Y-5894D01*
G03X446458Y-6623I557J-1286D01*
G01X446442Y-6658D01*
X444816Y-8284D01*
X444744Y-8290D01*
G03X443384Y-9650I136J-1496D01*
G01X443378Y-9722D01*
X440270Y-12830D01*
X402440D01*
G37*
G36*
G01X391800Y336860D02*
X386213Y342447D01*
X386278Y342576D01*
G03X384394Y344460I-1251J633D01*
G01X384265Y344395D01*
X380757Y347903D01*
X380743Y347952D01*
G03X379789Y348906I-1346J-392D01*
G01X379740Y348920D01*
X379277Y349383D01*
G02X379524Y350064I283J283D01*
G03X378029Y351153I-127J1396D01*
G01X378053Y351045D01*
X377834Y350826D01*
X377560Y351100D01*
X374439D01*
G02X374039Y351491I0J400D01*
G03X371235I-1402J-31D01*
G02X370835Y351100I-400J9D01*
G01X367679D01*
G02X367279Y351491I0J400D01*
G03X364475I-1402J-31D01*
G02X364075Y351100I-400J9D01*
G01X360919D01*
G02X360519Y351491I0J400D01*
G03X357715I-1402J-31D01*
G02X357315Y351100I-400J9D01*
G01X354159D01*
G02X353759Y351491I0J400D01*
G03X351257Y352330I-1402J-31D01*
G02X350661Y352295I-314J248D01*
G01X350290Y352666D01*
X350347Y352792D01*
G03X348361Y354778I-1369J617D01*
G01X348235Y354721D01*
X347092Y355864D01*
Y370804D01*
X347093Y370814D01*
G03Y371104I-1495J145D01*
G01X347092Y371114D01*
Y376760D01*
X346619Y377233D01*
G02X346606Y377785I283J283D01*
G03X346720Y377919I-1009J974D01*
G03X344757Y379882I-1121J842D01*
G03X344623Y379768I840J-1123D01*
G02X344071Y379781I-269J296D01*
G01X343561Y380291D01*
X343580Y380376D01*
G03X342779Y381994I-1362J333D01*
G03X342760Y382002I-554J-1288D01*
G01X342723Y382018D01*
X342554Y382188D01*
X342638Y382271D01*
Y383264D01*
X342761Y383316D01*
G03X342160Y386010I-542J1293D01*
G03X341886Y385971I60J-1401D01*
G01X341777Y385944D01*
X340816Y386905D01*
Y387012D01*
G02X341438Y387344I400J-1D01*
G03X343619Y388547I780J1165D01*
G03X341102Y389358I-1401J-38D01*
G01X341046Y389288D01*
X340816Y389327D01*
G02X340601Y389438I67J394D01*
G01X338018Y392021D01*
Y465613D01*
X310021Y493610D01*
Y508310D01*
G02X310536Y508693I400J0D01*
G03Y511535I485J1421D01*
G02X310021Y511918I-115J383D01*
G01Y513226D01*
X308203Y515044D01*
Y516752D01*
X308312Y516808D01*
G03Y519306I-637J1249D01*
G01X308203Y519362D01*
Y527450D01*
X308377Y527473D01*
G03X308701Y530172I-179J1390D01*
G02X308740Y530691I322J237D01*
G01X309008Y530959D01*
Y532134D01*
G03Y534066I-1016J966D01*
G01Y536520D01*
X309017Y536549D01*
G03Y537365I-1342J408D01*
G01X309008Y537394D01*
Y547763D01*
X309017Y547792D01*
G03Y548608I-1342J408D01*
G01X309008Y548637D01*
Y550932D01*
G03X309502Y552027I-908J1068D01*
G03X308365Y553377I-1402J-27D01*
G01X308203Y553408D01*
Y554552D01*
X308312Y554608D01*
G03Y557106I-637J1249D01*
G01X308203Y557162D01*
Y565350D01*
X308351Y565390D01*
G03Y568096I-367J1353D01*
G01X308203Y568136D01*
Y569025D01*
X308196Y569032D01*
Y569504D01*
X308346Y569543D01*
G03X309215Y570214I-354J1357D01*
G01X309224Y570230D01*
G03X307579Y572240I-1232J670D01*
G02X307061Y572622I-118J382D01*
G01Y572968D01*
G02X307505Y573365I400J0D01*
G03Y576149I170J1392D01*
G02X307061Y576546I-44J397D01*
G01Y586575D01*
G02X307534Y586968I400J-1D01*
G03X309250Y588338I314J1366D01*
G03X308808Y589356I-1402J-4D01*
G02X308818Y589947I274J291D01*
G03X308717Y592134I-926J1053D01*
G02X308571Y592578I235J323D01*
G03X307579Y595056I-896J1079D01*
G02X307372Y595406I193J350D01*
G01Y605460D01*
G02X307857Y605850I400J-1D01*
G03Y608590I300J1370D01*
G02X307372Y608980I-85J391D01*
G01Y609220D01*
X311676Y613524D01*
X326363D01*
G02X326402Y613112I-321J-238D01*
G03X329106I1352J-655D01*
G02X329466Y613686I360J174D01*
G01X332735D01*
G02X333095Y613112I0J-400D01*
G03X335799I1352J-655D01*
G02X336159Y613686I360J174D01*
G01X346173D01*
G02X346522Y613091I0J-400D01*
G03X349144I1311J-734D01*
G02X349493Y613686I349J195D01*
G01X352865D01*
G02X353214Y613091I0J-400D01*
G03X355836I1311J-733D01*
G02X356185Y613686I349J195D01*
G01X359629D01*
G02X359974Y613084I0J-400D01*
G03X359741Y612515I1244J-842D01*
G03X362540Y611528I1477J-275D01*
G02X363243I352J-190D01*
G03X366043Y612511I1323J712D01*
G03X365809Y613084I-1478J-269D01*
G02X366154Y613686I345J202D01*
G01X369537D01*
G02X369896Y613112I-1J-400D01*
G03X371525Y611107I1238J-659D01*
G03X371997Y611348I-390J1346D01*
G02X372642Y611067I247J-315D01*
G03X373176Y612291I1397J119D01*
G02X372531Y612572I-247J315D01*
G03X372517Y612684I-1397J-118D01*
G03X372372Y613112I-1383J-230D01*
G02X372731Y613686I360J174D01*
G01X383359D01*
X384586Y612459D01*
Y611063D01*
Y606105D01*
G03X391788I3601J0D01*
G01Y611005D01*
G03X391787Y611095I-3601J5D01*
G03X391160Y613060I-3601J-66D01*
G02X391490Y613686I330J226D01*
G01X392888D01*
G02X393270Y613168I0J-400D01*
G03X396094I1412J-511D01*
G02X396476Y613686I382J118D01*
G01X399581D01*
G02X399958Y613154I0J-400D01*
G03X402794I1418J-496D01*
G02X403171Y613686I377J132D01*
G01X412967D01*
G02X413349Y613168I0J-400D01*
G03X416173I1412J-511D01*
G02X416555Y613686I382J118D01*
G01X418191D01*
X420477Y611400D01*
X420665D01*
X420713Y611370D01*
G03X422195I741J1190D01*
G01X422243Y611400D01*
X422606D01*
X424320Y613114D01*
X426246D01*
G02X426646Y612716I0J-400D01*
G03X429648I1501J-59D01*
G02X430048Y613114I400J-2D01*
G01X432939D01*
G02X433339Y612716I0J-400D01*
G03X436341I1501J-59D01*
G02X436741Y613114I400J-2D01*
G01X443292D01*
X444644Y611762D01*
Y611355D01*
X444495Y611316D01*
G03Y608412I385J-1452D01*
G01X444644Y608373D01*
Y606105D01*
X444495Y606066D01*
G03Y603162I385J-1452D01*
G01X444644Y603123D01*
Y595978D01*
X444660Y595962D01*
Y595052D01*
X444512Y595012D01*
G03Y592306I368J-1353D01*
G01X444660Y592266D01*
Y587115D01*
X444512Y587075D01*
G03Y584369I368J-1353D01*
G01X444660Y584329D01*
Y582648D01*
X449403Y577905D01*
Y576428D01*
G02X448845Y576061I-400J0D01*
G03Y573485I-554J-1288D01*
G02X449403Y573118I158J-367D01*
G01Y570826D01*
G02X448831Y570465I-400J0D01*
G03Y567935I-605J-1265D01*
G02X449403Y567574I172J-361D01*
G01Y554875D01*
G02X448934Y554481I-400J0D01*
G03Y551719I-242J-1381D01*
G02X449403Y551325I69J-394D01*
G01Y551088D01*
X449158D01*
X449117Y551107D01*
G03X448435Y551243I-607J-1264D01*
G03X447171Y549427I75J-1400D01*
G03X448894Y548494I1339J416D01*
G02X449403Y548110I109J-385D01*
G01Y538432D01*
G02X448876Y538053I-400J0D01*
G03X447538Y535643I-444J-1330D01*
G02X447578Y535065I-255J-308D01*
G03X447680Y532967I979J-1004D01*
G02X447640Y532328I-259J-305D01*
G03X448742Y529794I770J-1172D01*
G03X448876Y529834I-333J1362D01*
G02X449403Y529455I127J-379D01*
G01Y517075D01*
G02X448934Y516681I-400J0D01*
G03X447445Y514659I-242J-1381D01*
G02X447233Y514103I-356J-183D01*
G03X448722Y511798I502J-1309D01*
G02X449403Y511514I281J-284D01*
G01Y510586D01*
X448519Y509702D01*
Y497917D01*
X418602Y468000D01*
Y400193D01*
X414246Y395837D01*
Y365642D01*
X414182Y365578D01*
Y359928D01*
X422520Y351590D01*
Y350175D01*
G02X421974Y349803I-400J0D01*
G03Y347191I-510J-1306D01*
G02X422520Y346819I146J-372D01*
G01Y343878D01*
X422890Y343508D01*
X431392D01*
X431893Y343007D01*
Y337611D01*
X431142Y336860D01*
X391800D01*
G37*
G36*
G01X958858Y-10842D02*
X958621Y-10606D01*
X957482Y-9468D01*
Y-8978D01*
G02X957851Y-8579I400J0D01*
G03Y-5781I-86J1399D01*
G02X957482Y-5382I31J399D01*
G01Y-3240D01*
X957632Y-3201D01*
G03X958644Y-2181I-349J1358D01*
G03X957950Y-610I-1361J338D01*
G01Y8067D01*
G03Y10533I-667J1233D01*
G01Y11835D01*
X958081Y11883D01*
G03X957701Y14598I-481J1317D01*
G03X956954Y14444I-101J-1398D01*
G01X956824Y14376D01*
X956100Y15100D01*
Y15490D01*
G02X956506Y15890I400J0D01*
G03Y18224I777J1167D01*
G02X956100Y18624I-6J400D01*
G01Y26500D01*
X956465Y26865D01*
X956597Y26791D01*
G03X957900Y29273I686J1223D01*
G01Y30703D01*
X958050Y30742D01*
G03Y33458I-350J1358D01*
G01X957900Y33497D01*
Y34698D01*
G03Y37216I-617J1259D01*
G01Y49362D01*
X958004Y49400D01*
G03X958027Y52050I-446J1329D01*
G01X957985Y52065D01*
X957350Y52700D01*
Y53446D01*
X957517Y53475D01*
G03X957677Y56202I-235J1382D01*
G02X957697Y56747I303J262D01*
G01X957700Y56750D01*
Y66401D01*
X957855Y66437D01*
G03X958401Y68906I-319J1365D01*
G02X958505Y69329I378J131D01*
G03X957845Y71780I-905J1071D01*
G01X957700Y71808D01*
Y72484D01*
X957813Y72539D01*
G03X958100Y74875I-613J1261D01*
G01Y86023D01*
X958207Y86061D01*
G03X958234Y88718I-433J1333D01*
G01X958100Y88765D01*
Y90850D01*
X958044Y90906D01*
G02X958095Y91514I283J282D01*
G03X958415Y91830I-812J1143D01*
G03X957492Y94043I-1132J827D01*
G01X957350Y94068D01*
Y99200D01*
X958621Y100471D01*
Y105381D01*
X988492Y135252D01*
Y200942D01*
X990150Y202600D01*
Y203938D01*
G02X990833Y204220I400J0D01*
G03Y206200I993J990D01*
G02X990150Y206482I-283J282D01*
G01Y207837D01*
G02X990833Y208119I400J0D01*
G03X990534Y209655I993J990D01*
G01X990483Y209532D01*
X990150D01*
Y210158D01*
X991371Y211379D01*
X992429D01*
X993400Y212350D01*
Y248700D01*
X993710Y249010D01*
G02X994262Y249023I283J-283D01*
G03X996549Y249657I944J1037D01*
G01X996592Y249800D01*
X997329D01*
G02X997619Y249124I0J-400D01*
G03X999553I967J-1015D01*
G02X999843Y249800I290J276D01*
G01X1000579D01*
X1000622Y249657D01*
G03X1003308I1343J403D01*
G01X1003351Y249800D01*
X1004088D01*
G02X1004378Y249124I0J-400D01*
G03X1006312I967J-1015D01*
G02X1006602Y249800I290J276D01*
G01X1007339D01*
X1007382Y249657D01*
G03X1010068I1343J403D01*
G01X1010111Y249800D01*
X1010848D01*
G02X1011138Y249124I0J-400D01*
G03X1012443Y246748I967J-1015D01*
G03X1012618Y249414I-337J1361D01*
G01X1012491Y249464D01*
Y249800D01*
X1013045D01*
X1013145Y249700D01*
X1014123D01*
X1014171Y249570D01*
G03X1016799I1314J490D01*
G01X1016847Y249700D01*
X1017513D01*
G02X1017813Y249036I0J-400D01*
G03X1020267Y248126I1052J-927D01*
G01Y248328D01*
X1022902D01*
X1023834Y249260D01*
Y251054D01*
X1023940Y251160D01*
G02X1024534Y251128I283J-283D01*
G03X1026506Y253100I1091J881D01*
G02X1026474Y253694I251J311D01*
G01X1029191Y256411D01*
G02X1029869Y256188I283J-283D01*
G03X1031467Y257786I1386J212D01*
G02X1031244Y258464I60J395D01*
G01X1039240Y266460D01*
X1076865D01*
X1077616Y265709D01*
Y264816D01*
X1068135Y255335D01*
X1068026Y255362D01*
G03X1066330Y253666I-334J-1362D01*
G01X1066357Y253557D01*
X1060879Y248079D01*
Y200649D01*
X1065992Y195536D01*
Y142374D01*
X1097900Y110466D01*
Y91250D01*
X1097775Y91200D01*
G03Y88600I525J-1300D01*
G01X1097900Y88550D01*
Y86669D01*
X1097765Y86623D01*
G03Y83969I453J-1327D01*
G01X1097900Y83923D01*
Y74965D01*
X1097763Y74919D01*
G03X1097296Y72523I444J-1330D01*
G02X1097307Y71926I-260J-303D01*
G03X1097170Y70013I952J-1030D01*
G03X1097376Y69807I1089J883D01*
G02Y69198I-260J-305D01*
G03X1096834Y68025I859J-1108D01*
G03X1097767Y66768I1401J65D01*
G01X1097900Y66721D01*
Y56108D01*
G03Y53658I681J-1225D01*
G01Y52397D01*
X1097750Y52358D01*
G03Y49642I350J-1358D01*
G01X1097900Y49603D01*
Y48367D01*
X1097753Y48327D01*
G03Y45623I372J-1352D01*
G01X1097900Y45583D01*
Y37167D01*
X1097740Y37134D01*
G03X1096915Y34900I282J-1373D01*
G03X1097430Y34490I1106J861D01*
G02X1097544Y33844I-168J-363D01*
G01X1096200Y32500D01*
Y29257D01*
G02X1095509Y28983I-400J0D01*
G03X1093101Y27817I-1021J-961D01*
G03X1095811Y27559I1387J205D01*
G01X1095858Y27693D01*
X1096200D01*
Y27000D01*
X1097900Y25300D01*
Y20000D01*
X1096000Y18100D01*
Y17778D01*
X1095696D01*
X1095636Y17863D01*
G03X1095363Y15964I-1148J-804D01*
G02X1096000Y15641I237J-323D01*
G01Y10540D01*
G02X1095363Y10217I-400J0D01*
G03X1093228Y8508I-875J-1095D01*
G03X1095887Y9221I1261J614D01*
G02X1096568Y9532I399J28D01*
G01X1097900Y8200D01*
Y-3468D01*
X1096669Y-4699D01*
G02X1095987Y-4441I-283J283D01*
G03X1094393Y-6035I-1499J-95D01*
G02X1094651Y-6717I-25J-399D01*
G01X1093389Y-7979D01*
X1092950Y-7540D01*
X1085680D01*
X1085010Y-8210D01*
X1083640D01*
X1082760Y-7330D01*
X1079420D01*
X1078570Y-8180D01*
X1077090D01*
X1076510Y-7600D01*
Y-7540D01*
X1072964D01*
G02X1072564Y-7133I0J400D01*
G03X1069621Y-6684I-1502J25D01*
G02X1068954Y-6854I-384J112D01*
G01X1068700Y-6600D01*
X1065789D01*
X1065735Y-6483D01*
G03X1063003I-1366J-625D01*
G01X1062949Y-6600D01*
X1059096D01*
X1059042Y-6483D01*
G03X1056310I-1366J-625D01*
G01X1056256Y-6600D01*
X1052402D01*
X1052349Y-6483D01*
G03X1049617I-1366J-625D01*
G01X1049564Y-6600D01*
X1045950D01*
X1044199Y-8351D01*
X1044110Y-8333D01*
G03X1042513Y-9143I-310J-1367D01*
G01X1042469Y-9240D01*
X1041756D01*
G02X1041356Y-8841I0J400D01*
G01Y-8824D01*
X1041358Y-8810D01*
G03X1041398Y-8272I-3561J535D01*
G01Y-3372D01*
G03X1036896Y115I-3601J0D01*
G03X1034194Y-3372I899J-3487D01*
G01Y-8272D01*
G03X1034225Y-8747I3601J-3D01*
G02X1033829Y-9200I-396J-53D01*
G01X1032543D01*
X1032093Y-8750D01*
Y-7620D01*
X1029684Y-5211D01*
X1027952D01*
X1027097Y-6066D01*
Y-7962D01*
X1025859Y-9200D01*
X1023000D01*
X1022828Y-9372D01*
G02X1022172Y-9234I-283J283D01*
G03X1019574Y-10287I-1306J-508D01*
G02X1019205Y-10842I-369J-155D01*
G01X1015958D01*
G02X1015583Y-10304I0J400D01*
G03X1012851Y-9072I-1410J518D01*
G02X1012148I-352J190D01*
G03X1009416Y-10304I-1322J-714D01*
G02X1009041Y-10842I-375J-138D01*
G01X1002610D01*
G02X1002226Y-10332I0J400D01*
G03X999348I-1439J431D01*
G02X998964Y-10842I-384J-110D01*
G01X995879D01*
G02X995504Y-10304I0J400D01*
G03X992684I-1410J518D01*
G02X992309Y-10842I-375J-138D01*
G01X982493D01*
G02X982118Y-10304I0J400D01*
G03X979298I-1410J518D01*
G02X978923Y-10842I-375J-138D01*
G01X975838D01*
G02X975454Y-10332I0J400D01*
G03X972576I-1439J431D01*
G02X972192Y-10842I-384J-110D01*
G01X958858D01*
G37*
G36*
G01X1031717Y335500D02*
X1028890Y338327D01*
X1028995Y338466D01*
G03X1029243Y339002I-1120J843D01*
G03X1027031Y340429I-1368J307D01*
G01X1026892Y340325D01*
X1023647Y343570D01*
Y343654D01*
G03X1022239Y345062I-1402J6D01*
G01X1022155D01*
X1019526Y347691D01*
G02X1019585Y348306I283J283D01*
G03X1020257Y349343I-720J1203D01*
G03X1018701Y350901I-1392J166D01*
G03X1017554Y350007I163J-1392D01*
G01X1017517Y349916D01*
X1016877D01*
G02X1016561Y350561I0J400D01*
G03X1014409I-1076J899D01*
G02X1014093Y349916I-316J-245D01*
G01X1013453D01*
X1013416Y350007D01*
G03X1010794I-1311J-498D01*
G01X1010757Y349916D01*
X1010117D01*
G02X1009801Y350561I0J400D01*
G03X1007649I-1076J899D01*
G02X1007333Y349916I-316J-245D01*
G01X1006693D01*
X1006656Y350007D01*
G03X1004034I-1311J-498D01*
G01X1003997Y349916D01*
X1003357D01*
G02X1003041Y350561I0J400D01*
G03X1003346Y351221I-1077J898D01*
G03X1000972Y352449I-1381J239D01*
G03X1000662Y351977I993J-990D01*
G02X1000012Y351854I-367J160D01*
G01X999903Y351963D01*
X998130D01*
X996704Y353389D01*
Y370856D01*
G03Y371062I-1498J103D01*
G01Y374823D01*
X996609Y374918D01*
X996602Y374990D01*
G03X995337Y376256I-1396J-130D01*
G01X995265Y376263D01*
X994851Y376677D01*
G02X995150Y377359I283J283D01*
G03X993805Y378704I56J1401D01*
G02X993123Y378405I-400J-16D01*
G01X992577Y378951D01*
G02X992631Y379561I283J282D01*
G03X992285Y382034I-805J1148D01*
G01X992150Y382081D01*
Y383238D01*
X992285Y383284D01*
G03X991884Y386010I-459J1325D01*
G02X991501Y386409I17J400D01*
G01Y386769D01*
X991351Y386919D01*
X991562Y387129D01*
X991658Y387117D01*
G03X990441Y388727I168J1392D01*
G02X989763Y388507I-395J63D01*
G01X987606Y390664D01*
Y398080D01*
X987618Y398092D01*
Y465613D01*
X960493Y492738D01*
Y502628D01*
X960506Y502640D01*
Y508209D01*
X960303Y508412D01*
X960505Y508614D01*
X960591Y508612D01*
G03X962088Y510472I38J1502D01*
G03X959571Y511181I-1459J-358D01*
G02X958895Y511469I-276J289D01*
G01Y511950D01*
X958930Y512001D01*
G03X958249Y514113I-1156J793D01*
G01X958207Y514128D01*
X957989Y514346D01*
Y516846D01*
G03X958671Y517860I-706J1211D01*
G03X958020Y519250I-1388J197D01*
G01Y527469D01*
X958168Y527509D01*
G03Y530217I-362J1354D01*
G01X958020Y530257D01*
Y531684D01*
X958142Y531806D01*
X958176Y531821D01*
G03X958156Y534388I-576J1279D01*
G01X958122Y534402D01*
X958020Y534502D01*
Y535764D01*
G03Y538150I-737J1193D01*
G01Y547007D01*
G03Y549393I-737J1193D01*
G01Y550627D01*
X958128Y550665D01*
G03X958155Y553326I-427J1335D01*
G01X958020Y553373D01*
Y554664D01*
G03Y557050I-737J1193D01*
G01Y559618D01*
X956804Y560834D01*
Y565035D01*
G02X957114Y565425I400J0D01*
G03Y568061I478J1318D01*
G02X956804Y568451I90J390D01*
G01Y569142D01*
G02X957292Y569532I400J0D01*
G03Y572268I308J1368D01*
G02X956804Y572658I-88J390D01*
G01Y572957D01*
G02X957222Y573356I400J0D01*
G03Y576158I61J1401D01*
G02X956804Y576557I-18J399D01*
G01Y586550D01*
G02X957248Y586947I400J0D01*
G03X958829Y588051I208J1387D01*
G03X958416Y589356I-1373J283D01*
G02X958426Y589947I274J291D01*
G03X958325Y592134I-926J1053D01*
G02X958179Y592578I235J323D01*
G03X957048Y595039I-896J1079D01*
G02X956804Y595407I156J368D01*
G01Y605508D01*
G02X957319Y605891I400J0D01*
G03X958652Y606134I446J1329D01*
G03X957819Y608621I-887J1086D01*
G02X957551Y609303I15J400D01*
G01X958738Y610490D01*
Y612046D01*
X961638Y614946D01*
X1028255D01*
G02X1028593Y614332I0J-400D01*
G03X1030961I1184J-751D01*
G02X1031299Y614946I338J214D01*
G01X1031833D01*
G02X1032158Y614314I-1J-400D01*
G03X1033741Y612169I1142J-814D01*
G02X1034259Y611713I126J-380D01*
G03X1034194Y611028I3536J-681D01*
G01Y606128D01*
G03X1034202Y605882I3601J-6D01*
G03X1041398Y606105I3595J223D01*
G01Y611005D01*
G03X1041376Y611406I-3601J4D01*
G03X1039511Y614194I-3581J-378D01*
G02X1039701Y614946I190J352D01*
G01X1043245D01*
X1043610Y614581D01*
G02X1043530Y613953I-283J-283D01*
G03X1043605Y611322I761J-1295D01*
G03X1045765Y612947I686J1336D01*
G02X1046160Y613409I395J62D01*
G01X1049115D01*
G02X1049510Y612947I0J-400D01*
G03X1052458I1474J-289D01*
G02X1052853Y613409I395J62D01*
G01X1062500D01*
G02X1062894Y612940I0J-400D01*
G03X1065844I1475J-283D01*
G02X1066238Y613409I394J69D01*
G01X1069295D01*
G02X1069687Y612931I0J-400D01*
G03X1069661Y612608I1375J-273D01*
G03X1072463I1401J-48D01*
G03X1072437Y612931I-1401J50D01*
G02X1072829Y613409I392J78D01*
G01X1075886D01*
G02X1076280Y612940I0J-400D01*
G03X1079230I1475J-283D01*
G02X1079624Y613409I394J69D01*
G01X1082579D01*
G02X1082973Y612940I0J-400D01*
G03X1085923I1475J-283D01*
G02X1086317Y613409I394J69D01*
G01X1090422D01*
X1090465Y613452D01*
X1092279D01*
X1092948Y612782D01*
Y585023D01*
X1098072Y579899D01*
Y576375D01*
X1097877Y576177D01*
X1097802Y576172D01*
G03Y573374I96J-1399D01*
G01X1097877Y573369D01*
X1098072Y573171D01*
Y570994D01*
G02X1097722Y570598I-400J1D01*
G03Y567802I112J-1398D01*
G02X1098072Y567406I-50J-397D01*
G01Y554492D01*
X1097925Y554451D01*
G03Y551749I375J-1351D01*
G01X1098072Y551708D01*
Y551255D01*
X1097931Y551232D01*
G03X1097903Y548458I188J-1389D01*
G01X1098072Y548431D01*
Y538136D01*
X1097893Y538117D01*
G03X1097279Y535546I147J-1394D01*
G02X1097290Y534909I-237J-323D01*
G03X1096759Y533872I870J-1100D01*
G03X1097170Y532816I1401J-63D01*
G02X1097127Y532239I-297J-268D01*
G03X1097209Y530011I891J-1083D01*
G03X1097890Y529760I809J1145D01*
G02X1098072Y529561I-18J-199D01*
G01Y516692D01*
X1097925Y516651D01*
G03X1097053Y514659I375J-1351D01*
G02X1096845Y514105I-356J-182D01*
G03X1097615Y511419I498J-1311D01*
G02X1098072Y511023I57J-396D01*
G01Y497957D01*
X1068202Y468087D01*
Y400102D01*
X1067050Y398950D01*
X1065400Y397301D01*
Y397272D01*
X1063664Y395536D01*
Y395502D01*
X1062715Y394553D01*
G02X1062047Y394726I-283J282D01*
G03X1059595Y395229I-1353J-367D01*
G03X1059790Y393287I1099J-870D01*
G02X1059815Y392699I-258J-306D01*
G01X1059402Y392286D01*
Y391007D01*
X1059388Y390972D01*
G03Y389948I1306J-512D01*
G01X1059402Y389913D01*
Y387107D01*
X1059388Y387072D01*
G03Y386048I1306J-512D01*
G01X1059402Y386013D01*
Y383207D01*
X1059388Y383172D01*
G03Y382148I1306J-512D01*
G01X1059402Y382113D01*
Y379307D01*
X1059388Y379272D01*
G03Y378248I1306J-512D01*
G01X1059402Y378213D01*
Y375407D01*
X1059388Y375372D01*
G03Y374348I1306J-512D01*
G01X1059402Y374313D01*
Y366200D01*
X1060542Y365060D01*
G02X1060436Y364418I-283J-283D01*
G03X1062313Y362541I619J-1258D01*
G02X1062955Y362647I359J-177D01*
G01X1072800Y352802D01*
Y349715D01*
G02X1072105Y349445I-400J0D01*
G03Y347549I-1033J-948D01*
G02X1072800Y347279I295J-270D01*
G01Y341872D01*
X1074181Y340491D01*
X1081189D01*
X1081688Y339992D01*
Y336066D01*
X1081123Y335500D01*
X1031717D01*
G37*
G36*
G01X1443529Y267984D02*
G03X1442983Y268529I-1225J-682D01*
G02Y269228I195J349D01*
G03X1442985Y271679I-680J1226D01*
G02Y272378I195J350D01*
G03X1443529Y272922I-681J1225D01*
G02X1444229I350J-194D01*
G03X1446135Y274828I1225J681D01*
G02Y275528I194J350D01*
G03X1446679Y276071I-680J1226D01*
G02X1447378I349J-194D01*
G03X1449285Y277978I1225J682D01*
G02Y278677I194J350D01*
G03X1449828Y279221I-683J1224D01*
G02X1450528I350J-194D01*
G03X1452434Y281128I1225J681D01*
G02Y281827I194J349D01*
G03X1452978Y282370I-680J1226D01*
G02X1453677I349J-195D01*
G03X1455583Y284277I1225J682D01*
G02Y284977I194J350D01*
G03X1456127Y285521I-681J1225D01*
G02X1456827I350J-194D01*
G03X1459277I1225J681D01*
G02X1459977I350J-194D01*
G03X1460521Y284977I1225J681D01*
G02Y284277I-194J-350D01*
G03Y281827I681J-1225D01*
G02Y281127I-194J-350D01*
G03X1459977Y280583I681J-1225D01*
G02X1459277I-350J194D01*
G03X1457370Y278677I-1225J-681D01*
G02Y277978I-194J-350D01*
G03X1456827Y277434I683J-1224D01*
G02X1456127I-350J194D01*
G03X1454221Y275528I-1225J-681D01*
G02Y274828I-194J-350D01*
G03X1453677Y274285I680J-1226D01*
G02X1452978I-350J194D01*
G03X1451071Y272378I-1225J-682D01*
G02Y271679I-194J-350D01*
G03X1450528Y271135I683J-1224D01*
G02X1449828I-350J194D01*
G03X1447922Y269229I-1225J-681D01*
G02Y268529I-194J-350D01*
G03X1447378Y267986I680J-1226D01*
G02X1446679I-350J194D01*
G03X1444228Y267984I-1225J-682D01*
G02X1443529I-350J194D01*
G37*
G36*
G01X1611816Y113022D02*
G03X1611272Y113566I-1225J-681D01*
G02Y114266I194J350D01*
G03X1611273Y116716I-681J1225D01*
G02Y117415I194J349D01*
G03X1611816Y117959I-683J1224D01*
G02X1612516I350J-194D01*
G03X1614966I1225J681D01*
G02X1615665I350J-195D01*
G03X1616223Y117408I1225J682D01*
G02X1616214Y116699I-190J-352D01*
G03X1616155Y114230I634J-1250D01*
G02X1616164Y113540I-198J-348D01*
G03X1615665Y113023I726J-1200D01*
G02X1614966I-349J194D01*
G03X1612516Y113022I-1225J-682D01*
G02X1611816I-350J194D01*
G37*
G36*
G01X1655910Y122471D02*
G03X1655367Y123015I-1226J-680D01*
G02Y123714I194J350D01*
G03X1653460Y125621I-681J1226D01*
G02X1652761I-349J194D01*
G03X1652217Y126164I-1224J-683D01*
G02Y126864I194J350D01*
G03Y129314I-681J1225D01*
G02Y130014I194J350D01*
G03X1652761Y130557I-680J1226D01*
G02X1653460I350J-194D01*
G03X1655910Y130558I1225J682D01*
G02X1656610I350J-194D01*
G03X1659060I1225J681D01*
G02X1659760I350J-194D01*
G03X1660304Y130014I1225J681D01*
G02Y129314I-194J-350D01*
G03Y126864I681J-1225D01*
G02Y126164I-194J-350D01*
G03X1660303Y123714I681J-1225D01*
G02Y123015I-194J-350D01*
G03X1659760Y122471I683J-1224D01*
G02X1659060I-350J194D01*
G03X1656610I-1225J-681D01*
G02X1655910I-350J194D01*
G37*
%LPC*%
G75*
G36*
G01X58175Y255329D02*
G02X56785Y255306I-675J-1229D01*
G03X56753Y256011I-204J344D01*
G02X58183Y256034I692J1445D01*
G03X58175Y255329I184J-355D01*
G37*
G36*
G01X325676Y104251D02*
G03X326253Y104144I338J214D01*
G02X325908Y102270I839J-1123D01*
G03X325331Y102377I-338J-214D01*
G02X325676Y104251I-839J1123D01*
G37*
G36*
G01X364495Y91490D02*
G03X363904I-295J-269D01*
G02Y93510I-1112J1010D01*
G03X364495I296J269D01*
G02Y91490I1112J-1010D01*
G37*
G36*
G01X364129Y86483D02*
G03X363540I-295J-271D01*
G02Y88517I-1105J1017D01*
G03X364129I294J271D01*
G02Y86483I1105J-1017D01*
G37*
G36*
G01X376347Y85404D02*
G03Y84850I288J-277D01*
G02X374327I-1010J-973D01*
G03Y85404I-288J277D01*
G02X376347I1010J973D01*
G37*
G36*
G01X358743Y69924D02*
G03Y69346I277J-289D01*
G02X356801I-971J-1011D01*
G03Y69924I-277J289D01*
G02X358743I971J1011D01*
G37*
G36*
G01X358702Y51293D02*
G03Y50699I268J-297D01*
G02X356822I-940J-1040D01*
G03Y51293I-268J297D01*
G02X358702I940J1040D01*
G37*
G36*
G01X363196Y46006D02*
G03X362587I-305J-258D01*
G02Y47822I-1069J908D01*
G03X363196I305J258D01*
G02Y46006I1069J-908D01*
G37*
G36*
G01X359577Y32318D02*
G03X359571Y31740I273J-292D01*
G02X357634Y31760I-979J-1004D01*
G03X357640Y32338I-273J292D01*
G02X359577Y32318I979J1004D01*
G37*
G36*
G01X373192Y18898D02*
G03X373437Y19395I-136J376D01*
G02X375251Y18501I1336J424D01*
G03X375006Y18004I136J-376D01*
G02X373192Y18898I-1336J-424D01*
G37*
G36*
G01X364276Y15953D02*
G03X363719Y15947I-275J-290D01*
G02X363697Y18103I-1057J1067D01*
G03X364254Y18109I275J290D01*
G02X364276Y15953I1057J-1067D01*
G37*
G36*
G01X358463Y13303D02*
G03Y12725I277J-289D01*
G02X356521I-971J-1011D01*
G03Y13303I-277J289D01*
G02X358463I971J1011D01*
G37*
G36*
G01X375007Y75306D02*
G02X373577I-715J-1206D01*
G03Y75994I-204J344D01*
G02X375007I715J1206D01*
G03Y75306I204J-344D01*
G37*
G36*
G01X381727Y61396D02*
G02X380164Y61350I-747J-1186D01*
G03X380145Y62014I-233J326D01*
G02X381708Y62060I747J1186D01*
G03X381727Y61396I233J-326D01*
G37*
G36*
G01X362540Y54128D02*
G02Y55556I-1322J714D01*
G03X363243I352J190D01*
G02Y54128I1322J-714D01*
G03X362540I-351J-190D01*
G37*
G36*
G01Y35228D02*
G02Y36656I-1322J714D01*
G03X363243I352J190D01*
G02Y35228I1322J-714D01*
G03X362540I-351J-190D01*
G37*
G36*
G01X381635Y26053D02*
G02X379949I-843J-1120D01*
G03Y26692I-241J320D01*
G02X381635I843J1120D01*
G03Y26053I241J-320D01*
G37*
G36*
G01X362540Y8400D02*
G02Y9828I-1322J714D01*
G03X363243I352J190D01*
G02Y8400I1322J-714D01*
G03X362540I-351J-190D01*
G37*
G36*
G01X376959Y5723D02*
G02Y7277I-1167J777D01*
G03X377625I333J222D01*
G02Y5723I1167J-777D01*
G03X376959I-333J-222D01*
G37*
G36*
G01X362540Y-2572D02*
G02Y-1144I-1322J714D01*
G03X363243I352J190D01*
G02Y-2572I1322J-714D01*
G03X362540I-351J-190D01*
G37*
G36*
G01X357780Y589938D02*
G03Y589367I280J-286D01*
G02X355816I-982J-1001D01*
G03Y589938I-280J285D01*
G02X357780I982J1001D01*
G37*
G36*
G01X363180Y584675D02*
G03X362603I-289J-277D01*
G02Y586753I-1085J1039D01*
G03X363180I289J277D01*
G02Y584675I1085J-1039D01*
G37*
G36*
G01X358734Y571001D02*
G03Y570446I288J-278D01*
G02X356714I-1010J-972D01*
G03Y571001I-288J277D01*
G02X358734I1010J972D01*
G37*
G36*
G01X358510Y552100D02*
G03Y551522I277J-289D01*
G02X356568I-971J-1011D01*
G03Y552100I-277J289D01*
G02X358510I971J1011D01*
G37*
G36*
G01X363180Y546875D02*
G03X362603I-289J-277D01*
G02Y548953I-1085J1039D01*
G03X363180I289J277D01*
G02Y546875I1085J-1039D01*
G37*
G36*
G01X375837Y544726D02*
G03X375845Y545304I-272J293D01*
G02X377784Y545277I984J999D01*
G03X377776Y544699I272J-293D01*
G02X375837Y544726I-984J-999D01*
G37*
G36*
G01X358688Y533045D02*
G03Y532501I293J-272D01*
G02X356634I-1027J-955D01*
G03Y533045I-293J272D01*
G02X358688I1027J955D01*
G37*
G36*
G01X376202Y517883D02*
G03Y517329I288J-277D01*
G02X374182I-1010J-973D01*
G03Y517883I-288J277D01*
G02X376202I1010J973D01*
G37*
G36*
G01X362698Y516269D02*
G03X363249Y516258I281J284D01*
G02X363209Y514083I1016J-1107D01*
G03X362658Y514094I-281J-284D01*
G02X362698Y516269I-1016J1107D01*
G37*
G36*
G01X363180Y509075D02*
G03X362603I-289J-277D01*
G02Y511153I-1085J1039D01*
G03X363180I289J277D01*
G02Y509075I1085J-1039D01*
G37*
G36*
G01X410478Y364173D02*
G03X410500Y364728I-277J289D01*
G02X410576Y366671I1047J932D01*
G03Y367249I-277J289D01*
G02X412518I971J1011D01*
G03Y366671I277J-289D01*
G02X412516Y364647I-971J-1011D01*
G03X412494Y364092I277J-289D01*
G02X410478Y364173I-1047J-932D01*
G37*
G36*
G01X362540Y603900D02*
G02Y605328I-1322J714D01*
G03X363243I352J190D01*
G02Y603900I1322J-714D01*
G03X362540I-351J-190D01*
G37*
G36*
G01X375160Y594586D02*
G02X375066Y592831I1044J-936D01*
G03X374444Y592864I-324J-234D01*
G02X372370Y592849I-1044J936D01*
G03X371761Y592825I-294J-271D01*
G02X371689Y594642I-1102J866D01*
G03X372298Y594666I294J271D01*
G02X374538Y594619I1102J-866D01*
G03X375160Y594586I324J234D01*
G37*
G36*
G01X363286Y592928D02*
G02Y594356I-1322J714D01*
G03X363989I351J190D01*
G02Y592928I1322J-714D01*
G03X363286I-351J-190D01*
G37*
G36*
G01X362540Y574028D02*
G02Y575456I-1322J714D01*
G03X363243I352J190D01*
G02Y574028I1322J-714D01*
G03X362540I-351J-190D01*
G37*
G36*
G01Y566100D02*
G02Y567528I-1322J714D01*
G03X363243I352J190D01*
G02Y566100I1322J-714D01*
G03X362540I-351J-190D01*
G37*
G36*
G01X362601Y555058D02*
G02Y556626I-1281J784D01*
G03X363284I341J208D01*
G02Y555058I1281J-784D01*
G03X362601I-341J-208D01*
G37*
G36*
G01X975284Y104251D02*
G03X975861Y104144I338J214D01*
G02X975516Y102270I839J-1123D01*
G03X974939Y102377I-338J-214D01*
G02X975284Y104251I-839J1123D01*
G37*
G36*
G01X1014103Y91490D02*
G03X1013512I-296J-269D01*
G02Y93510I-1112J1010D01*
G03X1014103I296J269D01*
G02Y91490I1112J-1010D01*
G37*
G36*
G01X1013737Y86483D02*
G03X1013148I-295J-271D01*
G02Y88517I-1105J1017D01*
G03X1013737I295J271D01*
G02Y86483I1105J-1017D01*
G37*
G36*
G01X1025955Y85404D02*
G03Y84850I288J-277D01*
G02X1023935I-1010J-973D01*
G03Y85404I-288J277D01*
G02X1025955I1010J973D01*
G37*
G36*
G01X1008351Y69924D02*
G03Y69346I277J-289D01*
G02X1006409I-971J-1011D01*
G03Y69924I-277J289D01*
G02X1008351I971J1011D01*
G37*
G36*
G01X1008310Y51293D02*
G03Y50699I268J-297D01*
G02X1006430I-940J-1040D01*
G03Y51293I-268J297D01*
G02X1008310I940J1040D01*
G37*
G36*
G01X1012788Y45875D02*
G03X1012211I-288J-277D01*
G02Y47953I-1085J1039D01*
G03X1012788I288J277D01*
G02Y45875I1085J-1039D01*
G37*
G36*
G01X1009185Y32318D02*
G03X1009179Y31740I273J-292D01*
G02X1007242Y31760I-979J-1004D01*
G03X1007248Y32338I-273J292D01*
G02X1009185Y32318I979J1004D01*
G37*
G36*
G01X1013884Y15953D02*
G03X1013327Y15947I-275J-290D01*
G02X1013305Y18103I-1057J1067D01*
G03X1013862Y18109I275J290D01*
G02X1013884Y15953I1057J-1067D01*
G37*
G36*
G01X1047394Y15661D02*
G03X1046925Y15287I-70J-394D01*
G02X1045768Y16738I-1400J70D01*
G03X1046237Y17112I70J394D01*
G02X1047394Y15661I1400J-70D01*
G37*
G36*
G01X1008071Y13303D02*
G03Y12725I277J-289D01*
G02X1006129I-971J-1011D01*
G03Y13303I-277J289D01*
G02X1008071I971J1011D01*
G37*
G36*
G01X1026779Y7498D02*
G03X1027385Y7467I316J245D01*
G02X1027291Y5642I1015J-967D01*
G03X1026685Y5673I-316J-245D01*
G02X1026779Y7498I-1015J967D01*
G37*
G36*
G01X1024615Y75306D02*
G02X1023185I-715J-1206D01*
G03Y75994I-204J344D01*
G02X1024615I715J1206D01*
G03Y75306I204J-344D01*
G37*
G36*
G01X1012148Y54128D02*
G02Y55556I-1322J714D01*
G03X1012851I352J190D01*
G02Y54128I1322J-714D01*
G03X1012148I-352J-190D01*
G37*
G36*
G01Y35228D02*
G02Y36656I-1322J714D01*
G03X1012851I352J190D01*
G02Y35228I1322J-714D01*
G03X1012148I-352J-190D01*
G37*
G36*
G01Y27300D02*
G02Y28728I-1322J714D01*
G03X1012851I352J190D01*
G02Y27300I1322J-714D01*
G03X1012148I-352J-190D01*
G37*
G36*
G01X1031207Y24330D02*
G02X1029654Y24304I-757J-1180D01*
G03X1029643Y24970I-227J329D01*
G02X1031196Y24996I757J1180D01*
G03X1031207Y24330I227J-329D01*
G37*
G36*
G01X1025003Y18760D02*
G02X1023684Y19551I-1263J-610D01*
G03X1024028Y20124I-16J399D01*
G02X1025347Y19333I1263J610D01*
G03X1025003Y18760I16J-399D01*
G37*
G36*
G01X1012148Y8400D02*
G02Y9828I-1322J714D01*
G03X1012851I352J190D01*
G02Y8400I1322J-714D01*
G03X1012148I-352J-190D01*
G37*
G36*
G01Y-2572D02*
G02Y-1144I-1322J714D01*
G03X1012851I352J190D01*
G02Y-2572I1322J-714D01*
G03X1012148I-352J-190D01*
G37*
G36*
G01X1024477Y592640D02*
G03X1023923I-277J-288D01*
G02X1021901Y592720I-973J1010D01*
G03X1021313Y592731I-299J-266D01*
G02X1021349Y594630I-1013J969D01*
G03X1021937Y594619I299J266D01*
G02X1023923Y594660I1013J-969D01*
G03X1024477I277J288D01*
G02Y592640I973J-1010D01*
G37*
G36*
G01X1007377Y589955D02*
G03Y589377I277J-289D01*
G02X1005435I-971J-1011D01*
G03Y589955I-277J289D01*
G02X1007377I971J1011D01*
G37*
G36*
G01X1012788Y584675D02*
G03X1012211I-288J-277D01*
G02Y586753I-1085J1039D01*
G03X1012788I288J277D01*
G02X1014956Y586755I1085J-1039D01*
G03X1015517Y586739I289J277D01*
G02Y584689I956J-1025D01*
G03X1014956Y584673I-272J-293D01*
G02X1012788Y584675I-1083J1041D01*
G37*
G36*
G01X1008303Y570999D02*
G03Y570421I277J-289D01*
G02X1006361I-971J-1011D01*
G03Y570999I-277J289D01*
G02X1008303I971J1011D01*
G37*
G36*
G01X1008118Y552100D02*
G03Y551522I277J-289D01*
G02X1006176I-971J-1011D01*
G03Y552100I-277J289D01*
G02X1008118I971J1011D01*
G37*
G36*
G01X1012788Y546875D02*
G03X1012211I-288J-277D01*
G02Y548953I-1085J1039D01*
G03X1012788I288J277D01*
G02Y546875I1085J-1039D01*
G37*
G36*
G01X1025534Y542016D02*
G03X1025512Y542615I-276J290D01*
G02Y544785I888J1085D01*
G03X1025534Y545384I-254J309D01*
G02X1027388Y545315I966J1016D01*
G03X1027366Y544716I254J-309D01*
G02Y542684I-966J-1016D01*
G03X1027388Y542085I276J-290D01*
G02X1027510Y540027I-888J-1085D01*
G03Y539473I288J-277D01*
G02X1025490I-1010J-973D01*
G03Y540027I-288J277D01*
G02X1025534Y542016I1010J973D01*
G37*
G36*
G01X1008178Y533126D02*
G03Y532548I277J-289D01*
G02X1006236I-971J-1011D01*
G03Y533126I-277J289D01*
G02X1008178I971J1011D01*
G37*
G36*
G01X1025810Y517883D02*
G03Y517329I288J-277D01*
G02X1023790I-1010J-973D01*
G03Y517883I-288J277D01*
G02X1025810I1010J973D01*
G37*
G36*
G01X1012306Y516269D02*
G03X1012857Y516258I281J284D01*
G02X1012817Y514083I1016J-1107D01*
G03X1012266Y514094I-281J-284D01*
G02X1012306Y516269I-1016J1107D01*
G37*
G36*
G01X1012788Y509075D02*
G03X1012211I-288J-277D01*
G02Y511153I-1085J1039D01*
G03X1012788I288J277D01*
G02Y509075I1085J-1039D01*
G37*
G36*
G01X1012148Y611528D02*
G02Y612956I-1322J714D01*
G03X1012851I352J190D01*
G02Y611528I1322J-714D01*
G03X1012148I-352J-190D01*
G37*
G36*
G01X1022726Y612019D02*
G02X1021807Y610859I474J-1319D01*
G03X1021274Y611281I-397J46D01*
G02X1022193Y612441I-474J1319D01*
G03X1022726Y612019I397J-46D01*
G37*
G36*
G01X1012148Y603900D02*
G02Y605328I-1322J714D01*
G03X1012851I352J190D01*
G02Y603900I1322J-714D01*
G03X1012148I-352J-190D01*
G37*
G36*
G01X1012894Y592928D02*
G02Y594356I-1322J714D01*
G03X1013597I352J190D01*
G02Y592928I1322J-714D01*
G03X1012894I-352J-190D01*
G37*
G36*
G01X1012148Y574028D02*
G02Y575456I-1322J714D01*
G03X1012851I352J190D01*
G02Y574028I1322J-714D01*
G03X1012148I-352J-190D01*
G37*
G36*
G01Y566100D02*
G02Y567528I-1322J714D01*
G03X1012851I352J190D01*
G02Y566100I1322J-714D01*
G03X1012148I-352J-190D01*
G37*
G36*
G01X1012209Y555058D02*
G02Y556626I-1281J784D01*
G03X1012892I341J208D01*
G02Y555058I1281J-784D01*
G03X1012209I-342J-208D01*
G37*
G54D76*
X388187Y88678D03*
Y50878D03*
Y69778D03*
Y13078D03*
Y31978D03*
Y551879D03*
Y589679D03*
Y570755D03*
Y514079D03*
Y532955D03*
X1037797Y50878D03*
Y88678D03*
Y69778D03*
Y13078D03*
Y31978D03*
Y551879D03*
Y589679D03*
Y570755D03*
Y514079D03*
Y532955D03*
G54D47*
X321061Y-7108D03*
X327754Y-1743D03*
X324407Y-4536D03*
X314368Y-7108D03*
X311021Y-4536D03*
X334447Y-1743D03*
X354526Y-7108D03*
X354525Y-1742D03*
X347833Y-1743D03*
X344486Y-4536D03*
X337793D03*
X341140Y-7108D03*
X334447D03*
X321061Y92757D03*
X327754Y87392D03*
X324407Y89964D03*
Y84599D03*
X314368Y92657D03*
X311021Y84714D03*
X334447Y87392D03*
X331100Y89964D03*
X354415Y92757D03*
Y87392D03*
X351179Y89964D03*
X347833Y87392D03*
X344486Y84714D03*
Y89964D03*
X337793Y84599D03*
X341140Y92757D03*
X334447D03*
X398029Y28007D03*
X408069D03*
X404722Y-9901D03*
X401375Y-1743D03*
X414761Y-7108D03*
X404722Y-4536D03*
X414761Y-1743D03*
X408068Y-7108D03*
X394682Y11792D03*
X394683Y-2200D03*
X404722Y89964D03*
X401375Y87392D03*
X414761Y92757D03*
X398029Y65807D03*
Y89964D03*
X404722Y84599D03*
X414761Y87392D03*
X408069Y65807D03*
X408068Y92757D03*
X394682Y87392D03*
Y49592D03*
X431494Y28007D03*
X424801D03*
X438187Y-4536D03*
X431494Y-9901D03*
X444880Y-4536D03*
X428147Y-1743D03*
X421454Y-7108D03*
X434840Y-1743D03*
X424801Y-9786D03*
X438187D03*
Y84714D03*
X431494Y65807D03*
Y89964D03*
X444880D03*
Y84714D03*
X428147Y87392D03*
X421454Y92757D03*
X434840Y87392D03*
X424801Y65807D03*
Y89964D03*
X438187D03*
X321061Y518157D03*
X327754Y512792D03*
X324407Y515364D03*
Y509999D03*
X314368Y518057D03*
X334447Y512792D03*
X331100Y515364D03*
X354526Y518157D03*
X354307Y512792D03*
X351179Y515364D03*
X347833Y512792D03*
X344486Y510114D03*
Y515364D03*
X337793Y509999D03*
X341140Y518157D03*
X334447D03*
X321061Y607292D03*
X324407Y604499D03*
Y609864D03*
X314368Y607292D03*
X311021Y609864D03*
X331100Y604614D03*
X354526Y607292D03*
X351179Y604499D03*
X344486Y609864D03*
Y604614D03*
X337793Y609864D03*
X341140Y607292D03*
X334447D03*
X404722Y515364D03*
X401375Y512792D03*
X414761Y518157D03*
X398029Y529007D03*
Y515364D03*
X404722Y509999D03*
X414761Y512792D03*
X408068Y518157D03*
X408069Y529007D03*
X394682Y512792D03*
X394595Y537058D03*
X398029Y566807D03*
X408069D03*
X394682Y550592D03*
Y588392D03*
X404722Y604499D03*
X414761Y607292D03*
X398029Y604499D03*
X404722Y609864D03*
X408068Y607292D03*
X438187Y510114D03*
X431494Y515364D03*
X444880D03*
Y510114D03*
X428147Y512792D03*
X421454Y518157D03*
X434840Y512792D03*
X424801Y515364D03*
X438187D03*
X431494Y566807D03*
X424801D03*
X438187Y609864D03*
X431494Y604499D03*
X421454Y607292D03*
X424801Y604614D03*
X438187D03*
X970669Y-7108D03*
X974015Y-4536D03*
X963976Y-7108D03*
X960629Y-4536D03*
X970669Y92757D03*
X974015Y89964D03*
Y84599D03*
X963976Y92657D03*
X960629Y84714D03*
X977362Y-1743D03*
X984055D03*
X1004134Y-7108D03*
X1004133Y-1742D03*
X997441Y-1743D03*
X994094Y-4536D03*
X987401D03*
X990748Y-7108D03*
X984055D03*
X977362Y87392D03*
X984055D03*
X980708Y89964D03*
X1004023Y92757D03*
Y87392D03*
X1000787Y89964D03*
X997441Y87392D03*
X994094Y84714D03*
Y89964D03*
X987401Y84599D03*
X990748Y92757D03*
X984055D03*
X1081102Y28007D03*
X1047637D03*
X1057677D03*
X1074409D03*
X1050983Y-1743D03*
X1087795Y-4536D03*
X1054330D03*
X1077755Y-1743D03*
X1064369D03*
X1084448D03*
X1044290Y11792D03*
X1044291Y-2200D03*
X1054330Y89964D03*
X1050983Y87392D03*
X1087795Y84714D03*
X1081102Y65807D03*
X1064369Y92757D03*
X1081102Y89964D03*
X1094488D03*
Y84714D03*
X1047637Y65807D03*
Y89964D03*
X1054330Y84599D03*
X1077755Y87392D03*
X1064369D03*
X1071062Y92757D03*
X1057677Y65807D03*
X1057676Y92757D03*
X1084448Y87392D03*
X1074409Y65807D03*
Y89964D03*
X1087795D03*
X1044290Y87392D03*
Y49592D03*
X970669Y518157D03*
X974015Y515364D03*
Y509999D03*
X963976Y518057D03*
X970669Y607292D03*
X974015Y604499D03*
Y609864D03*
X963976Y607292D03*
X960629Y609864D03*
X977362Y512792D03*
X984055D03*
X980708Y515364D03*
X1004134Y518157D03*
X1003915Y512792D03*
X1000787Y515364D03*
X997441Y512792D03*
X994094Y510114D03*
Y515364D03*
X987401Y509999D03*
X990748Y518157D03*
X984055D03*
X977362Y612457D03*
X984055D03*
X980708Y604614D03*
X1004134Y607292D03*
X1004133Y612358D03*
X1000787Y604499D03*
X997441Y612357D03*
X994094Y609864D03*
Y604614D03*
X987401Y609864D03*
X990748Y607292D03*
X984055D03*
X1054330Y515364D03*
X1050983Y512792D03*
X1087795Y510114D03*
X1064369Y518157D03*
X1081102Y515364D03*
X1094488D03*
Y510114D03*
X1047637Y529007D03*
Y515364D03*
X1054330Y509999D03*
X1077755Y512792D03*
X1064369D03*
X1071062Y518157D03*
X1057677Y529007D03*
X1057676Y518157D03*
X1084448Y512792D03*
X1074409Y515364D03*
X1087795D03*
X1044290Y512792D03*
X1044203Y537058D03*
X1081102Y566807D03*
X1047637D03*
X1057677D03*
X1074409D03*
X1044290Y550592D03*
Y588392D03*
X1054330Y604499D03*
X1087795Y609864D03*
X1064369Y607292D03*
X1081102Y604499D03*
X1047637D03*
X1054330Y609864D03*
X1071062Y607292D03*
X1057676D03*
X1074409Y604614D03*
X1087795D03*
X1074409Y593642D03*
G54D57*
X19800Y257900D03*
G54D45*
X19904Y254162D03*
X37000Y265350D03*
X33490Y267900D03*
X37000Y275000D03*
X321192Y13200D03*
X321334Y32100D03*
X334292Y13200D03*
Y32100D03*
X321061Y28014D03*
X327754Y35957D03*
X324407Y28014D03*
Y35957D03*
X314368Y28014D03*
X311021Y35957D03*
X334447D03*
X331100Y28014D03*
X354525Y28022D03*
X354526Y35957D03*
X351179Y28022D03*
X347833Y35957D03*
X344486D03*
Y28022D03*
X337793Y35957D03*
X341140Y28022D03*
X334446Y28014D03*
X321061Y17057D03*
X327754Y9114D03*
X324407Y17057D03*
Y9114D03*
X314368Y17057D03*
X311021Y9114D03*
X334446D03*
X331100Y17057D03*
X354526D03*
X354525Y9122D03*
X351179Y17057D03*
X347833Y9122D03*
X344486D03*
Y17057D03*
X337793Y9114D03*
X341140Y17057D03*
X334447D03*
X317714Y35957D03*
Y-4536D03*
Y9114D03*
X321192Y51000D03*
X321334Y69900D03*
X334292Y51000D03*
Y69900D03*
X321061Y65814D03*
X327754Y73757D03*
X324407Y65814D03*
Y73757D03*
X314368Y65814D03*
X334447Y73757D03*
X331100Y65814D03*
X354525Y65822D03*
X354526Y73757D03*
X351179Y65822D03*
X347833Y73757D03*
X344486D03*
Y65822D03*
X337793Y73757D03*
X341140Y65822D03*
X334446Y65814D03*
X321061Y54857D03*
X327754Y46914D03*
X324407Y54857D03*
Y46914D03*
X314368Y54857D03*
X311021Y46914D03*
X334446D03*
X331100Y54857D03*
X354526D03*
X354525Y46922D03*
X351179Y54857D03*
X347833Y46922D03*
X344486D03*
Y54857D03*
X337793Y46914D03*
X341140Y54857D03*
X334447D03*
X317714Y84714D03*
Y73757D03*
Y46914D03*
X348978Y220809D03*
Y209109D03*
X352357Y211060D03*
X355737Y209109D03*
Y220809D03*
X345598Y207159D03*
X348978Y205210D03*
Y216909D03*
X352357Y218860D03*
X345598D03*
X359117Y211060D03*
Y218860D03*
X355737Y216909D03*
Y213009D03*
X345598Y211060D03*
X348978Y213009D03*
X352357Y238360D03*
X345598D03*
Y230559D03*
X352357Y222760D03*
X348978Y224709D03*
X355737D03*
X348978Y228610D03*
X352357Y230559D03*
X348978Y236409D03*
Y240309D03*
X352357Y234460D03*
X345598Y242260D03*
Y234460D03*
X352357Y246160D03*
X345598D03*
X359117Y230559D03*
X355737Y228610D03*
Y236409D03*
X352357Y242260D03*
X355737Y240309D03*
X345598Y222760D03*
X380200Y-1200D03*
X408184Y32100D03*
Y13200D03*
X404723Y28022D03*
X401377Y35957D03*
X364565Y28014D03*
X361218D03*
X414762Y28021D03*
X404723Y35957D03*
X414763D03*
X394684D03*
X404723Y17057D03*
X401376Y9121D03*
X414762Y17058D03*
X398029Y17042D03*
X404722Y9121D03*
X414763Y9122D03*
X408069Y17042D03*
X376700Y-1300D03*
X371258Y-1858D03*
X411415Y36058D03*
Y-4536D03*
X411416Y9122D03*
X394682Y17157D03*
X371042Y46900D03*
X380792Y56500D03*
X408184Y51000D03*
Y69900D03*
X394492Y54700D03*
X404723Y65822D03*
X401377Y73757D03*
X414763Y65822D03*
X404723Y73757D03*
X414763D03*
X404723Y54857D03*
X401377Y46922D03*
X414763Y54857D03*
X398029Y54842D03*
X404723Y46922D03*
X414763D03*
X408069Y54842D03*
X380600Y37400D03*
X384992Y81600D03*
X411415Y84714D03*
X411416Y73757D03*
Y46922D03*
X394682Y68492D03*
X386292Y98800D03*
X401375Y103116D03*
X414819D03*
X408126D03*
X362497Y209109D03*
Y220809D03*
X369257D03*
X382777D03*
Y209109D03*
X376017Y220809D03*
Y209109D03*
X389537D03*
Y220809D03*
X396296Y209109D03*
Y220809D03*
X407706Y209109D03*
Y220809D03*
X372637Y207159D03*
X399676D03*
X372637Y211060D03*
X392916D03*
X389537Y213009D03*
X396296D03*
X369257D03*
X396296Y216909D03*
X376017D03*
X365877Y218860D03*
X372637D03*
X362497Y216909D03*
X382777Y213009D03*
X399676Y218860D03*
X386157Y211060D03*
X407706Y216909D03*
X379397Y207159D03*
X369257Y216909D03*
X382777D03*
X379397Y218860D03*
X392916D03*
X362497Y213009D03*
X386157Y218860D03*
X389537Y216909D03*
X376017Y213009D03*
X399676Y211060D03*
X379397Y238360D03*
Y250060D03*
X386157Y238360D03*
X389537Y248109D03*
X376017D03*
X382777D03*
X386157Y250060D03*
X359117Y238360D03*
X365877D03*
X372637D03*
X392916Y250060D03*
Y238360D03*
X396296Y248109D03*
X399676Y250060D03*
X407706Y248109D03*
X396296Y244209D03*
Y240309D03*
X376017Y224709D03*
X372637Y222760D03*
X365877D03*
X369257Y224709D03*
X362497D03*
X386157Y222760D03*
X396296Y228610D03*
X389537Y224709D03*
X399676Y222760D03*
X382777Y224709D03*
X379397Y222760D03*
X359117D03*
X392916D03*
X396296Y224709D03*
X379397Y230559D03*
X365877Y242260D03*
X407706Y236409D03*
X372637Y234460D03*
X365877D03*
X372637Y230559D03*
X365877D03*
X369257Y236409D03*
X362497D03*
X369257Y228610D03*
X362497D03*
X382777D03*
X389537Y236409D03*
X399676Y230559D03*
Y234460D03*
X382777Y236409D03*
X392916Y230559D03*
X407706Y224709D03*
Y228610D03*
X376017Y236409D03*
X369257Y240309D03*
X376017D03*
X386157Y230559D03*
X372637Y242260D03*
X379397Y234460D03*
X399676Y238360D03*
X359117Y242260D03*
X362497Y240309D03*
X359117Y234460D03*
Y246160D03*
X386157Y234460D03*
X392916D03*
X389537Y228610D03*
X396296Y236409D03*
X376017Y228610D03*
X391787Y254259D03*
X388407Y256500D03*
X385027Y254259D03*
X395166Y256400D03*
X398546Y254259D03*
X405306Y254500D03*
X401926Y256500D03*
X399676Y242260D03*
X389537Y240309D03*
X382777D03*
X392916Y242260D03*
X386157D03*
X379397D03*
X389537Y244209D03*
X382777D03*
X376017D03*
X392916Y246160D03*
X386157D03*
X379397D03*
X372637D03*
X365877D03*
X407706Y244209D03*
X399676Y246160D03*
X433508Y32100D03*
X421368D03*
X433508Y13200D03*
X421368D03*
X421455Y9121D03*
X421454Y-1817D03*
X438189Y35957D03*
X444882D03*
X428149D03*
X421456Y28022D03*
X434842Y35957D03*
X438189Y28022D03*
X438187Y9120D03*
X431494Y17042D03*
X428147Y9120D03*
X421456Y17057D03*
X434840Y9120D03*
X424801Y17042D03*
X438187Y17059D03*
X421368Y51000D03*
X433508D03*
Y69900D03*
X421368D03*
X421455Y46921D03*
X421456Y73757D03*
X438189D03*
X444880Y65822D03*
X428149Y73757D03*
X421456Y65822D03*
X434842Y73757D03*
X438189Y65822D03*
Y46922D03*
X431494Y54842D03*
X444880Y54859D03*
Y46922D03*
X428149D03*
X421456Y54857D03*
X434842Y46922D03*
X424801Y54842D03*
X438187Y54859D03*
X427696Y103100D03*
X421512Y103116D03*
X352357Y359260D03*
X355737Y376809D03*
Y388509D03*
X348978Y376809D03*
X345598Y390460D03*
X352357Y386560D03*
X341892Y396301D03*
X345598Y386560D03*
X348978Y388509D03*
X351192Y402800D03*
X348978Y380709D03*
Y372909D03*
X352357Y378760D03*
Y374860D03*
X359117Y386560D03*
X355737Y380709D03*
X359117Y374860D03*
X355737Y372909D03*
X348978Y369010D03*
X352357Y367060D03*
X355737Y384609D03*
X348978Y357309D03*
Y361209D03*
X352357Y363160D03*
X359117D03*
X355737Y361209D03*
Y369010D03*
X352357Y355360D03*
X355737Y357309D03*
X348978Y384609D03*
X324187Y499793D03*
X321061Y529014D03*
X324407D03*
X326922Y497170D03*
X331100Y529014D03*
X354525Y529022D03*
X351179D03*
X344486D03*
X341140D03*
X334446Y529014D03*
X317714Y510114D03*
X321334Y533100D03*
X321123Y552000D03*
X321334Y570900D03*
X321192Y589800D03*
X334292Y533100D03*
Y552000D03*
Y570900D03*
Y589800D03*
X327754Y536957D03*
X324407D03*
X311021D03*
X334447D03*
X354526D03*
X347833D03*
X344486D03*
X337793D03*
X321061Y566814D03*
Y555857D03*
X327754Y547914D03*
Y574757D03*
X324407Y555857D03*
Y566814D03*
Y547914D03*
Y574757D03*
X314368Y566814D03*
X311021Y574757D03*
X314368Y555857D03*
X311021Y547914D03*
X334446D03*
X334447Y574757D03*
X331100Y555857D03*
Y566814D03*
X354526Y555857D03*
X354525Y566822D03*
Y547922D03*
X354526Y574757D03*
X351179Y555857D03*
Y566822D03*
X347833Y547922D03*
Y574757D03*
X344486Y547922D03*
Y574757D03*
Y566822D03*
Y555857D03*
X337793Y547914D03*
Y574757D03*
X341140Y555857D03*
Y566822D03*
X334447Y555857D03*
X334446Y566814D03*
X327754Y585714D03*
X324407D03*
X311021D03*
X334446D03*
X354525Y585722D03*
X347833D03*
X344486D03*
X337793Y585714D03*
X317714Y536957D03*
Y547914D03*
Y574757D03*
Y585714D03*
X321061Y593657D03*
X324407D03*
X314368D03*
X331100D03*
X354526D03*
X351179D03*
X344486D03*
X341140D03*
X334447D03*
X317714Y609864D03*
X388407Y345160D03*
X395166D03*
X401926D03*
X379397Y359260D03*
X382777Y349509D03*
X386157Y351460D03*
Y359260D03*
X389537Y353409D03*
X372637Y359260D03*
X365877D03*
X359117D03*
X376017Y376809D03*
X369257D03*
X382777Y388509D03*
X369257D03*
X362497D03*
X376017D03*
X389537D03*
Y376809D03*
X382777D03*
X362497D03*
X396296Y353409D03*
X411086Y351460D03*
X405306Y347109D03*
X399676Y351460D03*
X392916D03*
Y359260D03*
X396296Y388509D03*
Y376809D03*
X411086Y374860D03*
X403056Y376809D03*
Y388509D03*
X392916Y355360D03*
X396296Y357309D03*
X389537D03*
X372637Y390460D03*
X396296Y384609D03*
X372637Y386560D03*
X392916D03*
X389537Y384609D03*
X399676Y390460D03*
X376017Y372909D03*
X369257Y384609D03*
X396296Y380709D03*
X369257Y372909D03*
X362497D03*
X372637Y378760D03*
X362497Y380709D03*
X372637Y374860D03*
X365877D03*
X376017Y380709D03*
X365877Y378760D03*
X382777Y384609D03*
X386157Y374860D03*
X399676Y378760D03*
X396296Y369010D03*
X386157Y386560D03*
X389537Y372909D03*
X403056Y380709D03*
X399676Y374860D03*
X379397Y386560D03*
X369257Y380709D03*
X382777D03*
Y372909D03*
X379397Y378760D03*
Y374860D03*
X392916Y378760D03*
X362497Y384609D03*
X359117Y378760D03*
X386157D03*
X392916Y374860D03*
X389537Y380709D03*
X396296Y372909D03*
X376017Y384609D03*
X379397Y367060D03*
X365877Y355360D03*
X403056Y361209D03*
X369257Y369010D03*
X362497D03*
X369257Y361209D03*
X362497D03*
X372637Y367060D03*
X365877D03*
X372637Y363160D03*
X365877D03*
X382777Y369010D03*
X389537Y361209D03*
X399676Y367060D03*
Y363160D03*
X382777Y361209D03*
X392916Y367060D03*
X403056Y372909D03*
Y369010D03*
X376017Y361209D03*
X369257Y357309D03*
X376017D03*
X386157Y367060D03*
X372637Y355360D03*
X379397Y363160D03*
X399676Y359260D03*
X359117Y355360D03*
X362497Y357309D03*
X359117Y367060D03*
X386157Y363160D03*
X392916D03*
X389537Y369010D03*
X396296Y361209D03*
X376017Y369010D03*
X391787Y347109D03*
X398546D03*
X411431Y359351D03*
X411086Y355360D03*
X403056Y353409D03*
X399676Y355360D03*
X382777Y353409D03*
X386157Y355360D03*
X403056Y396309D03*
X411086Y394359D03*
Y390460D03*
X399676Y386560D03*
X411086D03*
Y382660D03*
Y378760D03*
X398546Y402900D03*
X382777Y357309D03*
X379397Y355360D03*
X402892Y400400D03*
X385244Y504027D03*
X363760Y529293D03*
X404723Y529022D03*
X411415Y510114D03*
X394587Y529026D03*
X376785Y538305D03*
X376892Y577500D03*
X408184Y533100D03*
Y552000D03*
Y589800D03*
Y570900D03*
X401377Y536957D03*
X404723D03*
X414763D03*
X404723Y566822D03*
Y555857D03*
X401376Y547922D03*
X401377Y574757D03*
X414763Y566822D03*
Y555857D03*
X398029Y555842D03*
X404723Y547922D03*
Y574757D03*
X414763D03*
Y547922D03*
X408069Y555842D03*
X394684Y574757D03*
X401377Y585722D03*
X404723D03*
X414763D03*
X376892Y581127D03*
X370596Y585614D03*
X411416Y536957D03*
X411415Y547921D03*
X411416Y574757D03*
Y585722D03*
X394682Y569492D03*
X404723Y593657D03*
X414763D03*
X398029Y593642D03*
X408069D03*
X378600Y606200D03*
X371312Y604709D03*
X411415Y609864D03*
X394682Y607292D03*
X435192Y499400D03*
X421456Y529022D03*
X421368Y533100D03*
X434395Y532904D03*
X433508Y552000D03*
X421368D03*
X420634Y589800D03*
X433508Y570900D03*
X421368D03*
X433500Y589800D03*
X421456Y547922D03*
Y585722D03*
X438189Y536957D03*
X444882D03*
X428149D03*
X434842D03*
X438189Y547922D03*
Y574757D03*
X444880Y566822D03*
X444882Y574757D03*
X431494Y555842D03*
X444880Y555859D03*
Y547922D03*
X428149D03*
Y574757D03*
X421456Y555857D03*
Y566822D03*
X434842Y547922D03*
Y574757D03*
X438189Y566822D03*
X424801Y555842D03*
X438187Y555859D03*
X438189Y585722D03*
X428149D03*
X434842D03*
X431494Y593642D03*
X421456Y593657D03*
X424801Y593642D03*
X438187Y593659D03*
X970800Y13200D03*
X970942Y32100D03*
X970669Y28014D03*
X974015D03*
Y35957D03*
X963976Y28014D03*
X960629Y35957D03*
X970669Y17057D03*
X974015D03*
Y9114D03*
X963976Y17057D03*
X960629Y9114D03*
X967322Y35957D03*
Y-4536D03*
Y9114D03*
X970800Y50860D03*
X970942Y69900D03*
X970669Y65814D03*
X974015D03*
Y73757D03*
X963976Y65814D03*
X970669Y54857D03*
X974015D03*
Y46914D03*
X963976Y54857D03*
X960629Y46914D03*
X967322Y73757D03*
Y84714D03*
Y46914D03*
X983900Y13200D03*
Y32100D03*
X1026700Y1700D03*
X977362Y35957D03*
X984055D03*
X980708Y28014D03*
X1004133Y28022D03*
X1004134Y35957D03*
X1000787Y28022D03*
X997441Y35957D03*
X994094D03*
Y28022D03*
X987401Y35957D03*
X990748Y28022D03*
X984054Y28014D03*
X977362Y9114D03*
X984054D03*
X980708Y17057D03*
X1004134D03*
X1004133Y9122D03*
X1000787Y17057D03*
X997441Y9122D03*
X994094D03*
Y17057D03*
X987401Y9114D03*
X990748Y17057D03*
X984055D03*
X1020866Y-1858D03*
X983900Y51000D03*
Y69900D03*
X1014350Y73000D03*
X1030400Y56500D03*
X1031600Y42900D03*
X977362Y73757D03*
X984055D03*
X980708Y65814D03*
X1004133Y65822D03*
X1004134Y73757D03*
X1000787Y65822D03*
X997441Y73757D03*
X994094D03*
Y65822D03*
X987401Y73757D03*
X990748Y65822D03*
X984054Y65814D03*
X977362Y46914D03*
X984054D03*
X980708Y54857D03*
X1004134D03*
X1004133Y46922D03*
X1000787Y54857D03*
X997441Y46922D03*
X994094D03*
Y54857D03*
X987401Y46914D03*
X990748Y54857D03*
X984055D03*
X1020650Y46900D03*
X1030300Y63200D03*
X1035900Y98800D03*
X998586Y209109D03*
Y220809D03*
X1005345Y209109D03*
Y220809D03*
X1001965Y211060D03*
X1025625Y209109D03*
Y220809D03*
X1012105D03*
Y209109D03*
X1018865Y220809D03*
X1032385D03*
Y209109D03*
X1022245Y207159D03*
Y211060D03*
X995206Y207159D03*
X998586Y205210D03*
X1018865Y213009D03*
X998586Y216909D03*
X1001965Y218860D03*
X995206D03*
X1025625Y216909D03*
X1015485Y218860D03*
X1022245D03*
X1012105Y216909D03*
X1032385Y213009D03*
X1035765Y211060D03*
X1029005Y207159D03*
X1018865Y216909D03*
X1032385D03*
X1029005Y218860D03*
X1008725Y211060D03*
X1012105Y213009D03*
X1008725Y218860D03*
X1005345Y216909D03*
Y213009D03*
X1035765Y218860D03*
X1025625Y213009D03*
X995206Y211060D03*
X998586Y213009D03*
X995206Y238360D03*
X1029005D03*
X1008725D03*
X1001965D03*
X1035765D03*
Y250060D03*
X1029005D03*
X1032385Y248109D03*
X1025625D03*
X1015485Y238360D03*
X1022245D03*
X995206Y230559D03*
X1025625Y224709D03*
X1022245Y222760D03*
X1015485D03*
X1018865Y224709D03*
X1012105D03*
X1035765Y222760D03*
X1001965D03*
X998586Y224709D03*
X1032385D03*
X1029005Y222760D03*
X1008725D03*
X1005345Y224709D03*
X998586Y228610D03*
X1001965Y230559D03*
X998586Y236409D03*
Y240309D03*
X1029005Y230559D03*
X1015485Y242260D03*
X1001965Y234460D03*
X995206Y242260D03*
Y234460D03*
X1022245D03*
X1015485D03*
X1022245Y230559D03*
X1015485D03*
X1018865Y236409D03*
X1012105D03*
X1018865Y228610D03*
X1012105D03*
X1032385D03*
Y236409D03*
X1025625D03*
X1018865Y240309D03*
X1001965Y246160D03*
X995206D03*
X1025625Y240309D03*
X1035765Y230559D03*
X1022245Y242260D03*
X1029005Y234460D03*
X1008725Y242260D03*
X1012105Y240309D03*
X1008725Y230559D03*
Y234460D03*
X1005345Y228610D03*
Y236409D03*
X1001965Y242260D03*
X1005345Y240309D03*
X1008725Y246160D03*
X1035765Y234460D03*
X1025625Y228610D03*
X1034635Y254259D03*
X995206Y222760D03*
X1032385Y240309D03*
X1035765Y242260D03*
X1029005D03*
X1032385Y244209D03*
X1025625D03*
X1035765Y246160D03*
X1029005D03*
X1022245D03*
X1015485D03*
X1057792Y13200D03*
Y32100D03*
X1083116Y13200D03*
Y32100D03*
X1070976Y13200D03*
Y32100D03*
X1071062Y-1817D03*
X1071064Y9122D03*
X1054331Y28022D03*
X1050985Y35957D03*
X1087797D03*
X1064371Y28022D03*
X1094490Y35957D03*
X1054331D03*
X1077757D03*
X1064371D03*
X1071064Y28022D03*
X1084450Y35957D03*
X1087797Y28022D03*
X1044292Y35957D03*
X1054331Y17057D03*
X1050985Y9122D03*
X1087797D03*
X1064371Y17057D03*
X1081102Y17042D03*
X1054331Y9122D03*
X1077757D03*
X1064371D03*
X1071064Y17057D03*
X1057677Y17042D03*
X1084450Y9122D03*
X1074409Y17042D03*
X1087795Y17059D03*
X1061024Y35957D03*
X1061023Y-4536D03*
X1061024Y9122D03*
X1057792Y51000D03*
Y69900D03*
X1083116Y51000D03*
X1070976D03*
X1083116Y69900D03*
X1070976D03*
X1044100Y54700D03*
X1071064Y46922D03*
Y73757D03*
X1054331Y65822D03*
X1050985Y73757D03*
X1087797D03*
X1064371Y65822D03*
X1094488D03*
X1054331Y73757D03*
X1077757D03*
X1064371D03*
X1071064Y65822D03*
X1084450Y73757D03*
X1087797Y65822D03*
X1054331Y54857D03*
X1050985Y46922D03*
X1087797D03*
X1064371Y54857D03*
X1081102Y54842D03*
X1094488Y54859D03*
Y46922D03*
X1047637Y54842D03*
X1054331Y46922D03*
X1077757D03*
X1064371D03*
X1071064Y54857D03*
X1057677Y54842D03*
X1084450Y46922D03*
X1074409Y54842D03*
X1087795Y54859D03*
X1061024Y73757D03*
X1061023Y84714D03*
X1061024Y46922D03*
X1044290Y68964D03*
X1050983Y103116D03*
X1064427D03*
X1077304Y103100D03*
X1057734Y103116D03*
X1071120D03*
X1045904Y220809D03*
X1057314D03*
Y209109D03*
X1045904D03*
X1039145D03*
Y220809D03*
X1049284Y207159D03*
X1042524Y211060D03*
X1039145Y213009D03*
X1045904D03*
Y216909D03*
X1049284Y218860D03*
X1057314Y216909D03*
X1042524Y218860D03*
X1039145Y216909D03*
X1049284Y211060D03*
X1057314Y248109D03*
X1039145D03*
X1042524Y250060D03*
X1049284D03*
X1045904Y248109D03*
X1042524Y238360D03*
X1045904Y244209D03*
Y240309D03*
Y228610D03*
X1039145Y224709D03*
X1049284Y222760D03*
X1042524D03*
X1045904Y224709D03*
X1057314Y236409D03*
X1039145D03*
X1049284Y230559D03*
Y234460D03*
X1042524Y230559D03*
X1057314Y224709D03*
Y228610D03*
X1049284Y238360D03*
X1042524Y234460D03*
X1039145Y228610D03*
X1045904Y236409D03*
X1038015Y256500D03*
X1041395Y254259D03*
X1048154D03*
X1051534Y256500D03*
X1044774Y256400D03*
X1054914Y254500D03*
X1049284Y242260D03*
X1039145Y240309D03*
X1042524Y242260D03*
X1039145Y244209D03*
X1042524Y246160D03*
X1057314Y244209D03*
X1049284Y246160D03*
X973795Y499793D03*
X970669Y529014D03*
X974015D03*
X967322Y510114D03*
X970942Y533100D03*
X970731Y552000D03*
X970942Y570900D03*
X970731Y589800D03*
X974015Y536957D03*
X960629D03*
X970669Y555857D03*
Y566814D03*
X974015Y555857D03*
Y566814D03*
Y547914D03*
Y574757D03*
X963976Y566814D03*
X960629Y574757D03*
X963976Y555857D03*
X960629Y547914D03*
X974015Y585714D03*
X960629D03*
X967322Y536957D03*
Y574757D03*
Y547914D03*
Y585714D03*
X970669Y593657D03*
X974015D03*
X963976D03*
X967322Y609864D03*
X1034635Y343209D03*
X1031255Y341260D03*
X998586Y376809D03*
X995206Y390460D03*
X1001965Y359260D03*
X1008725D03*
X1015485D03*
X1022245Y347560D03*
X1025625Y345609D03*
X1022245Y359260D03*
X1029005Y347560D03*
Y359260D03*
X1032385Y349509D03*
X1035765Y351460D03*
Y359260D03*
X1032385Y388509D03*
Y376809D03*
X1005345D03*
Y388509D03*
X1001965Y386560D03*
X1025625Y376809D03*
Y388509D03*
X1018865Y376809D03*
X1012105D03*
X1018865Y388509D03*
X1012105D03*
X991500Y396301D03*
X1022245Y390460D03*
X995206Y386560D03*
X1022245D03*
X998586Y388509D03*
X1000800Y402800D03*
X998586Y380709D03*
X1025625Y372909D03*
X1018865Y384609D03*
X998586Y372909D03*
X1018865D03*
X1012105D03*
X1022245Y378760D03*
X1012105Y380709D03*
X1022245Y374860D03*
X1015485D03*
X1025625Y380709D03*
X1015485Y378760D03*
X1032385Y384609D03*
X1035765Y374860D03*
Y386560D03*
X1029005D03*
X1018865Y380709D03*
X1001965Y378760D03*
Y374860D03*
X1032385Y380709D03*
Y372909D03*
X1029005Y378760D03*
Y374860D03*
X1008725Y386560D03*
X1012105Y384609D03*
X1008725Y378760D03*
X1005345Y380709D03*
X1008725Y374860D03*
X1005345Y372909D03*
X998586Y369010D03*
X1001965Y367060D03*
X1005345Y384609D03*
X1035765Y378760D03*
X1025625Y384609D03*
X998586Y357309D03*
X1029005Y367060D03*
X1015485Y355360D03*
X998586Y361209D03*
X1018865Y369010D03*
X1012105D03*
X1018865Y361209D03*
X1012105D03*
X1022245Y367060D03*
X1015485D03*
X1022245Y363160D03*
X1015485D03*
X1032385Y369010D03*
Y361209D03*
X1025625D03*
X1018865Y357309D03*
X1001965Y363160D03*
X1025625Y357309D03*
X1035765Y367060D03*
X1022245Y355360D03*
X1029005Y363160D03*
X1008725Y355360D03*
X1012105Y357309D03*
X1008725Y363160D03*
Y367060D03*
X1005345Y361209D03*
Y369010D03*
X1001965Y355360D03*
X1005345Y357309D03*
X1035765Y363160D03*
X1025625Y369010D03*
X1032385Y353409D03*
X1035765Y355360D03*
X998586Y384609D03*
X1032385Y357309D03*
X1029005Y355360D03*
X1022245Y351460D03*
X1029005D03*
X1025625Y349509D03*
X1013500Y529200D03*
X1034200Y506956D03*
X1035750Y503006D03*
X976530Y497170D03*
X980708Y529014D03*
X1004133Y529022D03*
X1000787D03*
X994094D03*
X990748D03*
X984054Y529014D03*
X983900Y533100D03*
Y552000D03*
Y570900D03*
Y589800D03*
X1026500Y577500D03*
X977362Y536957D03*
X984055D03*
X1004134D03*
X997441D03*
X994094D03*
X987401D03*
X977362Y547914D03*
Y574757D03*
X984054Y547914D03*
X984055Y574757D03*
X980708Y555857D03*
Y566814D03*
X1004134Y555857D03*
X1004133Y566822D03*
Y547922D03*
X1004134Y574757D03*
X1000787Y555857D03*
Y566822D03*
X997441Y547922D03*
Y574757D03*
X994094Y547922D03*
Y574757D03*
Y555857D03*
Y566822D03*
X987401Y547914D03*
Y574757D03*
X990748Y555857D03*
Y566822D03*
X984055Y555857D03*
X984054Y566814D03*
X977362Y585714D03*
X984054D03*
X1004133Y585722D03*
X997441D03*
X994094D03*
X987401Y585714D03*
X1026500Y581000D03*
X1019800Y555800D03*
X980708Y593657D03*
X1004134D03*
X1000787D03*
X994094D03*
X990748D03*
X984055D03*
X1020700Y604600D03*
X1038015Y345160D03*
X1044774D03*
X1051534D03*
X1042524Y359260D03*
X1049284Y351460D03*
X1045904Y353409D03*
X1039145D03*
X1042524Y351460D03*
X1054914Y347000D03*
X1039145Y388509D03*
X1045904D03*
X1052664D03*
X1039145Y376809D03*
X1045904D03*
X1052664D03*
X1060694Y351460D03*
X1042524Y355360D03*
X1045904Y357309D03*
X1039145D03*
X1045904Y384609D03*
X1042524Y386560D03*
X1039145Y384609D03*
X1049284Y390460D03*
X1045904Y380709D03*
X1049284Y378760D03*
X1045904Y369010D03*
X1039145Y372909D03*
X1052664Y380709D03*
X1049284Y374860D03*
X1042524Y378760D03*
Y374860D03*
X1039145Y380709D03*
X1045904Y372909D03*
X1052664Y361209D03*
X1039145D03*
X1049284Y367060D03*
Y363160D03*
X1042524Y367060D03*
X1052664Y372909D03*
Y369010D03*
X1049284Y359260D03*
X1042524Y363160D03*
X1039145Y369010D03*
X1045904Y361209D03*
X1041395Y347109D03*
X1048154D03*
X1061039Y359351D03*
X1060694Y355360D03*
X1052664Y353409D03*
Y396309D03*
X1049284Y386560D03*
X1048154Y402900D03*
X1049284Y355360D03*
X1052500Y400400D03*
X1054331Y529022D03*
X1084800Y499400D03*
X1071064Y529022D03*
X1061023Y510114D03*
X1044195Y529026D03*
X1057792Y552000D03*
Y533100D03*
Y570900D03*
Y589800D03*
X1070976Y552000D03*
Y533100D03*
X1084003Y532904D03*
X1083116Y552000D03*
X1070976Y570900D03*
X1070242Y589800D03*
X1083116Y570900D03*
X1083108Y589800D03*
X1071064Y547922D03*
Y585722D03*
X1050985Y536957D03*
X1087797D03*
X1094490D03*
X1054331D03*
X1077757D03*
X1064371D03*
X1084450D03*
X1054331Y555857D03*
Y566822D03*
X1050984Y547922D03*
X1050985Y574757D03*
X1087797Y547922D03*
Y574757D03*
X1064371Y566822D03*
X1094488D03*
X1094490Y574757D03*
X1064371Y555857D03*
X1081102Y555842D03*
X1094488Y555859D03*
Y547922D03*
X1047637Y555842D03*
X1054331Y547922D03*
Y574757D03*
X1077757Y547922D03*
Y574757D03*
X1064371Y547922D03*
Y574757D03*
X1071064Y555857D03*
Y566822D03*
X1057677Y555842D03*
X1084450Y547922D03*
Y574757D03*
X1087797Y566822D03*
X1074409Y555842D03*
X1087795Y555859D03*
X1044292Y574757D03*
X1050985Y585722D03*
X1087797D03*
X1054331D03*
X1077757D03*
X1064371D03*
X1084450D03*
X1061024Y536957D03*
Y574757D03*
Y547922D03*
Y585722D03*
X1044290Y569492D03*
X1054331Y593657D03*
X1064371D03*
X1081102Y593642D03*
X1047637D03*
X1071064Y593657D03*
X1057677Y593642D03*
X1087795Y593659D03*
X1061023Y609864D03*
X1044290Y607292D03*
%LPD*%
G75*
G54D10*
X-17936Y-49379D03*
Y-53779D03*
Y-44979D03*
Y-40579D03*
X-18079Y-35764D03*
Y-58764D03*
X-14186Y196989D03*
Y199989D03*
X-14839Y445588D03*
X-14753Y448601D03*
X-17179Y643156D03*
X-17194Y638753D03*
X-17179Y647556D03*
Y660756D03*
Y651956D03*
Y656356D03*
X-13636Y-40479D03*
Y-44879D03*
Y-53679D03*
X-9079Y-50164D03*
X-4679D03*
X-279D03*
X-9079Y-54264D03*
X-4679D03*
X-279D03*
X22964Y-40379D03*
Y-44779D03*
Y-53579D03*
Y-49179D03*
X18964Y-53579D03*
Y-49179D03*
X13964Y-53579D03*
Y-49179D03*
X8964Y-40379D03*
Y-44779D03*
Y-53579D03*
Y-49179D03*
X3964Y-40379D03*
Y-44779D03*
Y-53579D03*
Y-49179D03*
X25921Y-35764D03*
X30321D03*
X43521D03*
X39121D03*
X34721D03*
X8321D03*
X12721D03*
X21521D03*
X17121D03*
X-13679D03*
X-9279D03*
X3921D03*
X-4879D03*
X-479D03*
X17121Y-58764D03*
X21521D03*
X12721D03*
X8321D03*
X34721D03*
X39121D03*
X43521D03*
X30321D03*
X25921D03*
X-479D03*
X-13679D03*
X-4879D03*
X3921D03*
X-13636Y-49279D03*
X-9279Y-58764D03*
X875Y211336D03*
X6074Y211293D03*
X3474Y211263D03*
X875Y208352D03*
X36200Y208600D03*
X33200D03*
X20700D03*
X17700Y211600D03*
X20700D03*
X17700Y208600D03*
X23700Y211600D03*
Y208600D03*
X33200Y211600D03*
X30200D03*
Y208600D03*
X36200Y211600D03*
X6074Y208321D03*
X3474Y208263D03*
X5500Y218500D03*
X-5300Y200191D03*
X-7900D03*
X-2700Y200202D03*
X-11586Y196989D03*
Y199989D03*
X-2600Y232300D03*
X-5246Y232351D03*
X-7846D03*
X20500Y221000D03*
Y224000D03*
X17500Y221000D03*
Y224000D03*
X23500D03*
Y221000D03*
X33300Y224000D03*
Y221000D03*
X30300D03*
Y224000D03*
X36300D03*
Y221000D03*
X-14129Y235221D03*
X-11484Y235215D03*
Y232215D03*
X-14084D03*
X2678Y221018D03*
X5277Y221110D03*
X5173Y224042D03*
X2574Y223963D03*
X-26Y223982D03*
X-11652Y445530D03*
Y448530D03*
X22421Y647556D03*
X26821D03*
X31221D03*
X18021D03*
Y643156D03*
X31221D03*
X26821D03*
X22421D03*
X18006Y638753D03*
X9221Y647556D03*
X13621D03*
Y643156D03*
X9221D03*
X4821D03*
Y647556D03*
X22406Y638753D03*
X26806D03*
X31206D03*
X-12794D03*
X-12779Y647556D03*
Y643156D03*
X40006Y638753D03*
X44406D03*
X35606D03*
X35621Y647556D03*
Y643156D03*
X-9599Y610630D03*
X-3301Y619643D03*
Y601615D03*
X4549Y620682D03*
X4548Y600577D03*
X13801Y624130D03*
Y597130D03*
X23360Y620172D03*
X23352Y601079D03*
X27301Y610630D03*
X18021Y660756D03*
X35621Y656356D03*
X26821Y660756D03*
X18021Y651956D03*
X31221D03*
X22421Y660756D03*
X26821Y651956D03*
X22421D03*
X4821D03*
X13621D03*
X9221D03*
X-8379Y660756D03*
X4821Y656356D03*
X9221D03*
X13621D03*
X-3979D03*
X421D03*
X13621Y660756D03*
X-3979D03*
X421D03*
X4821D03*
X-12779Y651956D03*
X22421Y656356D03*
X26821D03*
X31221D03*
X18021D03*
X-8379D03*
X-12779D03*
X31221Y660756D03*
X35621Y651956D03*
Y660756D03*
X44421D03*
X40021D03*
X-12779D03*
X9221D03*
X107921Y-58764D03*
X102921D03*
X97921D03*
X92921D03*
X87921D03*
X82921D03*
X77921D03*
X72921D03*
X67921D03*
X62921D03*
X57921D03*
X52921D03*
X47921Y-35764D03*
Y-58764D03*
X107921Y-35764D03*
X102921D03*
X97921D03*
X92921D03*
X87921D03*
X82921D03*
X77921D03*
X72921D03*
X67921D03*
X62921D03*
X57921D03*
X52921D03*
X96249Y204722D03*
X64700Y210100D03*
Y212800D03*
X64778Y218062D03*
X58000Y206500D03*
X56900Y197800D03*
X93870Y199131D03*
X97730Y188584D03*
X58200Y230400D03*
Y233400D03*
X55600Y230400D03*
X53000Y230300D03*
Y233300D03*
X55600Y233400D03*
X58200Y227400D03*
X53000Y227300D03*
X55600Y227400D03*
X58200Y239400D03*
X53000Y239300D03*
X55600Y239400D03*
X58200Y236400D03*
X55600D03*
X53000Y236300D03*
X71500Y263300D03*
X68800D03*
X53004Y244632D03*
X55275Y245900D03*
X57875D03*
X57457Y248537D03*
Y251237D03*
X57600Y262800D03*
X57500Y260200D03*
X62800Y265500D03*
X71500Y266000D03*
X65500Y265500D03*
X68800Y266000D03*
X60000Y265500D03*
X76540Y397355D03*
X81900Y398300D03*
X79140Y397355D03*
X98149Y399769D03*
X102456Y393756D03*
X76052Y420935D03*
X78000Y423100D03*
X80100Y425000D03*
X81500Y427400D03*
X79700Y409700D03*
X77400Y407800D03*
X81500Y412100D03*
X84913Y434471D03*
X87013Y436371D03*
X107571Y406291D03*
X48806Y638753D03*
X75206D03*
X106006D03*
X70806D03*
X53206D03*
X66406D03*
X92806D03*
X97206D03*
X101606D03*
X57606D03*
X62006D03*
X79606D03*
X84006D03*
X88406D03*
X53221Y660756D03*
X101621D03*
X97221D03*
X92821D03*
X106021D03*
X48821D03*
X70821D03*
X66421D03*
X62021D03*
X57621D03*
X75221D03*
X88421D03*
X84021D03*
X79621D03*
X167921Y-58764D03*
X162921D03*
X157921D03*
X152921D03*
X147921D03*
X142921D03*
X137921D03*
X132921D03*
X127921D03*
X122921D03*
X117921D03*
X112921D03*
X162921Y-35764D03*
X157921D03*
X152921D03*
X147921D03*
X142921D03*
X137921D03*
X132921D03*
X127921D03*
X122921D03*
X117921D03*
X112921D03*
X167921D03*
X166000Y212900D03*
X168600D03*
X164300Y207870D03*
X160800Y212900D03*
X163400D03*
X157800Y207300D03*
X161216Y209533D03*
Y206933D03*
X154500Y205500D03*
X150600Y212900D03*
X151000Y205500D03*
X140889Y211972D03*
X137615Y212039D03*
X143900Y204600D03*
X147500Y205500D03*
X137300Y204500D03*
X140200Y204400D03*
X153200Y212900D03*
X122044Y162340D03*
X139815Y268974D03*
X137900Y272800D03*
X139800Y237000D03*
X165825Y239543D03*
X168425Y236943D03*
Y239543D03*
X165825Y236943D03*
X163225D03*
X152825D03*
X145025D03*
X147625D03*
X150225D03*
X142425D03*
X163225Y239543D03*
X158025Y236943D03*
X155425D03*
X160625D03*
X142371Y244384D03*
X142466Y268982D03*
X142700Y276200D03*
X136729Y276386D03*
X139683Y276174D03*
X163225Y242143D03*
X168425Y244743D03*
X165825D03*
X163225D03*
X168425Y242143D03*
X165825D03*
X150700Y276800D03*
X169150Y259470D03*
Y255470D03*
X157633Y268727D03*
X162833D03*
X160233D03*
X165433D03*
X168033Y271327D03*
X162833Y276527D03*
Y273927D03*
Y271327D03*
X165433Y276527D03*
Y273927D03*
Y271327D03*
X159983Y276507D03*
X168033Y276527D03*
Y273927D03*
Y268727D03*
X153300Y276800D03*
X139866Y333016D03*
X160233Y306257D03*
Y308857D03*
Y303657D03*
X157518Y335391D03*
X157745Y332800D03*
X139900Y302400D03*
X142433Y301057D03*
X147633D03*
X150233D03*
X145033D03*
X145200Y341300D03*
X148200D03*
X142465Y332940D03*
X152833Y301057D03*
X163233Y306257D03*
Y308857D03*
X168433Y306257D03*
Y308857D03*
Y301057D03*
X165833D03*
X163233D03*
X160633D03*
X158033D03*
X155433D03*
X169150Y287600D03*
Y291600D03*
X165833Y306257D03*
X163233Y303657D03*
X168433D03*
X165833D03*
Y308857D03*
X151000Y341300D03*
X169150Y323600D03*
Y319600D03*
X160501Y332965D03*
X160274Y335556D03*
X165701Y338165D03*
Y335565D03*
X163101Y332965D03*
X168301D03*
X165701D03*
X163101Y335565D03*
X168301Y340765D03*
Y338165D03*
Y335565D03*
X163101Y338165D03*
Y340765D03*
X165701D03*
X154200Y341100D03*
X139767Y364883D03*
X147833Y364457D03*
X142421Y364908D03*
X145033Y364457D03*
X142863Y402829D03*
X140219Y402894D03*
X137619Y402900D03*
X134992D03*
X142818Y400163D03*
X143073Y397194D03*
X140475Y397310D03*
X140218Y400163D03*
X137529Y400296D03*
X134929D03*
X114084Y399937D03*
X122840Y400827D03*
X150633Y364457D03*
X167433Y369657D03*
X169150Y355600D03*
Y351600D03*
X167700Y363900D03*
X161833Y364457D03*
X164633D03*
X159033D03*
X156233D03*
X153433D03*
X164633Y369657D03*
X161833D03*
X161933Y372357D03*
X164733D03*
X167533D03*
X166340Y374785D03*
X167670Y383993D03*
Y387993D03*
X130613Y429647D03*
X123648Y425041D03*
X125328Y427269D03*
X127932Y428571D03*
X110519Y410307D03*
X110199Y413852D03*
X110406Y638753D03*
X145606D03*
X141206D03*
X136806D03*
X132406D03*
X158806D03*
X119206D03*
X123606D03*
X114806D03*
X128006D03*
X163206D03*
X154406D03*
X167606D03*
X150006D03*
X132421Y660756D03*
X145621D03*
X141221D03*
X136821D03*
X123621D03*
X114821D03*
X128021D03*
X110421D03*
X119221D03*
X150021D03*
X167621D03*
X163221D03*
X158821D03*
X154421D03*
X182921Y-58764D03*
X177921D03*
X172921D03*
X227921Y-35764D03*
X222921D03*
X217921D03*
X212921D03*
X207921D03*
X202921D03*
X197921D03*
X192921D03*
X187921D03*
X182921D03*
X177921D03*
X227921Y-58764D03*
X222921D03*
X217921D03*
X212921D03*
X207921D03*
X202921D03*
X197921D03*
X192921D03*
X187921D03*
X172921Y-35764D03*
X211606Y638753D03*
X224806D03*
X220406D03*
X216006D03*
X189606D03*
X198406D03*
X202806D03*
X207206D03*
X176406D03*
X172006D03*
X185206D03*
X180806D03*
X194006D03*
X226500Y649900D03*
X229206Y638753D03*
X224821Y660756D03*
X220421D03*
X198421D03*
X211621D03*
X189621D03*
X202821D03*
X207221D03*
X194021D03*
X185221D03*
X172021D03*
X176421D03*
X180821D03*
X229221D03*
X216021D03*
X292921Y-35764D03*
X287921D03*
X282921D03*
X277921D03*
X272921D03*
X267921D03*
X262921D03*
X257921D03*
X252921D03*
X247921D03*
X242921D03*
X237921D03*
X232921D03*
X292921Y-58764D03*
X287921D03*
X282921D03*
X277921D03*
X272921D03*
X267921D03*
X262921D03*
X257921D03*
X252921D03*
X247921D03*
X242921D03*
X237921D03*
X232921D03*
X290806Y638753D03*
X268806D03*
X273206D03*
X277606D03*
X282006D03*
X260006D03*
X264406D03*
X255606D03*
X251206D03*
X286406D03*
X242406D03*
X246806D03*
X233606D03*
X238006D03*
X286421Y660756D03*
X268821D03*
X282021D03*
X273221D03*
X277621D03*
X264421D03*
X251221D03*
X255621D03*
X260021D03*
X246821D03*
X242421D03*
X238021D03*
X233621D03*
X290821D03*
X352921Y-58764D03*
Y-35764D03*
X347921Y-58764D03*
Y-35764D03*
X342921Y-58764D03*
Y-35764D03*
X337921Y-58764D03*
Y-35764D03*
X332921Y-58764D03*
Y-35764D03*
X327921Y-58764D03*
Y-35764D03*
X322921Y-58764D03*
Y-35764D03*
X317921Y-58764D03*
Y-35764D03*
X312921Y-58764D03*
X307921D03*
Y-35764D03*
X302921Y-58764D03*
Y-35764D03*
X297921D03*
Y-58764D03*
X312921Y-35764D03*
X330406Y638753D03*
X348006D03*
X326006D03*
X312806D03*
X317206D03*
X321606D03*
X352406D03*
X295206D03*
X299606D03*
X308406D03*
X304006D03*
X334806D03*
X339206D03*
X343606D03*
X312821Y660756D03*
X317221D03*
X308421D03*
X304021D03*
X352421D03*
X295221D03*
X326021D03*
X321621D03*
X339221D03*
X299621D03*
X334821D03*
X330421D03*
X343621D03*
X348021D03*
X392921Y-35764D03*
X387921Y-58764D03*
Y-35764D03*
X382921Y-58764D03*
Y-35764D03*
X377921Y-58764D03*
Y-35764D03*
X372921Y-58764D03*
Y-35764D03*
X367921Y-58764D03*
Y-35764D03*
X362921Y-58764D03*
Y-35764D03*
X357921Y-58764D03*
Y-35764D03*
X392921Y-58764D03*
X402921Y-35764D03*
X397921Y-58764D03*
Y-35764D03*
X412921Y-58764D03*
Y-35764D03*
X407921Y-58764D03*
Y-35764D03*
X402921Y-58764D03*
X404594Y264899D03*
X407594D03*
X411188D03*
X414188D03*
X417190D03*
X380885Y273876D03*
Y270876D03*
X382494Y278904D03*
X371094D03*
X378294D03*
X375294D03*
X368094D03*
X389694D03*
X392694D03*
X385945Y278480D03*
X407094Y278910D03*
X414207D03*
X411288D03*
X404094D03*
X400842Y278914D03*
X368094Y295904D03*
X371094D03*
X385494D03*
X375294D03*
X378294D03*
X382494D03*
X389694D03*
X392694D03*
X365693Y311893D03*
X391144Y324173D03*
X388394D03*
X385494D03*
X411294Y295904D03*
X414294D03*
X407094D03*
X404094D03*
X399894D03*
X396894D03*
Y324173D03*
X408894D03*
X411894D03*
X405894D03*
X414894D03*
X393894D03*
X402894D03*
X399894D03*
X383206Y638753D03*
X387606D03*
X392006D03*
X396406D03*
X400806D03*
X405206D03*
X409606D03*
X414006D03*
X370006D03*
X365606D03*
X374406D03*
X378806D03*
X356806D03*
X361206D03*
X374421Y660756D03*
X387621D03*
X383221D03*
X400821D03*
X396421D03*
X392021D03*
X405221D03*
X409621D03*
X414021D03*
X361221D03*
X365621D03*
X356821D03*
X370021D03*
X378821D03*
X477921Y-58764D03*
Y-35764D03*
X472921Y-58764D03*
Y-35764D03*
X467921Y-58764D03*
Y-35764D03*
X462921Y-58764D03*
Y-35764D03*
X457921Y-58764D03*
Y-35764D03*
X452921Y-58764D03*
Y-35764D03*
X447921Y-58764D03*
Y-35764D03*
X442921Y-58764D03*
Y-35764D03*
X437921Y-58764D03*
Y-35764D03*
X432921Y-58764D03*
X422921Y-35764D03*
X417921Y-58764D03*
Y-35764D03*
X432921D03*
X427921Y-58764D03*
Y-35764D03*
X422921Y-58764D03*
X425911Y264710D03*
X420188Y264899D03*
X423092Y264697D03*
X432643Y264508D03*
X418523Y278910D03*
X428694D03*
X432894D03*
X425694D03*
X435894Y278938D03*
X443094Y278904D03*
X440094D03*
X421523Y278944D03*
X451675Y291739D03*
X449148Y292841D03*
X446209Y292842D03*
X451816Y295904D03*
X435894D03*
X418494D03*
X443094D03*
X440094D03*
X446383Y295841D03*
X428694Y295904D03*
X432894D03*
X425694D03*
X421494D03*
X418494Y324173D03*
X451267Y324476D03*
X448694Y323949D03*
X421494Y324173D03*
X446094Y323904D03*
X425694Y324173D03*
X428694D03*
X432894D03*
X435894D03*
X455226Y291686D03*
X454922Y295841D03*
X466806Y638753D03*
X462406D03*
X475606D03*
X471206D03*
X418406D03*
X422806D03*
X427206D03*
X440406D03*
X436006D03*
X431606D03*
X449206D03*
X458006D03*
X453606D03*
X444806D03*
X458021Y660756D03*
X449221D03*
X462421D03*
X466821D03*
X471221D03*
X418421D03*
X475621D03*
X453621D03*
X422821D03*
X427221D03*
X440421D03*
X431621D03*
X436021D03*
X444821D03*
X537921Y-58764D03*
Y-35764D03*
X532921Y-58764D03*
Y-35764D03*
X527921Y-58764D03*
Y-35764D03*
X522921Y-58764D03*
Y-35764D03*
X517921Y-58764D03*
Y-35764D03*
X512921Y-58764D03*
Y-35764D03*
X507921Y-58764D03*
Y-35764D03*
X502921Y-58764D03*
Y-35764D03*
X497921Y-58764D03*
Y-35764D03*
X492921Y-58764D03*
Y-35764D03*
X487921Y-58764D03*
Y-35764D03*
X482921Y-58764D03*
Y-35764D03*
X480006Y638753D03*
X484406D03*
X488806D03*
X493206D03*
X497606D03*
X510806D03*
X537206D03*
X519606D03*
X524006D03*
X532806D03*
X528406D03*
X515206D03*
X502006D03*
X506406D03*
X524021Y660756D03*
X480021D03*
X484421D03*
X497621D03*
X493221D03*
X488821D03*
X519621D03*
X532821D03*
X537221D03*
X528421D03*
X515221D03*
X510821D03*
X506421D03*
X502021D03*
X597921Y-35764D03*
Y-58764D03*
X592921Y-35764D03*
Y-58764D03*
X587921Y-35764D03*
Y-58764D03*
X582921Y-35764D03*
Y-58764D03*
X577921Y-35764D03*
Y-58764D03*
X572921Y-35764D03*
Y-58764D03*
X567921Y-35764D03*
Y-58764D03*
X562921Y-35764D03*
Y-58764D03*
X557921Y-35764D03*
Y-58764D03*
X552921Y-35764D03*
Y-58764D03*
X547921D03*
Y-35764D03*
X542921Y-58764D03*
Y-35764D03*
X590006Y638753D03*
X572406D03*
X559206D03*
X568006D03*
X563606D03*
X550406D03*
X581206D03*
X585606D03*
X576806D03*
X598806D03*
X594406D03*
X601500Y649500D03*
X554806Y638753D03*
X541606D03*
X546006D03*
X559221Y660756D03*
X546021D03*
X554821D03*
X598821D03*
X572421D03*
X568021D03*
X563621D03*
X585621D03*
X541621D03*
X594421D03*
X576821D03*
X590021D03*
X581221D03*
X550421D03*
X637921Y-58764D03*
X632921Y-35764D03*
Y-58764D03*
X627921Y-35764D03*
Y-58764D03*
X622921Y-35764D03*
Y-58764D03*
X617921Y-35764D03*
Y-58764D03*
X612921Y-35764D03*
Y-58764D03*
X607921Y-35764D03*
Y-58764D03*
X602921Y-35764D03*
Y-58764D03*
X652921Y-35764D03*
Y-58764D03*
X647921Y-35764D03*
Y-58764D03*
X642921Y-35764D03*
Y-58764D03*
X637921Y-35764D03*
X662921D03*
Y-58764D03*
X657921Y-35764D03*
Y-58764D03*
X638406Y638753D03*
X634006D03*
X642806D03*
X629606D03*
X616406D03*
X612006D03*
X603206D03*
X625206D03*
X651606D03*
X647206D03*
X660406D03*
X620806D03*
X656006D03*
X607606D03*
X607621Y660756D03*
X638421D03*
X647221D03*
X616421D03*
X634021D03*
X612021D03*
X620821D03*
X625221D03*
X629621D03*
X642821D03*
X603221D03*
X656021D03*
X660421D03*
X651621D03*
X692921Y-58764D03*
X687921Y-35764D03*
Y-58764D03*
X682921Y-35764D03*
Y-58764D03*
X677921Y-35764D03*
Y-58764D03*
X672921Y-35764D03*
Y-58764D03*
X667921Y-35764D03*
Y-58764D03*
X697921Y-35764D03*
Y-58764D03*
X692921Y-35764D03*
X722921D03*
Y-58764D03*
X717921Y-35764D03*
Y-58764D03*
X712921Y-35764D03*
Y-58764D03*
X707921Y-35764D03*
Y-58764D03*
X702921Y-35764D03*
Y-58764D03*
X704466Y-7874D03*
X690966Y-21374D03*
X700525Y1668D03*
X700517Y-17425D03*
X681713Y-17927D03*
X690966Y5626D03*
X681714Y2178D03*
X673864Y-16889D03*
X667566Y-7874D03*
X673864Y1139D03*
X695606Y638753D03*
X673606D03*
X708806D03*
X704406D03*
X700006D03*
X722006D03*
X717606D03*
X713206D03*
X664806D03*
X669206D03*
X686806D03*
X682406D03*
X678006D03*
X691206D03*
X690966Y624130D03*
Y597130D03*
X700525Y620172D03*
X700517Y601079D03*
X704466Y610630D03*
X667566D03*
X673864Y619643D03*
Y601615D03*
X681714Y620682D03*
X681713Y600577D03*
X664821Y660756D03*
X695621D03*
X708821D03*
X700021D03*
X704421D03*
X669221D03*
X686821D03*
X691221D03*
X678021D03*
X673621D03*
X682421D03*
X722021D03*
X717621D03*
X713221D03*
X777921Y-58764D03*
X772921Y-35764D03*
Y-58764D03*
X767921Y-35764D03*
Y-58764D03*
X762921Y-35764D03*
Y-58764D03*
X757921Y-35764D03*
Y-58764D03*
X752921Y-35764D03*
Y-58764D03*
X787921Y-35764D03*
Y-58764D03*
X782921Y-35764D03*
Y-58764D03*
X777921Y-35764D03*
X747921D03*
Y-58764D03*
X742921Y-35764D03*
Y-58764D03*
X737921Y-35764D03*
Y-58764D03*
X732921Y-35764D03*
Y-58764D03*
X727921Y-35764D03*
Y-58764D03*
X786674Y211463D03*
X785920Y204763D03*
X786300Y207400D03*
X787200Y244200D03*
Y271900D03*
X787100Y241100D03*
X773419Y270414D03*
X787200Y276400D03*
X787100Y303900D03*
X753098Y338316D03*
X744698Y332816D03*
X787000Y308300D03*
X787400Y340400D03*
X741774Y376463D03*
X785400Y372400D03*
X757500Y374000D03*
X770406Y638753D03*
X779206D03*
X774806D03*
X730806D03*
X726406D03*
X739606D03*
X735206D03*
X748406D03*
X744006D03*
X766006D03*
X761606D03*
X757206D03*
X752806D03*
X783606D03*
X744021Y660756D03*
X735221D03*
X779221D03*
X770421D03*
X774821D03*
X726421D03*
X730821D03*
X739621D03*
X748421D03*
X783621D03*
X757221D03*
X761621D03*
X752821D03*
X766021D03*
X842921Y-35764D03*
X837921Y-58764D03*
Y-35764D03*
X832921Y-58764D03*
X847921D03*
Y-35764D03*
X842921Y-58764D03*
X832921Y-35764D03*
X827921Y-58764D03*
Y-35764D03*
X822921Y-58764D03*
Y-35764D03*
X817921Y-58764D03*
Y-35764D03*
X812921Y-58764D03*
Y-35764D03*
X807921Y-58764D03*
Y-35764D03*
X802921Y-58764D03*
Y-35764D03*
X797921D03*
Y-58764D03*
X792921Y-35764D03*
Y-58764D03*
X816900Y216300D03*
X816874Y212863D03*
X814274D03*
X811674D03*
X808818Y211179D03*
X808618Y208579D03*
X803200Y213100D03*
X800600D03*
X794474Y211463D03*
X791874D03*
X789274D03*
X788522Y204343D03*
X791122Y204339D03*
X789432Y236947D03*
X789400Y273700D03*
X811983Y244843D03*
Y242243D03*
X814583Y239643D03*
X815432Y237000D03*
X814583Y244843D03*
Y242243D03*
X812832Y237000D03*
X811983Y239643D03*
X802432Y237000D03*
X799832D03*
X792032D03*
X794632D03*
X810232D03*
X797232D03*
X805032D03*
X807632D03*
X791000Y244400D03*
X793600D03*
X816800Y234300D03*
X816900Y230900D03*
X817000Y252500D03*
X789800Y276400D03*
X792400D03*
X801991Y276557D03*
X804591D03*
X792191Y269101D03*
X789591D03*
X814891Y271657D03*
Y274257D03*
Y276857D03*
Y269057D03*
X812291D03*
Y274257D03*
Y276857D03*
Y271657D03*
X817000Y255100D03*
Y257700D03*
X817491Y276857D03*
Y274257D03*
Y271657D03*
Y269057D03*
X817183Y242243D03*
Y239643D03*
Y244843D03*
X818032Y237000D03*
X788600Y306100D03*
X789500Y301200D03*
X797300D03*
X799900D03*
X810300D03*
X802500D03*
X812900D03*
X807700D03*
X805100D03*
X815500D03*
X811991Y308957D03*
Y306357D03*
Y303757D03*
X814591Y306357D03*
Y308957D03*
Y303757D03*
X792900Y308400D03*
X789900D03*
X794700Y301200D03*
X792100D03*
X793000Y340400D03*
X790300Y340300D03*
X816991Y337357D03*
Y334757D03*
Y339957D03*
X814391D03*
Y337357D03*
Y334757D03*
X811791Y337357D03*
Y339957D03*
Y334757D03*
X791879Y332798D03*
X794600Y332600D03*
X816938Y319888D03*
Y323888D03*
X817100Y317000D03*
X818100Y301200D03*
X817191Y303757D03*
Y306357D03*
Y308957D03*
X789860Y364947D03*
X816591Y369857D03*
Y372457D03*
X811391Y369857D03*
X813991D03*
Y372457D03*
X811391D03*
X790900Y372300D03*
X788300Y372400D03*
X802759Y364575D03*
X816672Y358809D03*
X795310Y364721D03*
X816593Y356210D03*
X807959Y364575D03*
X805359D03*
X810559D03*
X815759D03*
X813159D03*
X816900Y361400D03*
X792610Y364821D03*
X816591Y375057D03*
X792238Y396753D03*
X789600Y396809D03*
X811515Y397289D03*
X808915D03*
X813648Y395557D03*
X815472Y390442D03*
X814877Y393138D03*
X792000Y399409D03*
X789400D03*
X849606Y638753D03*
X836406D03*
X832006D03*
X796806D03*
X801206D03*
X792406D03*
X827606D03*
X818806D03*
X823206D03*
X810006D03*
X788006D03*
X845206D03*
X814406D03*
X805606D03*
X840806D03*
X849621Y660756D03*
X832021D03*
X810021D03*
X818821D03*
X836421D03*
X788021D03*
X814421D03*
X801221D03*
X805621D03*
X823221D03*
X827621D03*
X840821D03*
X796821D03*
X792421D03*
X845221D03*
X907921Y-58764D03*
Y-35764D03*
X902921Y-58764D03*
Y-35764D03*
X897921Y-58764D03*
Y-35764D03*
X892921Y-58764D03*
Y-35764D03*
X887921Y-58764D03*
Y-35764D03*
X882921Y-58764D03*
Y-35764D03*
X877921Y-58764D03*
Y-35764D03*
X872921Y-58764D03*
Y-35764D03*
X867921Y-58764D03*
Y-35764D03*
X862921Y-58764D03*
Y-35764D03*
X857921Y-58764D03*
Y-35764D03*
X852921Y-58764D03*
Y-35764D03*
X858406Y638753D03*
X854006D03*
X884806D03*
X880406D03*
X876006D03*
X871606D03*
X867206D03*
X911206D03*
X906806D03*
X889206D03*
X898006D03*
X902406D03*
X893606D03*
X862806D03*
X854021Y660756D03*
X858421D03*
X862821D03*
X898021D03*
X902421D03*
X871621D03*
X884821D03*
X893621D03*
X867221D03*
X889221D03*
X911221D03*
X906821D03*
X880421D03*
X876021D03*
X937921Y-35764D03*
X932921Y-58764D03*
Y-35764D03*
X927921Y-58764D03*
Y-35764D03*
X922921Y-58764D03*
Y-35764D03*
X917921Y-58764D03*
Y-35764D03*
X912921Y-58764D03*
Y-35764D03*
X942921D03*
X967921D03*
X962921Y-58764D03*
Y-35764D03*
X957921Y-58764D03*
Y-35764D03*
X952921Y-58764D03*
Y-35764D03*
X947921Y-58764D03*
Y-35764D03*
X942921Y-58764D03*
X972921D03*
Y-35764D03*
X967921Y-58764D03*
X937921D03*
X924406Y638753D03*
X920006D03*
X915606D03*
X972806D03*
X968406D03*
X964006D03*
X917100Y649300D03*
X942006Y638753D03*
X937606D03*
X933206D03*
X928806D03*
X959606D03*
X955206D03*
X950806D03*
X946406D03*
X959621Y660756D03*
X964021D03*
X968421D03*
X972821D03*
X920021D03*
X915621D03*
X924421D03*
X946421D03*
X942021D03*
X937621D03*
X933221D03*
X928821D03*
X955221D03*
X950821D03*
X1002921Y-58764D03*
Y-35764D03*
X997921Y-58764D03*
Y-35764D03*
X992921Y-58764D03*
Y-35764D03*
X987921Y-58764D03*
Y-35764D03*
X982921Y-58764D03*
Y-35764D03*
X977921Y-58764D03*
Y-35764D03*
X1032921Y-58764D03*
Y-35764D03*
X1027921Y-58764D03*
Y-35764D03*
X1022921Y-58764D03*
Y-35764D03*
X1017921Y-58764D03*
Y-35764D03*
X1012921Y-58764D03*
Y-35764D03*
X1007921Y-58764D03*
Y-35764D03*
X1030489Y270889D03*
Y273889D03*
X1027902Y278904D03*
X1020702D03*
X1017702D03*
X1024902D03*
X1032102D03*
X1017567Y295859D03*
X1024767D03*
X1020567D03*
X1031967D03*
X1027767D03*
X1015293Y311955D03*
X1003606Y638753D03*
X1012406D03*
X977206D03*
X990406D03*
X986006D03*
X994806D03*
X1016806D03*
X1021206D03*
X981606D03*
X999206D03*
X1025606D03*
X1008006D03*
X1030006D03*
X1034406D03*
X999221Y660756D03*
X1034421D03*
X1030021D03*
X1008021D03*
X1012421D03*
X1003621D03*
X1016821D03*
X977221D03*
X981621D03*
X1021221D03*
X1025621D03*
X994821D03*
X986021D03*
X990421D03*
X1067921Y-58764D03*
Y-35764D03*
X1062921Y-58764D03*
Y-35764D03*
X1057921Y-58764D03*
Y-35764D03*
X1052921Y-58764D03*
Y-35764D03*
X1047921Y-58764D03*
Y-35764D03*
X1042921Y-58764D03*
Y-35764D03*
X1037921Y-58764D03*
Y-35764D03*
X1092921Y-58764D03*
Y-35764D03*
X1087921Y-58764D03*
Y-35764D03*
X1082921Y-58764D03*
Y-35764D03*
X1077921Y-58764D03*
Y-35764D03*
X1072921Y-58764D03*
Y-35764D03*
X1075865Y264766D03*
X1070300Y264900D03*
X1073200Y264991D03*
X1057202Y264899D03*
X1060402Y264799D03*
X1066300Y264700D03*
X1063402Y264799D03*
X1054202Y264899D03*
X1042302Y278904D03*
X1039302D03*
X1056602Y278910D03*
X1035814Y278775D03*
X1049867Y278999D03*
X1053459Y278910D03*
X1060958D03*
X1075302D03*
X1078302D03*
X1082330D03*
X1070926D03*
X1063652D03*
X1067783D03*
X1082432Y264620D03*
X1085518Y278910D03*
X1089702Y278904D03*
X1077282Y338533D03*
X1080282D03*
X1056792Y338673D03*
X1063992D03*
X1060992D03*
X1071192D03*
X1068192D03*
X1039167Y295859D03*
X1042167D03*
X1034967D03*
X1046367D03*
X1056567D03*
X1049367D03*
X1053567D03*
X1038720Y324174D03*
X1044220D03*
X1035820D03*
X1050220D03*
X1047220D03*
X1053220D03*
X1056220D03*
X1041470D03*
X1059220D03*
X1060767Y295859D03*
X1095756Y292841D03*
X1082367Y295859D03*
X1085367D03*
X1075167D03*
X1078167D03*
X1089567D03*
X1092567D03*
X1095567Y295841D03*
X1070967Y295859D03*
X1063767D03*
X1067967D03*
X1062220Y324174D03*
X1095402Y323904D03*
X1083220Y324174D03*
X1076020D03*
X1079020D03*
X1071820D03*
X1065220D03*
X1068820D03*
X1096006Y638753D03*
X1078406D03*
X1082806D03*
X1074006D03*
X1069606D03*
X1091606D03*
X1052006D03*
X1038806D03*
X1087206D03*
X1060806D03*
X1056406D03*
X1065206D03*
X1043206D03*
X1047606D03*
X1078421Y660756D03*
X1060821D03*
X1087221D03*
X1038821D03*
X1091621D03*
X1052021D03*
X1074021D03*
X1065221D03*
X1096021D03*
X1056421D03*
X1043221D03*
X1047621D03*
X1082821D03*
X1069621D03*
X1157921Y-58764D03*
Y-35764D03*
X1152921Y-58764D03*
Y-35764D03*
X1147921Y-58764D03*
Y-35764D03*
X1142921Y-58764D03*
Y-35764D03*
X1137921Y-58764D03*
Y-35764D03*
X1132921Y-58764D03*
Y-35764D03*
X1127921Y-58764D03*
Y-35764D03*
X1122921Y-58764D03*
Y-35764D03*
X1117921Y-58764D03*
Y-35764D03*
X1112921Y-58764D03*
Y-35764D03*
X1107921Y-58764D03*
Y-35764D03*
X1102921Y-58764D03*
Y-35764D03*
X1097921Y-58764D03*
Y-35764D03*
X1104256Y291841D03*
X1101615Y292447D03*
X1098756Y292841D03*
X1101567Y295859D03*
X1104221Y295696D03*
X1098567Y295841D03*
X1112490Y312723D03*
X1112515Y315369D03*
X1101200Y324013D03*
X1098402Y324017D03*
X1135606Y638753D03*
X1126806D03*
X1144406D03*
X1140006D03*
X1118006D03*
X1122406D03*
X1153206D03*
X1157606D03*
X1104806D03*
X1100406D03*
X1131206D03*
X1148806D03*
X1109206D03*
X1113606D03*
X1157621Y660756D03*
X1148821D03*
X1122421D03*
X1126821D03*
X1100421D03*
X1118021D03*
X1140021D03*
X1113621D03*
X1109221D03*
X1153221D03*
X1144421D03*
X1104821D03*
X1131221D03*
X1135621D03*
X1217921Y-58764D03*
Y-35764D03*
X1212921Y-58764D03*
Y-35764D03*
X1207921Y-58764D03*
Y-35764D03*
X1202921Y-58764D03*
Y-35764D03*
X1197921Y-58764D03*
Y-35764D03*
X1192921Y-58764D03*
Y-35764D03*
X1187921Y-58764D03*
Y-35764D03*
X1182921Y-58764D03*
Y-35764D03*
X1177921Y-58764D03*
Y-35764D03*
X1172921Y-58764D03*
Y-35764D03*
X1167921Y-58764D03*
Y-35764D03*
X1162921Y-58764D03*
Y-35764D03*
X1188406Y638753D03*
X1214806D03*
X1197206D03*
X1201606D03*
X1192806D03*
X1170806D03*
X1162006D03*
X1166406D03*
X1206006D03*
X1219206D03*
X1179606D03*
X1175206D03*
X1210406D03*
X1184006D03*
X1184021Y660756D03*
X1219221D03*
X1192821D03*
X1188421D03*
X1201621D03*
X1179621D03*
X1214821D03*
X1206021D03*
X1166421D03*
X1210421D03*
X1170821D03*
X1162021D03*
X1175221D03*
X1197221D03*
X1232921Y-58764D03*
Y-35764D03*
X1227921Y-58764D03*
Y-35764D03*
X1222921Y-58764D03*
Y-35764D03*
X1252921Y-58764D03*
Y-35764D03*
X1247921Y-58764D03*
Y-35764D03*
X1242921Y-58764D03*
Y-35764D03*
X1237921Y-58764D03*
Y-35764D03*
X1257921D03*
X1272921Y-58764D03*
Y-35764D03*
X1267921Y-58764D03*
Y-35764D03*
X1262921Y-58764D03*
Y-35764D03*
X1257921Y-58764D03*
X1277921D03*
Y-35764D03*
X1263206Y638753D03*
X1223606D03*
X1228006D03*
X1258806D03*
X1241206D03*
X1236806D03*
X1250006D03*
X1245606D03*
X1276406D03*
X1254406D03*
X1280806D03*
X1272006D03*
X1267606D03*
X1232406D03*
X1228021Y660756D03*
X1232421D03*
X1280821D03*
X1245621D03*
X1236821D03*
X1223621D03*
X1276421D03*
X1241221D03*
X1272021D03*
X1258821D03*
X1250021D03*
X1254421D03*
X1263221D03*
X1267621D03*
X1342921Y-35764D03*
Y-58764D03*
X1317921D03*
X1312921Y-35764D03*
Y-58764D03*
X1307921Y-35764D03*
Y-58764D03*
X1302921Y-35764D03*
Y-58764D03*
X1297921D03*
Y-35764D03*
X1292921Y-58764D03*
Y-35764D03*
X1287921Y-58764D03*
Y-35764D03*
X1282921Y-58764D03*
Y-35764D03*
X1322921D03*
Y-58764D03*
X1317921Y-35764D03*
X1337921D03*
Y-58764D03*
X1332921Y-35764D03*
Y-58764D03*
X1327921Y-35764D03*
Y-58764D03*
X1324806Y638753D03*
X1298406D03*
X1285206D03*
X1294006D03*
X1302806D03*
X1333606D03*
X1338006D03*
X1320406D03*
X1311606D03*
X1329206D03*
X1307206D03*
X1342406D03*
X1289606D03*
X1316006D03*
X1329221Y660756D03*
X1311621D03*
X1316021D03*
X1333621D03*
X1342421D03*
X1285221D03*
X1324821D03*
X1338021D03*
X1298421D03*
X1289621D03*
X1294021D03*
X1320421D03*
X1302821D03*
X1307221D03*
X1402921Y-58764D03*
X1397921D03*
X1402921Y-35764D03*
X1392921Y-58764D03*
X1397921Y-35764D03*
X1387921Y-58764D03*
X1392921Y-35764D03*
X1382921Y-58764D03*
X1387921Y-35764D03*
X1377921Y-58764D03*
X1382921Y-35764D03*
X1372921Y-58764D03*
X1377921Y-35764D03*
X1367921Y-58764D03*
X1362921Y-35764D03*
Y-58764D03*
X1357921Y-35764D03*
Y-58764D03*
X1352921Y-35764D03*
Y-58764D03*
X1347921Y-35764D03*
Y-58764D03*
X1395913Y-7874D03*
X1402211Y1139D03*
Y-16889D03*
X1351206Y638753D03*
X1360006D03*
X1404506Y638853D03*
X1355606Y638753D03*
X1386906Y638853D03*
X1364406Y638753D03*
X1391306Y638853D03*
X1346806Y638753D03*
X1400106Y638853D03*
X1382006Y638753D03*
X1377606D03*
X1373206D03*
X1395706Y638853D03*
X1368806Y638753D03*
X1402211Y601615D03*
Y619643D03*
X1395913Y610630D03*
X1368821Y660756D03*
X1346821D03*
X1355621D03*
X1360021D03*
X1364421D03*
X1351221D03*
X1404521Y660856D03*
X1400121D03*
X1395721D03*
X1386921D03*
X1377621Y660756D03*
X1382021D03*
X1373221D03*
X1391321Y660856D03*
X1407921Y-58764D03*
X1412921Y-35764D03*
X1407921D03*
X1442921Y-58764D03*
X1447921Y-35764D03*
X1437921Y-58764D03*
X1442921Y-35764D03*
X1432921Y-58764D03*
X1437921Y-35764D03*
X1427921Y-58764D03*
X1432921Y-35764D03*
X1422921Y-58764D03*
X1427921Y-35764D03*
X1417921Y-58764D03*
X1422921Y-35764D03*
X1412921Y-58764D03*
X1417921Y-35764D03*
X1462921Y-58764D03*
X1457921D03*
X1462921Y-35764D03*
X1452921Y-58764D03*
X1457921Y-35764D03*
X1447921Y-58764D03*
X1452921Y-35764D03*
X1410061Y2178D03*
X1410060Y-17927D03*
X1419313Y5626D03*
Y-21374D03*
X1428872Y1668D03*
X1428864Y-17425D03*
X1432813Y-7874D03*
X1422106Y638853D03*
X1466106D03*
X1448506D03*
X1457306D03*
X1417706D03*
X1413306D03*
X1461706D03*
X1452906D03*
X1408906D03*
X1444106D03*
X1435306D03*
X1426506D03*
X1430906D03*
X1439706D03*
X1432813Y610630D03*
X1428864Y601079D03*
X1428872Y620172D03*
X1419313Y597130D03*
Y624130D03*
X1410060Y600577D03*
X1410061Y620682D03*
X1457321Y660856D03*
X1417721D03*
X1413321D03*
X1408921D03*
X1422121D03*
X1426521D03*
X1435321D03*
X1444121D03*
X1439721D03*
X1430921D03*
X1448521D03*
X1452921D03*
X1466121D03*
X1461721D03*
X1502921Y-58764D03*
X1507921Y-35764D03*
X1497921Y-58764D03*
X1502921Y-35764D03*
X1492921Y-58764D03*
X1497921Y-35764D03*
X1487921Y-58764D03*
X1492921Y-35764D03*
X1482921Y-58764D03*
X1487921Y-35764D03*
X1477921Y-58764D03*
X1482921Y-35764D03*
X1472921Y-58764D03*
X1477921Y-35764D03*
X1467921Y-58764D03*
X1472921Y-35764D03*
X1467921D03*
X1527921Y-58764D03*
X1522921D03*
X1527921Y-35764D03*
X1517921Y-58764D03*
X1522921Y-35764D03*
X1512921Y-58764D03*
X1517921Y-35764D03*
X1507921Y-58764D03*
X1512921Y-35764D03*
X1496906Y638853D03*
X1492506D03*
X1501706Y638753D03*
X1506106D03*
X1514906D03*
X1483706Y638853D03*
X1523706Y638753D03*
X1510506D03*
X1488106Y638853D03*
X1474906D03*
X1519306Y638753D03*
X1479306Y638853D03*
X1528106Y638753D03*
X1470506Y638853D03*
X1496921Y660856D03*
X1483721D03*
X1488121D03*
X1492521D03*
X1479321D03*
X1510521Y660756D03*
X1528121D03*
X1523721D03*
X1501721D03*
X1506121D03*
X1514921D03*
X1519321D03*
X1474921Y660856D03*
X1470521D03*
X1587921Y-58764D03*
X1582921D03*
X1587921Y-35764D03*
X1532921D03*
X1542921D03*
X1532921Y-58764D03*
X1537921Y-35764D03*
X1577921Y-58764D03*
X1582921Y-35764D03*
X1572921Y-58764D03*
X1577921Y-35764D03*
X1567921Y-58764D03*
X1572921Y-35764D03*
X1562921Y-58764D03*
X1567921Y-35764D03*
X1557921Y-58764D03*
X1562921Y-35764D03*
X1552921Y-58764D03*
X1557921Y-35764D03*
X1547921Y-58764D03*
X1552921Y-35764D03*
X1542921Y-58764D03*
X1547921Y-35764D03*
X1537921Y-58764D03*
X1580121Y647556D03*
X1555106Y638753D03*
X1555121Y647556D03*
X1590121D03*
X1590106Y638753D03*
X1590121Y643156D03*
X1585121Y647556D03*
X1585106Y638753D03*
X1585121Y643156D03*
X1565121Y647556D03*
X1570121Y643156D03*
X1570106Y638753D03*
X1565106D03*
X1565121Y643156D03*
X1570121Y647556D03*
X1560121D03*
X1560106Y638753D03*
X1560121Y643156D03*
X1575121D03*
X1575106Y638753D03*
X1575121Y647556D03*
X1555121Y643156D03*
X1580106Y638753D03*
X1580121Y643156D03*
X1550121Y647556D03*
X1541306Y638753D03*
X1545706D03*
X1550106D03*
X1550121Y643156D03*
X1536906Y638753D03*
X1532506D03*
X1565121Y651956D03*
X1570121Y660756D03*
Y656356D03*
X1565121Y660756D03*
X1555121Y651956D03*
X1590121Y660756D03*
Y656356D03*
Y651956D03*
X1585121Y660756D03*
Y656356D03*
Y651956D03*
X1580121Y660756D03*
Y656356D03*
Y651956D03*
X1560121Y660756D03*
Y656356D03*
Y651956D03*
X1555121Y660756D03*
Y656356D03*
X1570121Y651956D03*
X1575121D03*
Y656356D03*
Y660756D03*
X1565121Y656356D03*
X1550121Y651956D03*
Y656356D03*
X1541321Y660756D03*
X1550121D03*
X1545721D03*
X1532521D03*
X1536921D03*
X1642921Y-35764D03*
Y-58764D03*
X1637921Y-35764D03*
Y-58764D03*
X1632921Y-35764D03*
Y-58764D03*
X1627921D03*
X1622921D03*
X1627921Y-35764D03*
X1617921Y-58764D03*
X1622921Y-35764D03*
X1612921Y-58764D03*
X1617921Y-35764D03*
X1607921Y-58764D03*
X1612921Y-35764D03*
X1602921Y-58764D03*
X1607921Y-35764D03*
X1597921Y-58764D03*
X1602921Y-35764D03*
X1592921Y-58764D03*
X1597921Y-35764D03*
X1592921D03*
X1647921D03*
Y-58764D03*
X1625106Y638753D03*
X1625121Y647556D03*
X1630121Y643156D03*
X1630106Y638753D03*
X1630121Y647556D03*
X1635121Y643156D03*
X1635106Y638753D03*
X1635121Y647556D03*
X1640121Y643156D03*
Y647556D03*
X1640106Y638753D03*
X1650121Y647556D03*
X1650106Y638753D03*
X1650121Y643156D03*
X1645121Y647556D03*
X1645106Y638753D03*
X1645121Y643156D03*
X1625121D03*
X1620121Y647556D03*
X1620106Y638753D03*
X1620121Y643156D03*
X1615121Y647556D03*
X1615106Y638753D03*
X1615121Y643156D03*
X1610121Y647556D03*
X1610106Y638753D03*
X1610121Y643156D03*
X1605121Y647556D03*
X1605106Y638753D03*
X1605121Y643156D03*
X1600121Y647556D03*
X1600106Y638753D03*
X1600121Y643156D03*
X1595121Y647556D03*
X1595106Y638753D03*
X1595121Y643156D03*
X1625121Y651956D03*
Y660756D03*
X1630121Y651956D03*
Y656356D03*
Y660756D03*
X1635121Y651956D03*
Y656356D03*
Y660756D03*
X1625121Y656356D03*
X1640121D03*
Y651956D03*
X1650121Y660756D03*
Y656356D03*
Y651956D03*
X1645121Y660756D03*
Y656356D03*
Y651956D03*
X1640121Y660756D03*
X1620121D03*
Y656356D03*
Y651956D03*
X1615121Y660756D03*
Y656356D03*
Y651956D03*
X1610121Y660756D03*
Y656356D03*
Y651956D03*
X1605121Y660756D03*
Y656356D03*
Y651956D03*
X1600121Y660756D03*
Y656356D03*
Y651956D03*
X1595121Y660756D03*
Y656356D03*
Y651956D03*
X1692921Y-40764D03*
X1702921Y-54764D03*
X1687921D03*
X1682921D03*
X1677921D03*
X1672921D03*
X1692921D03*
X1697921D03*
X1707921D03*
X1712921D03*
X1697921Y-40764D03*
X1692921Y-50764D03*
X1687921D03*
X1682921D03*
X1677921D03*
X1672921D03*
X1712921D03*
X1707921D03*
X1702921D03*
X1697921Y-45764D03*
X1707921D03*
X1702921D03*
X1712921D03*
X1697921Y-50764D03*
X1667921Y-35764D03*
X1712921D03*
Y-58764D03*
X1707921Y-35764D03*
Y-58764D03*
X1702921Y-35764D03*
Y-58764D03*
X1697921Y-35764D03*
Y-58764D03*
X1687921Y-40764D03*
X1672921Y-45764D03*
X1677921D03*
X1682921D03*
Y-40764D03*
X1687921Y-45764D03*
X1692921D03*
X1667921Y-58764D03*
X1662921Y-35764D03*
Y-58764D03*
X1657921Y-35764D03*
Y-58764D03*
X1652921Y-35764D03*
Y-58764D03*
X1712921Y-40764D03*
X1707921D03*
X1702921D03*
X1677921D03*
X1672921D03*
X1677921Y-35764D03*
Y-58764D03*
X1672921Y-35764D03*
Y-58764D03*
X1682921Y-35764D03*
Y-58764D03*
X1692921Y-35764D03*
Y-58764D03*
X1687921Y-35764D03*
Y-58764D03*
X1690121Y647556D03*
X1710121D03*
X1710106Y638753D03*
X1710121Y643156D03*
X1705121Y647556D03*
X1705106Y638753D03*
X1695121Y643156D03*
X1695106Y638753D03*
X1695121Y647556D03*
X1700121Y643156D03*
X1700106Y638753D03*
X1685121Y647556D03*
X1685106Y638753D03*
X1685121Y643156D03*
X1680121Y647556D03*
X1680106Y638753D03*
X1680121Y643156D03*
X1675121Y647556D03*
X1675106Y638753D03*
X1675121Y643156D03*
X1670121Y647556D03*
X1670106Y638753D03*
X1670121Y643156D03*
X1665121Y647556D03*
X1665106Y638753D03*
X1665121Y643156D03*
X1660121Y647556D03*
X1660106Y638753D03*
X1660121Y643156D03*
X1655121Y647556D03*
X1655106Y638753D03*
X1655121Y643156D03*
X1690121D03*
X1690106Y638753D03*
X1700121Y647556D03*
X1705121Y643156D03*
X1690121Y656356D03*
Y651956D03*
X1710121Y660756D03*
Y656356D03*
Y651956D03*
X1705121Y660756D03*
Y656356D03*
Y651956D03*
X1690121Y660756D03*
X1695121Y651956D03*
Y656356D03*
Y660756D03*
X1685121Y651956D03*
X1680121Y660756D03*
Y656356D03*
Y651956D03*
X1675121Y660756D03*
Y656356D03*
Y651956D03*
X1670121Y660756D03*
Y656356D03*
Y651956D03*
X1665121Y660756D03*
Y656356D03*
Y651956D03*
X1660121Y660756D03*
Y656356D03*
Y651956D03*
X1655121Y660756D03*
Y656356D03*
Y651956D03*
X1685121Y660756D03*
Y656356D03*
X1700121Y651956D03*
Y656356D03*
Y660756D03*
X1737921Y-50764D03*
X1722921Y-45764D03*
X1727921D03*
X1732921D03*
X1747921D03*
X1752921D03*
X1727921Y-54764D03*
X1757921D03*
X1717921D03*
X1722921D03*
X1767921Y-40764D03*
Y-50764D03*
X1762921D03*
X1757921D03*
X1762921Y-54764D03*
X1752921D03*
X1747921D03*
X1742921D03*
X1737921D03*
X1732921D03*
X1772921D03*
X1767921D03*
X1762921Y-40764D03*
X1772921D03*
X1722921Y-50764D03*
X1717921D03*
X1732921D03*
X1757921Y-40764D03*
X1717921Y-45764D03*
Y-58764D03*
X1742921Y-50764D03*
X1747921D03*
X1752921D03*
X1742921Y-58764D03*
X1737921Y-35764D03*
Y-58764D03*
X1732921Y-35764D03*
Y-58764D03*
X1727921Y-35764D03*
Y-58764D03*
X1722921Y-35764D03*
Y-58764D03*
X1717921Y-35764D03*
X1757921Y-45764D03*
X1762921D03*
X1742921D03*
X1752921Y-40764D03*
X1747921D03*
X1742921D03*
X1737921D03*
X1732921D03*
X1727921D03*
X1722921D03*
X1717921D03*
X1727921Y-50764D03*
X1767921Y-45764D03*
X1772921D03*
X1737921D03*
X1772921Y-35764D03*
Y-58764D03*
X1767921Y-35764D03*
Y-58764D03*
X1762921Y-35764D03*
Y-58764D03*
X1757921Y-35764D03*
Y-58764D03*
X1752921Y-35764D03*
Y-58764D03*
X1747921Y-35764D03*
Y-58764D03*
X1742921Y-35764D03*
X1772921Y-50764D03*
X1775121Y643156D03*
Y647556D03*
X1775106Y638753D03*
X1730121Y647556D03*
X1730106Y638753D03*
X1730121Y643156D03*
X1725121Y647556D03*
X1725106Y638753D03*
X1725121Y643156D03*
X1720121Y647556D03*
X1720106Y638753D03*
X1720121Y643156D03*
X1715121Y647556D03*
X1715106Y638753D03*
X1715121Y643156D03*
X1770121Y647556D03*
X1770106Y638753D03*
X1770121Y643156D03*
X1765121Y647556D03*
X1765106Y638753D03*
X1765121Y643156D03*
X1760121Y647556D03*
X1760106Y638753D03*
X1760121Y643156D03*
X1755121Y647556D03*
X1755106Y638753D03*
X1755121Y643156D03*
X1750121Y647556D03*
X1750106Y638753D03*
X1750121Y643156D03*
X1745121Y647556D03*
X1745106Y638753D03*
X1745121Y643156D03*
X1740121Y647556D03*
X1740106Y638753D03*
X1740121Y643156D03*
X1735121Y647556D03*
X1735106Y638753D03*
X1735121Y643156D03*
X1770121Y660756D03*
X1775121D03*
Y656356D03*
Y651956D03*
X1725121Y660756D03*
Y656356D03*
Y651956D03*
X1720121Y660756D03*
Y656356D03*
Y651956D03*
X1715121Y660756D03*
Y656356D03*
Y651956D03*
X1770121D03*
X1765121Y660756D03*
Y656356D03*
Y651956D03*
X1760121Y660756D03*
Y656356D03*
Y651956D03*
X1755121Y660756D03*
Y656356D03*
Y651956D03*
X1750121Y660756D03*
Y656356D03*
Y651956D03*
X1745121Y660756D03*
Y656356D03*
Y651956D03*
X1740121Y660756D03*
Y656356D03*
Y651956D03*
X1735121Y660756D03*
Y656356D03*
Y651956D03*
X1730121Y660756D03*
Y656356D03*
X1770121D03*
X1730121Y651956D03*
X1817921Y-40764D03*
X1832921Y-45764D03*
Y-54764D03*
X1827921D03*
X1822921D03*
X1817921D03*
X1812921D03*
X1807921D03*
X1802921D03*
X1797921D03*
X1792921D03*
X1787921D03*
X1782921D03*
X1777921D03*
X1832921Y-50764D03*
X1827921D03*
X1822921D03*
X1817921D03*
X1812921D03*
X1807921D03*
X1802921D03*
X1797921D03*
X1792921D03*
X1787921D03*
X1782921Y-40764D03*
X1792921D03*
X1802921D03*
X1807921D03*
X1822921D03*
X1827921D03*
X1832921D03*
X1812921D03*
X1797921D03*
X1777921Y-45764D03*
X1782921D03*
X1787921D03*
X1792921D03*
X1797921D03*
X1802921D03*
X1807921D03*
X1812921D03*
X1817921D03*
X1822921D03*
X1787921Y-40764D03*
X1832921Y-35764D03*
Y-58764D03*
X1827921Y-35764D03*
Y-58764D03*
X1822921Y-35764D03*
Y-58764D03*
X1817921Y-35764D03*
Y-58764D03*
X1812921Y-35764D03*
Y-58764D03*
X1807921Y-35764D03*
Y-58764D03*
X1802921Y-35764D03*
Y-58764D03*
X1797921Y-35764D03*
Y-58764D03*
X1792921Y-35764D03*
Y-58764D03*
X1787921Y-35764D03*
Y-58764D03*
X1782921Y-35764D03*
Y-58764D03*
X1777921Y-35764D03*
Y-58764D03*
X1782921Y-50764D03*
X1777921D03*
Y-40764D03*
X1827921Y-45764D03*
X1794992Y61342D03*
X1797664Y61334D03*
X1797645Y64153D03*
X1792382Y61363D03*
X1792363Y64182D03*
X1794973Y64161D03*
X1807891Y62180D03*
X1810563Y62172D03*
X1810693Y59493D03*
X1808021Y59501D03*
X1805411Y59522D03*
X1813393Y59493D03*
X1813363Y62172D03*
X1810578Y56866D03*
X1805282Y56880D03*
X1807916Y56895D03*
X1813278Y56866D03*
X1805281Y62201D03*
X1831148Y144592D03*
X1836200Y153424D03*
X1833000D03*
X1833600Y145900D03*
X1793205Y165531D03*
X1793268Y162774D03*
X1780121Y643156D03*
X1780106Y638753D03*
X1780121Y647556D03*
X1785121Y643156D03*
X1790121D03*
X1835121Y647556D03*
X1835106Y638753D03*
X1835121Y643156D03*
X1830121Y647556D03*
X1830106Y638753D03*
X1830121Y643156D03*
X1825121Y647556D03*
X1825106Y638753D03*
X1825121Y643156D03*
X1820121Y647556D03*
X1820106Y638753D03*
X1820121Y643156D03*
X1815121Y647556D03*
X1815106Y638753D03*
X1815121Y643156D03*
X1810121Y647556D03*
X1810106Y638753D03*
X1810121Y643156D03*
X1805121Y647556D03*
X1805106Y638753D03*
X1805121Y643156D03*
X1800121Y647556D03*
X1800106Y638753D03*
X1800121Y643156D03*
X1795121Y647556D03*
X1795106Y638753D03*
X1795121Y643156D03*
X1790121Y647556D03*
X1790106Y638753D03*
X1785121Y647556D03*
X1785106Y638753D03*
X1800121Y656356D03*
X1780121Y651956D03*
Y656356D03*
Y660756D03*
X1835121D03*
Y656356D03*
Y651956D03*
X1830121Y660756D03*
Y656356D03*
Y651956D03*
X1825121Y660756D03*
Y656356D03*
Y651956D03*
X1820121Y660756D03*
Y656356D03*
Y651956D03*
X1815121Y660756D03*
Y656356D03*
Y651956D03*
X1810121Y660756D03*
Y656356D03*
Y651956D03*
X1805121Y660756D03*
Y656356D03*
Y651956D03*
X1800121Y660756D03*
Y651956D03*
X1795121Y660756D03*
Y656356D03*
Y651956D03*
X1790121Y660756D03*
Y656356D03*
Y651956D03*
X1785121Y660756D03*
Y656356D03*
Y651956D03*
X1857921Y-45764D03*
X1837921D03*
X1897921D03*
X1892921D03*
X1887921D03*
X1882921D03*
X1877921D03*
X1872921D03*
X1867921D03*
X1862921D03*
X1842921Y-54764D03*
X1852921Y-45764D03*
X1847921D03*
X1842921D03*
X1897921Y-54764D03*
X1892921D03*
X1887921D03*
X1882921D03*
X1877921D03*
X1872921D03*
X1867921D03*
X1862921D03*
X1857921D03*
X1852921D03*
X1847921D03*
X1837921D03*
X1897921Y-50764D03*
X1892921D03*
X1887921D03*
X1882921D03*
X1877921D03*
X1872921D03*
X1867921D03*
X1862921D03*
X1857921D03*
X1852921D03*
X1847921D03*
X1842921D03*
X1837921D03*
X1892921Y-40764D03*
X1897921D03*
X1877921D03*
X1882921D03*
X1887921D03*
X1857921D03*
X1862921D03*
X1867921D03*
X1872921D03*
X1837921D03*
X1842921D03*
X1847921D03*
X1852921D03*
Y-35764D03*
Y-58764D03*
X1847921Y-35764D03*
Y-58764D03*
X1842921Y-35764D03*
Y-58764D03*
X1837921Y-35764D03*
Y-58764D03*
X1862921D03*
X1857921Y-35764D03*
Y-58764D03*
X1882921D03*
X1877921Y-35764D03*
Y-58764D03*
X1872921Y-35764D03*
Y-58764D03*
X1867921Y-35764D03*
Y-58764D03*
X1862921Y-35764D03*
X1897921D03*
Y-58764D03*
X1892921Y-35764D03*
Y-58764D03*
X1887921Y-35764D03*
Y-58764D03*
X1882921Y-35764D03*
X1847797Y26331D03*
X1847564Y21636D03*
X1844732Y-7874D03*
X1851030Y1139D03*
Y-16889D03*
X1858880Y2178D03*
X1858879Y-17927D03*
X1868132Y5626D03*
Y-21374D03*
X1877691Y1668D03*
X1877683Y-17425D03*
X1881632Y-7874D03*
X1895121Y647556D03*
X1895106Y638753D03*
X1895121Y643156D03*
X1890121Y647556D03*
X1890106Y638753D03*
X1890121Y643156D03*
X1885121Y647556D03*
X1885106Y638753D03*
X1885121Y643156D03*
X1880121Y647556D03*
X1880106Y638753D03*
X1880121Y643156D03*
X1875121Y647556D03*
X1875106Y638753D03*
X1875121Y643156D03*
X1870121Y647556D03*
X1870106Y638753D03*
X1870121Y643156D03*
X1865121Y647556D03*
X1865106Y638753D03*
X1865121Y643156D03*
X1860121Y647556D03*
X1860106Y638753D03*
X1860121Y643156D03*
X1855121Y647556D03*
X1855106Y638753D03*
X1855121Y643156D03*
X1850121Y647556D03*
X1850106Y638753D03*
X1850121Y643156D03*
X1845121Y647556D03*
X1845106Y638753D03*
X1845121Y643156D03*
X1840121Y647556D03*
X1840106Y638753D03*
X1840121Y643156D03*
X1844732Y610630D03*
X1851030Y619643D03*
Y601615D03*
X1858880Y620682D03*
X1858879Y600577D03*
X1868132Y624130D03*
Y597130D03*
X1877691Y620172D03*
X1877683Y601079D03*
X1881632Y610630D03*
X1895121Y660756D03*
Y656356D03*
Y651956D03*
X1890121Y660756D03*
Y656356D03*
Y651956D03*
X1885121Y660756D03*
Y656356D03*
Y651956D03*
X1880121Y660756D03*
Y656356D03*
Y651956D03*
X1875121Y660756D03*
Y656356D03*
Y651956D03*
X1870121Y660756D03*
Y656356D03*
Y651956D03*
X1865121Y660756D03*
Y656356D03*
Y651956D03*
X1860121Y660756D03*
Y656356D03*
Y651956D03*
X1855121Y660756D03*
Y656356D03*
Y651956D03*
X1850121Y660756D03*
Y656356D03*
Y651956D03*
X1845121Y660756D03*
Y656356D03*
Y651956D03*
X1840121Y660756D03*
Y656356D03*
Y651956D03*
X1927921Y-40764D03*
X1947921Y-45764D03*
X1942921D03*
X1937921D03*
X1932921D03*
X1927921D03*
X1922921D03*
X1917921D03*
X1912921D03*
X1907921D03*
X1902921D03*
X1927921Y-50764D03*
X1932921D03*
Y-40764D03*
X1937921D03*
X1942921D03*
X1947921D03*
X1907921Y-50764D03*
X1902921D03*
X1922921Y-40764D03*
X1917921D03*
X1912921D03*
X1907921D03*
X1902921D03*
X1922921Y-54764D03*
X1917921D03*
X1912921D03*
X1907921D03*
X1902921D03*
X1927921D03*
X1932921D03*
X1937921D03*
X1942921D03*
X1947921D03*
X1952921D03*
X1957921D03*
Y-50764D03*
X1952921D03*
X1947921D03*
X1942921D03*
X1937921D03*
X1922921D03*
X1917921D03*
X1912921D03*
X1957921Y-35764D03*
Y-58764D03*
X1952921Y-35764D03*
Y-58764D03*
X1947921Y-35764D03*
Y-58764D03*
X1942921Y-35764D03*
Y-58764D03*
X1937921Y-35764D03*
Y-58764D03*
X1932921Y-35764D03*
Y-58764D03*
X1927921Y-35764D03*
Y-58764D03*
X1922921Y-35764D03*
Y-58764D03*
X1917921Y-35764D03*
Y-58764D03*
X1912921Y-35764D03*
Y-58764D03*
X1907921Y-35764D03*
Y-58764D03*
X1902921Y-35764D03*
Y-58764D03*
X1960106Y638753D03*
X1955106D03*
X1950106D03*
X1945121Y647556D03*
Y643156D03*
X1945106Y638753D03*
X1940121Y647556D03*
Y643156D03*
X1940106Y638753D03*
X1935121Y647556D03*
Y643156D03*
X1935106Y638753D03*
X1930106D03*
X1925106D03*
X1920121Y647556D03*
X1910121Y643156D03*
X1910106Y638753D03*
X1905121Y647556D03*
Y643156D03*
X1905106Y638753D03*
X1900121Y647556D03*
X1900106Y638753D03*
X1900121Y643156D03*
X1920106Y638753D03*
X1915121Y647556D03*
X1920121Y643156D03*
X1910121Y647556D03*
X1915106Y638753D03*
X1915121Y643156D03*
X1960121Y656356D03*
Y660756D03*
X1955121Y656356D03*
Y660756D03*
X1950121Y651956D03*
Y656356D03*
Y660756D03*
X1945121Y651956D03*
Y656356D03*
Y660756D03*
X1940121Y651956D03*
Y656356D03*
Y660756D03*
X1935121Y651956D03*
Y656356D03*
Y660756D03*
X1930121Y651956D03*
Y656356D03*
Y660756D03*
X1925121Y651956D03*
Y656356D03*
Y660756D03*
X1920121Y651956D03*
Y656356D03*
X1905121Y651956D03*
Y656356D03*
Y660756D03*
X1900121D03*
Y656356D03*
Y651956D03*
X1915121D03*
Y656356D03*
Y660756D03*
X1920121D03*
X1910121D03*
Y656356D03*
Y651956D03*
X1967921Y-45764D03*
X1962921D03*
Y-40764D03*
X1967921D03*
Y-54764D03*
X1962921D03*
X1967921Y-50764D03*
X1962921D03*
X1967921Y-35764D03*
Y-58764D03*
X1962921Y-35764D03*
Y-58764D03*
X1970121Y647556D03*
Y643156D03*
X1970106Y638753D03*
X1965121Y647556D03*
Y643156D03*
X1965106Y638753D03*
X1970121Y651956D03*
Y656356D03*
Y660756D03*
X1965121Y651956D03*
Y656356D03*
Y660756D03*
G54D20*
X1565000Y-15000D03*
X1723503Y-5000D03*
Y-15000D03*
X1753503Y-5000D03*
Y-15000D03*
G54D11*
G01X430749Y-124922D02*
G02I-12000J0D01*
G01X425599D02*
G02I-6850J0D01*
G01X434749D02*
X402749D01*
G01X434749Y-140922D02*
Y-220922D01*
G01D02*
X1729349D01*
G01X434749Y-176422D02*
X1729349D01*
G01X418749Y-140922D02*
Y-108922D01*
G01X434749Y-140922D02*
X1729349D01*
G01X941849D02*
Y-220922D01*
G01X1079349Y-140922D02*
Y-220922D01*
G01X1194349Y-140922D02*
Y-220922D01*
G01X1361849Y-140922D02*
Y-220922D01*
G01X1531849Y-140922D02*
Y-220922D01*
G01X1729349Y-140922D02*
Y-220922D01*
G01X1757349Y-124922D02*
G02I-12000J0D01*
G01X1752199D02*
G02I-6850J0D01*
G01X1745349Y-140922D02*
Y-108922D01*
G01X1761349Y-124922D02*
X1729349D01*
G01X1929453Y532541D02*
X1933555D01*
G01X1925351D02*
X1929453D01*
G01D02*
Y535443D01*
G01Y529639D02*
Y532541D01*
X-20700Y31400D03*
Y25200D03*
Y22300D03*
Y28100D03*
X-20600Y41200D03*
X-20526Y44263D03*
X-20500Y60300D03*
Y57300D03*
X-20700Y48800D03*
X-20726Y37463D03*
X-20800Y34400D03*
X-20500Y54300D03*
Y51300D03*
X-18000Y247400D03*
X-15000D03*
X-18000Y262700D03*
X-15000D03*
X-14690Y471140D03*
X-16726Y503651D03*
X-17084Y467626D03*
X-17300Y530800D03*
X-17397Y564242D03*
X30600Y-12000D03*
X25838Y-20458D03*
X10600Y25100D03*
X1068Y24831D03*
X27102Y25383D03*
X39530Y5205D03*
X45670Y5185D03*
X33370D03*
X45429Y-4669D03*
X33628Y131D03*
X40994Y-7148D03*
X45700Y40D03*
X11539Y31427D03*
X27200Y30600D03*
X27239Y28027D03*
X25600Y32500D03*
X11600Y33944D03*
X26760Y49595D03*
X27800Y86900D03*
X22100Y56400D03*
X27800Y89900D03*
Y83900D03*
X30400Y89800D03*
Y86800D03*
Y83800D03*
X10925Y56167D03*
X27904Y56294D03*
X30686Y79943D03*
X23530Y94840D03*
X11030D03*
X13530D03*
X16030D03*
X18530D03*
X22380Y92670D03*
X21030Y94840D03*
X2380Y92670D03*
X4880D03*
X7380D03*
X9880D03*
X12380D03*
X14880D03*
X17380D03*
X19880D03*
X3530Y94840D03*
X6030D03*
X8530D03*
X-1000Y81500D03*
X24880Y92670D03*
X25870Y80880D03*
X28294Y80889D03*
X32500Y81791D03*
X25100Y56300D03*
X-1190Y53240D03*
X25886Y71467D03*
X25925Y75867D03*
X26185Y67017D03*
X27488Y64671D03*
X11925Y65311D03*
X27625Y73967D03*
X27525Y69367D03*
X11925Y67811D03*
X11864Y62794D03*
X24064Y61894D03*
X15111Y62553D03*
X27564Y61894D03*
X11600Y36444D03*
X25900Y40300D03*
X27564Y59394D03*
X24064D03*
X25700Y36200D03*
X27300Y34300D03*
Y38300D03*
X27208Y42313D03*
X27239Y47027D03*
X25700Y44400D03*
X27525Y77867D03*
X44200Y139400D03*
X44300Y144800D03*
X44200Y130700D03*
Y116800D03*
X44100Y97800D03*
X44200Y111500D03*
X44300Y102700D03*
Y125600D03*
X44600Y154100D03*
X7995Y285385D03*
X32450Y454050D03*
X35100Y453900D03*
X35900Y423500D03*
X43550Y431300D03*
X20075Y424850D03*
X12025Y427900D03*
X7025D03*
X2025D03*
X21397Y439354D03*
Y444354D03*
X18836Y441785D03*
X7736D03*
X-6104Y461190D03*
X5000Y469000D03*
X10443Y490649D03*
X40132Y499800D03*
X24400Y519500D03*
X280Y524350D03*
X40185Y482918D03*
X37568Y482836D03*
X26780Y488910D03*
X21000Y495800D03*
X13300Y509600D03*
X13600Y504300D03*
X4000Y509500D03*
X2485Y498185D03*
X13700Y498500D03*
X24591Y479139D03*
X35896Y557668D03*
X33396D03*
X38696D03*
X-10200Y558200D03*
X21700Y532300D03*
X19100D03*
X27000D03*
X1040Y531218D03*
X21948Y566700D03*
X19448D03*
X27114Y557563D03*
X24748Y566700D03*
X0Y566800D03*
X29400Y532300D03*
X46400Y536290D03*
Y539790D03*
X43505Y538714D03*
X43241Y535965D03*
X41500Y533800D03*
X29914Y557563D03*
X45880Y554710D03*
Y557820D03*
X46560Y581000D03*
Y577500D03*
X1500Y540600D03*
X15787Y551700D03*
X17100Y545400D03*
X13639Y534683D03*
Y537183D03*
X15800Y543300D03*
X15600Y539100D03*
X17139Y534683D03*
Y537183D03*
X17100Y541200D03*
X17035Y549558D03*
X15800Y547500D03*
X17139Y553683D03*
X1500Y543100D03*
X1439Y538083D03*
X15800Y579500D03*
Y575300D03*
X17108Y585513D03*
X17156Y581481D03*
X17100Y577400D03*
X17139Y573183D03*
X1500Y576600D03*
X17139Y570683D03*
X1500Y579100D03*
X1439Y574083D03*
X15770Y587700D03*
X15800Y583500D03*
X27495Y591409D03*
X-12450Y590965D03*
X30212Y591417D03*
X35085Y591621D03*
X32609Y591538D03*
X46500Y595190D03*
X43190Y598410D03*
X43210Y595180D03*
X43190Y601910D03*
X17139Y589683D03*
X65800Y14200D03*
X59061Y476D03*
X61152Y-12752D03*
X59281Y-20641D03*
X99102Y-12010D03*
X105892Y8700D03*
X62076Y5575D03*
X76247Y1189D03*
X84202Y-11395D03*
X81702D03*
X79202D03*
X73611Y1158D03*
X71111D03*
X68611D03*
X73574Y-1437D03*
X71074D03*
X68574D03*
X79500Y-16600D03*
X55713Y-5095D03*
X76165Y-1415D03*
X106200Y26500D03*
X102100Y73800D03*
X105892Y45290D03*
X52500Y67200D03*
Y63700D03*
Y60700D03*
Y37700D03*
Y34700D03*
Y43700D03*
Y40700D03*
Y57700D03*
X71050Y89600D03*
X48700Y90700D03*
Y95500D03*
X61300Y89800D03*
X81861Y93392D03*
X108385Y84291D03*
X63737Y130602D03*
X48900Y132600D03*
X68592D03*
X85250Y127680D03*
X77730Y126860D03*
X63858Y97620D03*
X66600Y102360D03*
X62422Y109413D03*
X68000Y111000D03*
X48900Y123500D03*
X62524Y123395D03*
X68584Y123900D03*
X68654Y118680D03*
X48800Y118900D03*
X48700Y109600D03*
X48600Y104900D03*
X63582Y116409D03*
X62502Y105100D03*
X52500Y152000D03*
X60300Y151500D03*
X70800Y151400D03*
X48800Y137600D03*
X63878Y144800D03*
X68632Y137800D03*
X63888Y140064D03*
X107254Y128041D03*
X106698Y215610D03*
X100500Y188600D03*
X97500Y185700D03*
X104800D03*
X102400D03*
X99900D03*
X77650Y178150D03*
X73500Y191500D03*
X107750Y238730D03*
X83300Y267400D03*
X108000Y249330D03*
X53400Y277582D03*
Y274500D03*
X48800Y282600D03*
Y285100D03*
X53500Y307300D03*
X85300Y335750D03*
X69500Y322000D03*
X103500Y302100D03*
X99770Y325249D03*
X67400Y391690D03*
X67230Y397380D03*
X67710Y402040D03*
X55616Y368998D03*
X52000Y354500D03*
X61000Y383000D03*
X57500Y388100D03*
X77300Y390600D03*
X107224Y393848D03*
X76500Y368300D03*
X76300Y358400D03*
X82037Y358542D03*
X70600Y368400D03*
X82100Y368300D03*
X70900Y358300D03*
X51500Y406000D03*
X57471Y410749D03*
X64007Y408276D03*
X63630Y424280D03*
X63600Y429000D03*
X51890Y424470D03*
Y418970D03*
X103100Y411800D03*
X72603Y474072D03*
X60300Y508650D03*
X51607Y511747D03*
X74480Y504480D03*
X79630Y504580D03*
X60000Y526500D03*
X79400Y502150D03*
X74600Y502064D03*
X77000Y502133D03*
X49800Y524300D03*
X76996Y504587D03*
X60700Y521900D03*
X57936Y516012D03*
X60202Y495342D03*
X57302Y495442D03*
X105958Y518550D03*
X106392Y537000D03*
X105392Y574800D03*
X105412Y556580D03*
X105000Y614533D03*
X82459Y618932D03*
X105352Y594770D03*
X101898Y611483D03*
X150391Y14814D03*
X163427Y14714D03*
X157084Y14814D03*
X160431Y-1801D03*
X153738Y9114D03*
X150391Y-7851D03*
X163391D03*
X157084D03*
X153738Y-1751D03*
X160431Y9114D03*
X126616Y14714D03*
X136756Y16900D03*
X120273Y16839D03*
X132959Y14814D03*
X141880Y17114D03*
X147045Y9114D03*
X130163D03*
X141856Y9100D03*
X136780Y9098D03*
X123620Y9114D03*
X126580Y-7851D03*
X132959Y-7700D03*
X120273Y-9901D03*
X141893Y-9864D03*
X136806Y-9650D03*
X136780Y-1801D03*
X123620D03*
X130313Y-1751D03*
X141906Y-2050D03*
X147045Y-1751D03*
X169770Y14814D03*
X167124Y-1751D03*
X169770Y-7700D03*
X166974Y9114D03*
X169770Y30100D03*
X120273Y27899D03*
X141893Y27936D03*
X136806Y28150D03*
X126580Y29949D03*
X132959Y30100D03*
X157084Y29949D03*
X163391D03*
X150391D03*
X169770Y90364D03*
X166974Y84714D03*
Y73849D03*
Y46914D03*
X169770Y52614D03*
X167124Y36049D03*
X169770Y67900D03*
X157084Y67749D03*
X163391D03*
X130313Y73849D03*
X123620Y73799D03*
X141906Y73550D03*
X136780Y73799D03*
X126580Y67749D03*
X132959Y67900D03*
X141880Y54914D03*
X123620Y35983D03*
X141856Y46900D03*
X141906Y35750D03*
X136806Y65950D03*
X141893Y65736D03*
X136756Y54700D03*
X136780Y35999D03*
X130313Y35983D03*
X123620Y46914D03*
X132959Y52614D03*
X126616Y52514D03*
X147045Y46914D03*
Y36049D03*
X120273Y54839D03*
Y92500D03*
X126616Y90314D03*
X132959Y90414D03*
X141880Y92714D03*
X163427Y90314D03*
X157084Y90414D03*
X150391D03*
X160431Y84714D03*
X153738D03*
X136756Y92500D03*
X141856Y84700D03*
X136780Y84698D03*
X123620Y84714D03*
X147045D03*
X130163D03*
Y46914D03*
X136780Y46898D03*
X120273Y66000D03*
X147045Y73849D03*
X153738Y36049D03*
Y73849D03*
X160431Y73799D03*
X157084Y52614D03*
X160431Y35999D03*
X150391Y67749D03*
Y52614D03*
X163427Y52514D03*
X160431Y46914D03*
X153738D03*
X156954Y192872D03*
X154454Y193021D03*
X151810Y192670D03*
X124895Y212033D03*
X153788Y187309D03*
X156928Y190053D03*
X148900Y180400D03*
X148800Y185300D03*
Y182900D03*
X148900Y190100D03*
X148800Y187700D03*
X113800Y180500D03*
X116900D03*
X151359Y187700D03*
X156294Y187625D03*
X151300Y190200D03*
X141263Y215216D03*
X125563Y218616D03*
X137763Y217716D03*
X128500Y218700D03*
X141263Y217716D03*
X137763Y215216D03*
X154130Y190186D03*
X169150Y223600D03*
Y227600D03*
X112904Y237218D03*
X122820Y244133D03*
X123074Y275948D03*
X113100Y269163D03*
X125624Y223633D03*
Y221133D03*
X141263Y234216D03*
X141200Y229600D03*
X141211Y225615D03*
X141300Y221700D03*
X139763Y231700D03*
Y227600D03*
Y223700D03*
X139582Y219800D03*
X128200Y250700D03*
X125563Y250616D03*
X141263Y249716D03*
Y247216D03*
X137763D03*
Y249716D03*
X125624Y255633D03*
X141300Y253700D03*
X139631Y251900D03*
X125624Y253133D03*
X137763Y279216D03*
X141263Y266216D03*
X139763Y255700D03*
Y259600D03*
X139800Y263700D03*
X141313Y257533D03*
X141263Y279216D03*
X141200Y261600D03*
X137300Y337200D03*
X118800Y298400D03*
X123301Y308044D03*
X110180Y280920D03*
X109960Y313190D03*
X119050Y341625D03*
X113000Y304000D03*
X113100Y333106D03*
X125624Y287633D03*
X128200Y282600D03*
X141263Y311216D03*
X137763D03*
X141263Y281716D03*
X139730Y284200D03*
X139763Y288200D03*
Y292000D03*
Y296000D03*
X125624Y285133D03*
X141200Y286100D03*
X141261Y290076D03*
X141300Y294000D03*
X141263Y298216D03*
X137763Y281716D03*
X125563Y282616D03*
X141211Y325515D03*
X128200Y314800D03*
X141263Y330216D03*
X139763Y327800D03*
X141300Y317500D03*
Y321500D03*
X139582Y315800D03*
X139763Y319400D03*
X125563Y314616D03*
X141263Y313716D03*
X137763D03*
X139763Y323600D03*
X125624Y317133D03*
Y319633D03*
X109640Y376070D03*
X113500Y369000D03*
X110670Y344500D03*
X112600Y366300D03*
X122300Y372100D03*
X119300Y400900D03*
X110397Y402603D03*
X109924Y393848D03*
X141289Y349488D03*
X128100Y346700D03*
X141300Y353300D03*
X141200Y357200D03*
X137763Y345716D03*
X141263D03*
Y343216D03*
X125624Y349133D03*
X137763Y343216D03*
X141263Y362216D03*
X139582Y347800D03*
X139763Y351400D03*
Y355200D03*
Y359500D03*
X125624Y351633D03*
X125563Y346616D03*
X141300Y381800D03*
X139763Y384000D03*
X125624Y381133D03*
X141263Y394216D03*
Y390416D03*
X141261Y385876D03*
X139736Y392300D03*
X125563Y378616D03*
X137763Y375216D03*
X141263D03*
Y377716D03*
X137763D03*
X139631Y379900D03*
X128500Y378700D03*
X139900Y388000D03*
X125624Y383633D03*
X117363Y417416D03*
X130163Y510114D03*
X147045D03*
X132959Y515814D03*
X126616Y515714D03*
X120273Y517900D03*
X136780Y510098D03*
X136756Y517900D03*
X141856Y510100D03*
X141880Y518114D03*
X123620Y510114D03*
X150391Y515814D03*
X169770Y515764D03*
X163427Y515714D03*
X166974Y510114D03*
X160431D03*
X157084Y515814D03*
X153738Y510114D03*
X141893Y528936D03*
X136806Y529150D03*
X141906Y536750D03*
X132959Y553614D03*
X126616Y553514D03*
X130163Y547914D03*
X123620D03*
X136780Y547898D03*
X141856Y547900D03*
X147045Y537049D03*
Y547914D03*
X120210Y529200D03*
X130313Y537049D03*
X132959Y531100D03*
X126580Y530949D03*
X123620Y536999D03*
X136780D03*
X123620Y574799D03*
X130313Y574849D03*
X132959Y568900D03*
X126580Y568749D03*
X141856Y585700D03*
X141906Y574550D03*
X136780Y574799D03*
Y585698D03*
X120092Y566900D03*
X136806Y566950D03*
X147045Y585714D03*
Y574849D03*
X141880Y555914D03*
X120273Y555700D03*
X136756D03*
X141893Y566736D03*
X130163Y585714D03*
X123620D03*
X150391Y530949D03*
Y553614D03*
X166974Y537049D03*
X163391Y530949D03*
X160431Y536999D03*
X169770Y553564D03*
X163427Y553514D03*
X166974Y547914D03*
X160431D03*
X157084Y530949D03*
X153738Y537049D03*
X157084Y553614D03*
X153738Y547914D03*
X169770Y531100D03*
X150391Y568749D03*
X163391D03*
X160431Y585714D03*
X166974D03*
Y574849D03*
X160431Y574799D03*
X169770Y568900D03*
X157084Y568749D03*
X153738Y585714D03*
Y574849D03*
X147045Y612649D03*
X123620Y612599D03*
X136780D03*
X130313Y612649D03*
X160431Y612599D03*
X166974Y612649D03*
X153738D03*
X126616Y591314D03*
X116992Y590700D03*
X132959Y591414D03*
X136756Y593500D03*
X141880Y593714D03*
X132959Y606700D03*
X126580Y606549D03*
X120092Y604900D03*
X141906Y612350D03*
X136806Y604750D03*
X141893Y604536D03*
X150391Y591414D03*
Y606549D03*
X163427Y591314D03*
X163391Y606549D03*
X169770Y606700D03*
Y591364D03*
X157084Y591414D03*
Y606549D03*
X173591Y-1801D03*
X178691Y17114D03*
X173567Y16900D03*
X178717Y-2050D03*
X183856Y-1751D03*
X173617Y-9650D03*
X178704Y-9864D03*
X178667Y9100D03*
X173591Y9098D03*
X183856Y9114D03*
X178704Y27936D03*
X173617Y28150D03*
X190549Y9114D03*
X197242D03*
X210402Y9098D03*
X210428Y-9650D03*
X193895Y-7851D03*
X187202D03*
X200202D03*
X210402Y-1801D03*
X190549Y-1751D03*
X197242Y-1801D03*
X203935Y-1751D03*
X206581Y-7700D03*
X203785Y9114D03*
X210378Y16900D03*
X210428Y28150D03*
X200202Y29949D03*
X187202D03*
X193895Y14814D03*
Y29949D03*
X200238Y14714D03*
X187202Y14814D03*
X206581D03*
Y30100D03*
X220667Y-1751D03*
X215528Y-2050D03*
X215515Y-9864D03*
X227360Y-1751D03*
X230706Y-7851D03*
X224013D03*
X215478Y9100D03*
X220667Y9114D03*
X227360D03*
X224013Y29949D03*
X230706D03*
Y14814D03*
X224013D03*
X215502Y17114D03*
X215515Y27936D03*
X178691Y92714D03*
X173591Y84698D03*
X178667Y84700D03*
X183856Y84714D03*
X173567Y92500D03*
X183856Y36049D03*
X173591Y46898D03*
X183856Y73849D03*
X178717Y73550D03*
X173591Y73799D03*
X178691Y54914D03*
X173591Y35999D03*
X183856Y46914D03*
X178717Y35750D03*
X178667Y46900D03*
X173567Y54700D03*
X173617Y65950D03*
X178704Y65736D03*
X206581Y52614D03*
X210378Y54700D03*
X210402Y46898D03*
X193895Y67749D03*
X200202D03*
X187202D03*
X203785Y46914D03*
X190549D03*
X197242D03*
X200238Y52514D03*
X193895Y52614D03*
X187202D03*
X190549Y36049D03*
X203935D03*
X197242Y35999D03*
X206581Y67900D03*
X210428Y65950D03*
X210402Y35999D03*
X197242Y73799D03*
X203935Y73849D03*
X210402Y73799D03*
Y84698D03*
X210378Y92500D03*
X190549Y73849D03*
Y84714D03*
X197242D03*
X203785D03*
X193895Y90414D03*
X206581D03*
X200238Y90314D03*
X187202Y90414D03*
X215478Y46900D03*
X215502Y54914D03*
X215515Y65736D03*
X224013Y52614D03*
X220667Y46914D03*
X230706Y52614D03*
X224013Y67749D03*
X230706D03*
X227360Y46914D03*
Y36049D03*
X220667D03*
X215528Y35750D03*
X215502Y92714D03*
X220667Y73849D03*
Y84714D03*
X227360D03*
X230706Y90414D03*
X215478Y84700D03*
X215528Y73550D03*
X227360Y73849D03*
X224013Y90414D03*
X197617Y243089D03*
X191537Y242989D03*
Y240489D03*
X197617Y240589D03*
X191537Y237989D03*
X197617Y238089D03*
X192037Y270750D03*
X194537D03*
X197037D03*
X194537Y299750D03*
X197037D03*
X192037D03*
X194537Y332480D03*
X197037D03*
X192037D03*
X194500Y360200D03*
X197137Y360350D03*
X191900Y360173D03*
X195200Y377800D03*
Y380300D03*
X172697Y407196D03*
X197242Y510114D03*
X200238Y515714D03*
X203785Y510114D03*
X190549D03*
X187202Y515814D03*
X193895D03*
X183856Y510114D03*
X173591Y510098D03*
X173567Y517900D03*
X178691Y518114D03*
X206581Y515814D03*
X210402Y510098D03*
X210378Y517900D03*
X215502Y518114D03*
X215478Y510100D03*
X224013Y515814D03*
X220667Y510114D03*
X227360D03*
X230706Y515814D03*
X193895Y553614D03*
X200238Y553514D03*
X183856Y547914D03*
X190549D03*
X203785D03*
X197242D03*
X190549Y537049D03*
X183856D03*
X187202Y530949D03*
X193895D03*
X197242Y536999D03*
X203935Y537049D03*
X200202Y530949D03*
X206581Y553614D03*
X210402Y547898D03*
X178717Y536750D03*
X173617Y529150D03*
X173591Y536999D03*
X178704Y528936D03*
X178667Y547900D03*
X173591Y547898D03*
X206581Y531100D03*
X210402Y536999D03*
X210428Y529150D03*
X187202Y553614D03*
X178691Y555914D03*
X173567Y555700D03*
X210378D03*
X203935Y574849D03*
X200202Y568749D03*
X197242Y574799D03*
X190549Y585714D03*
X183856D03*
X187202Y568749D03*
X193895D03*
X190549Y574849D03*
X183856D03*
X210402Y585698D03*
X206581Y568900D03*
X210428Y566950D03*
X210402Y574799D03*
X178667Y585700D03*
X178717Y574550D03*
X173591Y574799D03*
Y585698D03*
X173617Y566950D03*
X178704Y566736D03*
X197242Y585714D03*
X203785D03*
X215515Y528936D03*
X215528Y536750D03*
X215478Y547900D03*
X224013Y530949D03*
X220667Y537049D03*
X230706Y530949D03*
X227360Y537049D03*
X230706Y553614D03*
X220667Y547914D03*
X227360D03*
X224013Y553614D03*
X215502Y555914D03*
X220667Y585714D03*
X215528Y574550D03*
X215478Y585700D03*
X215515Y566736D03*
X224013Y568749D03*
X220667Y574849D03*
X230706Y568749D03*
X227360Y574849D03*
Y585714D03*
Y612649D03*
X220667D03*
X203935D03*
X197242Y612599D03*
X190549Y612649D03*
X183856D03*
X210402Y612599D03*
X173591D03*
X187202Y591414D03*
X193895D03*
X187202Y606549D03*
X193895D03*
X200202D03*
X210428Y604750D03*
X206581Y606700D03*
X210378Y593500D03*
X206581Y591414D03*
X178717Y612350D03*
X173617Y604750D03*
X178704Y604536D03*
X173567Y593500D03*
X178691Y593714D03*
X200238Y591314D03*
X224013Y606549D03*
X230706D03*
Y591414D03*
X215515Y604536D03*
X215528Y612350D03*
X215502Y593714D03*
X224013Y591414D03*
X270864Y-1801D03*
X247213D03*
X240746Y-1751D03*
X264171D03*
X252339Y-2050D03*
X234053Y-1801D03*
X257478Y-1751D03*
X243392Y-7700D03*
X260824Y-7851D03*
X252326Y-9864D03*
X237013Y-7851D03*
X247239Y-9650D03*
X267517Y-7851D03*
X252289Y9100D03*
X264171Y9114D03*
X240596D03*
X247213Y9098D03*
X270864Y9114D03*
X234053D03*
X257478D03*
X267517Y14814D03*
Y29949D03*
X247189Y16900D03*
X252326Y27936D03*
X243392Y30100D03*
X247239Y28150D03*
X260824Y29949D03*
X237013D03*
X252313Y17114D03*
X243392Y14814D03*
X260824D03*
X237049Y14714D03*
X284050Y-9650D03*
X289137Y-9864D03*
X273824Y-7851D03*
X280203Y-7700D03*
X289100Y9100D03*
X284024Y9098D03*
X277407Y9114D03*
X277557Y-1751D03*
X289150Y-2050D03*
X284024Y-1801D03*
X273824Y29949D03*
X273860Y14714D03*
X284000Y16900D03*
X280203Y14814D03*
Y30100D03*
X289124Y17114D03*
X284050Y28150D03*
X289137Y27936D03*
X247213Y46898D03*
X257478Y46914D03*
X240596D03*
X243392Y67900D03*
X267517Y67749D03*
Y52614D03*
X270864Y46914D03*
X252326Y65736D03*
X237013Y67749D03*
X260824D03*
X247239Y65950D03*
X243392Y52614D03*
X264171Y46914D03*
X247213Y35999D03*
X257478Y36049D03*
X252339Y35750D03*
X234053Y35999D03*
X240746Y36049D03*
X264171D03*
X237049Y52514D03*
X252289Y46900D03*
X247189Y54700D03*
X252313Y54914D03*
X260824Y52614D03*
X270864Y35999D03*
X234053Y46914D03*
X247213Y73799D03*
Y84698D03*
X264171Y84714D03*
X252339Y73550D03*
X257478Y84714D03*
X240746Y73849D03*
X257478D03*
X234053Y73799D03*
X264171Y73849D03*
X243392Y90414D03*
X252313Y92714D03*
X237049Y90314D03*
X270864Y84714D03*
X247189Y92500D03*
X240596Y84714D03*
X234053D03*
X252289Y84700D03*
X260824Y90414D03*
X267517D03*
X270864Y73799D03*
X273824Y67749D03*
X280203Y67900D03*
X284024Y35999D03*
X277557Y36049D03*
X277407Y46914D03*
X289137Y65736D03*
X284050Y65950D03*
X284024Y46898D03*
X284000Y54700D03*
X289100Y46900D03*
X289150Y35750D03*
X289124Y54914D03*
X280203Y52614D03*
X273860Y90314D03*
X277407Y84714D03*
X289100Y84700D03*
X284024Y84698D03*
X284000Y92500D03*
X289150Y73550D03*
X284024Y73799D03*
X289124Y92714D03*
X280203Y90414D03*
X277407Y73849D03*
X264171Y104284D03*
X267517Y109984D03*
X270864Y104284D03*
X257478D03*
X260824Y109984D03*
X243392Y109534D03*
X252339Y112865D03*
X247213Y113114D03*
X237049Y109884D03*
X240596Y104284D03*
X247239Y105265D03*
X252326Y105051D03*
X234053Y104284D03*
X273860Y109884D03*
X284050Y105265D03*
X289137Y105051D03*
X289150Y112865D03*
X284024Y113114D03*
X280203Y109534D03*
X277407Y104284D03*
X271239Y211060D03*
X284759Y207159D03*
X291519D03*
X274619Y213009D03*
Y216909D03*
X277999Y211060D03*
Y214960D03*
Y203260D03*
Y207159D03*
X281379Y213009D03*
X288139Y216909D03*
X284759Y214960D03*
X291519D03*
Y218860D03*
X281379Y201309D03*
X284759Y199360D03*
X291519D03*
X267859Y244209D03*
Y240309D03*
X271239Y238360D03*
X264179D03*
Y250060D03*
X264092Y222710D03*
X264179Y226660D03*
X271239Y269560D03*
Y273460D03*
Y265660D03*
X267859Y263709D03*
Y259809D03*
X264179Y265660D03*
X267859Y252009D03*
X264179Y253960D03*
X291519Y238360D03*
X284759Y234460D03*
X288139Y232509D03*
X281379D03*
X277999Y234460D03*
X274619Y232509D03*
Y220809D03*
Y224709D03*
Y228610D03*
X277999Y230559D03*
X274619Y244209D03*
X277999Y250060D03*
X274619Y240309D03*
Y248109D03*
Y236409D03*
X291519Y246160D03*
Y250060D03*
X284759Y246160D03*
X291519Y242260D03*
X281379Y220809D03*
X284759Y226660D03*
X288139Y236409D03*
X291519Y234460D03*
Y222760D03*
Y230559D03*
Y226660D03*
X281379Y240309D03*
Y252009D03*
X274619D03*
X277999Y253960D03*
X284759D03*
X291519D03*
X284759Y265660D03*
X291519D03*
Y277360D03*
X281379Y275409D03*
Y271509D03*
X284759Y277360D03*
Y273460D03*
X288139Y275409D03*
Y271509D03*
X277999Y277360D03*
X274619Y255909D03*
Y259809D03*
X277999Y269560D03*
X274619Y275409D03*
Y267609D03*
Y263709D03*
X288139Y255909D03*
X291519Y269560D03*
Y257860D03*
Y261760D03*
X281379Y259809D03*
X288139Y252009D03*
X271239Y328060D03*
X267859Y333909D03*
Y341709D03*
Y330009D03*
X264179Y328060D03*
Y339760D03*
X291519Y285160D03*
Y292959D03*
X284759Y285160D03*
X277999Y308560D03*
Y300760D03*
Y292959D03*
Y285160D03*
X291519Y308560D03*
X284759D03*
Y300760D03*
X291519D03*
X284759Y292959D03*
X291519Y316360D03*
X281379Y318309D03*
X291519Y328060D03*
X288139Y341709D03*
X274619Y330009D03*
Y326110D03*
Y322209D03*
X277999Y328060D03*
X274619Y341709D03*
X277999Y320260D03*
Y316360D03*
X274619Y333909D03*
Y337809D03*
X284759Y324160D03*
X288139Y318309D03*
X284759Y316360D03*
X281379Y337809D03*
X291519Y339760D03*
Y335860D03*
X284759Y331960D03*
X291519D03*
X281379Y326110D03*
X288139D03*
X267559Y369010D03*
X271239Y355360D03*
X267859Y349509D03*
Y353409D03*
X267559Y361209D03*
X264179Y343660D03*
Y355360D03*
X267492Y380709D03*
X271239Y390460D03*
X267859Y388509D03*
X271239Y382660D03*
X284759Y351460D03*
X281379Y345609D03*
X291519Y359260D03*
Y355360D03*
Y351460D03*
X284759Y343660D03*
X274619Y365109D03*
X277999Y363160D03*
Y367060D03*
X274619Y369010D03*
Y361209D03*
Y345609D03*
X277999Y347560D03*
X274619Y353409D03*
Y357309D03*
Y349509D03*
X277999Y343660D03*
X291519Y347560D03*
Y343660D03*
X288139Y365109D03*
X281379D03*
X284759Y363160D03*
X291519D03*
X284759Y370959D03*
X291519Y367060D03*
Y370959D03*
X288139Y361209D03*
X281379Y357309D03*
X288139Y345609D03*
Y380709D03*
Y400209D03*
X274619Y380709D03*
X277999Y394359D03*
X274619Y392410D03*
X277999Y390460D03*
Y386560D03*
X274619Y376809D03*
Y372909D03*
X291519Y374860D03*
X277999Y382660D03*
X284759Y398260D03*
X281379Y396309D03*
X291519Y398260D03*
X284759Y390460D03*
X291519D03*
X281379Y376809D03*
Y384609D03*
X284759Y382660D03*
X291519D03*
Y378760D03*
X264171Y510114D03*
X257478D03*
X260824Y515814D03*
Y491044D03*
X247177Y490514D03*
X252313D03*
X236892Y493400D03*
X243392Y493094D03*
X267584Y491219D03*
X271092Y495944D03*
X257392Y495800D03*
X264192D03*
X233292Y495900D03*
X239492Y498500D03*
X247177Y498514D03*
X252313D03*
X252289Y510100D03*
X267517Y515814D03*
X270864Y510114D03*
X247189Y517900D03*
X252313Y518114D03*
X247213Y510098D03*
X240596Y510114D03*
X243392Y515814D03*
X234053Y510114D03*
X237049Y515714D03*
X284024Y490644D03*
X289124D03*
X273860Y515714D03*
X277557Y495944D03*
X277407Y510114D03*
X289100Y510100D03*
X289124Y518114D03*
X284024Y510098D03*
X280203Y515814D03*
X273992Y491144D03*
X280203Y490644D03*
X284024Y498644D03*
X289124D03*
X284000Y517900D03*
X257478Y537049D03*
X237013Y530949D03*
X252339Y536750D03*
X243392Y531100D03*
X247213Y536999D03*
X252326Y528936D03*
X240746Y537049D03*
X234053Y536999D03*
X267517Y553614D03*
X270864Y547914D03*
X267517Y530949D03*
X270864Y536999D03*
X260824Y553614D03*
X237049Y553514D03*
X243392Y553614D03*
X264171Y547914D03*
X257478D03*
X252289Y547900D03*
X240596Y547914D03*
X247213Y547898D03*
X234053Y547914D03*
X264171Y537049D03*
X260824Y530949D03*
X247189Y555700D03*
X252313Y555914D03*
X270864Y574799D03*
Y585714D03*
X267517Y568749D03*
X247239Y566950D03*
X252326Y566736D03*
X234053Y574799D03*
X240746Y574849D03*
X247213Y574799D03*
X234053Y585714D03*
X237013Y568749D03*
X264171Y585714D03*
X257478D03*
X264171Y574849D03*
X257478D03*
X260824Y568749D03*
X252339Y574550D03*
X252289Y585700D03*
X240596Y585714D03*
X247213Y585698D03*
X243392Y568900D03*
X277407Y537049D03*
X273824Y530949D03*
X273860Y553514D03*
X284024Y547898D03*
X289100Y547900D03*
X280203Y553614D03*
Y531100D03*
X284024Y536999D03*
X289137Y528936D03*
X284050Y529150D03*
X289150Y536750D03*
X277407Y547914D03*
X273824Y568749D03*
X284000Y555700D03*
X289124Y555914D03*
X280203Y568900D03*
X277407Y574849D03*
Y585714D03*
X289100Y585700D03*
X289150Y574550D03*
X284024Y574799D03*
Y585698D03*
X284050Y566950D03*
X289137Y566736D03*
X284024Y612599D03*
X240746Y612649D03*
X247213Y612599D03*
X234053D03*
X257478Y612649D03*
X247239Y604750D03*
X252326Y604536D03*
X260824Y606549D03*
X237013D03*
X243392Y606700D03*
X264171Y612449D03*
X252339Y612350D03*
X267517Y591414D03*
X260824D03*
X237049Y591314D03*
X247189Y593500D03*
X252313Y593714D03*
X243392Y591414D03*
X267517Y606549D03*
X270864Y612399D03*
X273824Y606549D03*
X273860Y591314D03*
X284050Y604750D03*
X289150Y612350D03*
X280203Y606700D03*
Y591414D03*
X277407Y612449D03*
X289124Y593714D03*
X284000Y593500D03*
X289137Y604536D03*
X297635Y-7851D03*
X304328D03*
X300982Y-1751D03*
X294289D03*
X321061Y-1743D03*
X314368Y-1843D03*
X331100Y-4536D03*
X327754Y-7108D03*
X317714Y-9786D03*
X311021D03*
X314368Y9114D03*
X321061D03*
X331100D03*
X294289D03*
X300982D03*
X307675Y-1843D03*
X311021Y28014D03*
X307675Y9300D03*
X304328Y29949D03*
X307992Y13200D03*
X297635Y14814D03*
X308092Y32100D03*
X297635Y29949D03*
X304328Y14814D03*
X317714Y28014D03*
X311021Y17057D03*
X317714D03*
X327754D03*
Y28014D03*
X347833Y-7108D03*
X351179Y9122D03*
Y-4536D03*
X341140Y-1743D03*
X337793Y-9901D03*
X341140Y9122D03*
X347833Y17057D03*
Y28022D03*
X337793Y17057D03*
Y28014D03*
X311021Y65814D03*
X317714D03*
X321061Y35957D03*
X307950Y50729D03*
X300982Y36049D03*
X294289Y46914D03*
X304328Y52614D03*
X307675Y35957D03*
X304328Y67749D03*
X297635D03*
X294289Y36049D03*
X300982Y46914D03*
X297635Y52614D03*
X314368Y35957D03*
Y46914D03*
X311021Y54857D03*
X317714D03*
X321061Y46914D03*
X331100D03*
X327754Y65814D03*
X331100Y35957D03*
X327754Y54857D03*
Y92757D03*
X331100Y84714D03*
Y73757D03*
X314368D03*
Y87392D03*
X311021Y89964D03*
X317714D03*
X321061Y87392D03*
Y73757D03*
X307992Y70400D03*
X304278Y90414D03*
X307592Y73800D03*
X300982Y84714D03*
X294289D03*
X300982Y73849D03*
X294289D03*
X308166Y87394D03*
X297635Y90414D03*
X341140Y35957D03*
X337793Y65814D03*
Y54857D03*
X351179Y46922D03*
X347833Y54857D03*
X341140Y46922D03*
X347833Y65822D03*
X351179Y35957D03*
X347833Y92757D03*
X351179Y84599D03*
Y73757D03*
X337793Y89964D03*
X341140Y87392D03*
Y73757D03*
X326592Y105600D03*
X313637Y105725D03*
X300992Y112300D03*
X297642Y107700D03*
X304192Y105000D03*
X294899Y213009D03*
X308418Y201309D03*
X317428Y193507D03*
X301648Y194841D03*
X332078Y218860D03*
X329818Y214958D03*
X298279Y218860D03*
X311798Y211060D03*
Y218860D03*
Y214960D03*
X308418Y213009D03*
X305039Y211060D03*
Y218860D03*
X324200Y201308D03*
X298279Y199360D03*
X294899Y201309D03*
X312918Y205210D03*
X315178Y209109D03*
X298279Y207159D03*
Y203260D03*
Y211060D03*
X318558Y218860D03*
X315178Y216909D03*
Y213009D03*
X301659Y209109D03*
X325318Y211060D03*
X345598Y214960D03*
X352357D03*
X334328Y199108D03*
X345598Y203260D03*
X355737Y205210D03*
X338838Y211058D03*
X335458Y216909D03*
X294899Y224709D03*
X332078Y242260D03*
Y250060D03*
X328698Y232509D03*
Y220809D03*
X332078Y234460D03*
X298279Y246160D03*
X325318Y250060D03*
X321938Y248109D03*
X305039Y246160D03*
X308418Y244209D03*
X294899D03*
Y248109D03*
X325318Y242260D03*
Y226660D03*
X298279Y234460D03*
X308418Y228610D03*
Y224709D03*
X305039Y230559D03*
X311798Y222760D03*
X308418Y232509D03*
X294899Y228610D03*
X325318Y234460D03*
Y230559D03*
Y222760D03*
X305039Y250060D03*
X318558Y246160D03*
X301659Y248109D03*
X308418Y240309D03*
X315178D03*
X301659D03*
X318558Y242260D03*
X298279Y226660D03*
X318558D03*
X315178Y220809D03*
X321938D03*
X315178Y232509D03*
X301659Y228610D03*
X308418Y236409D03*
X321938D03*
X311798Y238360D03*
X318558D03*
X305039Y226660D03*
X308418Y252009D03*
X298279Y253960D03*
X325318D03*
X308418Y275409D03*
X301659D03*
X308418Y255909D03*
X321938Y275409D03*
X315178Y279310D03*
X318558Y277360D03*
X311798Y261760D03*
X321938Y259809D03*
X301659D03*
X308418Y263709D03*
X325318Y269560D03*
X305039D03*
X318558D03*
X328698Y267609D03*
Y259809D03*
X332078Y269560D03*
X321938Y255909D03*
X308418Y259809D03*
X325318Y273460D03*
Y265660D03*
X301659Y267609D03*
X321938Y263709D03*
X294899Y275409D03*
Y263709D03*
X298279Y265660D03*
X305039Y273460D03*
Y277360D03*
X311798D03*
Y269560D03*
X305039Y265660D03*
X298279Y277360D03*
X328698Y252009D03*
X355737Y244209D03*
X348978D03*
X345598Y226660D03*
X352357D03*
X348978Y232509D03*
X342218Y220809D03*
X355737Y232509D03*
X338838Y246160D03*
X335458Y248109D03*
X338838Y242260D03*
Y234460D03*
X335458Y236409D03*
X338838Y238360D03*
X335458Y224709D03*
X338838Y253960D03*
X335458Y252009D03*
X338838Y265660D03*
X335458Y259809D03*
Y267609D03*
X345598Y265660D03*
X348978Y263709D03*
X355737Y259809D03*
X352357Y261760D03*
X345598Y273460D03*
Y269560D03*
X342218Y263709D03*
Y271509D03*
Y259809D03*
Y255909D03*
Y267609D03*
Y279310D03*
Y275409D03*
X311798Y292959D03*
X305039D03*
X321938Y283209D03*
X315178D03*
X318558Y281260D03*
Y292959D03*
X311798Y285160D03*
X328698Y310509D03*
X332078Y300760D03*
X328698Y283209D03*
X332078Y292959D03*
Y281260D03*
X298279Y308560D03*
X321938Y310509D03*
X315178D03*
X305039Y308560D03*
X311798D03*
X305039Y300760D03*
X325318D03*
X311798D03*
X298279D03*
X318558D03*
X325318Y292959D03*
Y281260D03*
X305039Y285160D03*
X298279D03*
Y292959D03*
X318558Y312460D03*
X325318D03*
X308418Y333909D03*
Y341709D03*
X325318Y339760D03*
Y335860D03*
X301659Y337809D03*
X315178Y330009D03*
X301659D03*
X308418Y337809D03*
X305039Y331960D03*
X298279Y328060D03*
Y331960D03*
X311798Y324160D03*
X308418Y330009D03*
X315178Y322209D03*
X321938D03*
X294899Y333909D03*
X305039Y328060D03*
X321938Y330009D03*
Y337809D03*
X328698Y330009D03*
Y326110D03*
Y333909D03*
X325318Y324160D03*
X318558Y320260D03*
X301659Y318309D03*
X308418D03*
X305039Y316360D03*
X332078Y331960D03*
Y339760D03*
X298279Y316360D03*
X294899Y322209D03*
Y318309D03*
X311798Y316360D03*
X308418Y326110D03*
X315178Y314409D03*
X332078Y312460D03*
X335458Y310509D03*
X338838Y300760D03*
Y292959D03*
Y281260D03*
X335458Y283209D03*
X342218Y310509D03*
Y283209D03*
X345598Y335860D03*
Y331960D03*
X342218Y314409D03*
X338838Y312460D03*
Y316360D03*
X335458Y330009D03*
X338838Y331960D03*
Y339760D03*
X345598Y328060D03*
Y339760D03*
X352357Y335860D03*
X348978Y333909D03*
X342218Y322209D03*
Y318309D03*
Y330009D03*
Y326110D03*
Y333909D03*
X355737Y337809D03*
X345598Y320260D03*
Y324160D03*
X308418Y357309D03*
X311798Y359260D03*
X298279Y351460D03*
X294899Y349509D03*
Y353409D03*
X321938Y349509D03*
X318558Y359260D03*
X321938Y361209D03*
X298279Y343660D03*
X315178Y357309D03*
X301659D03*
Y349509D03*
X308418Y361209D03*
Y353409D03*
Y345609D03*
X305039Y347560D03*
X325318Y343660D03*
Y347560D03*
X328698Y365109D03*
X332078Y363160D03*
X328698Y345609D03*
X325318Y355360D03*
X332078Y347560D03*
Y355360D03*
X294899Y369010D03*
X325318Y367060D03*
Y370959D03*
X318558D03*
X308418Y365109D03*
X315178D03*
X325318Y363160D03*
X298279D03*
X305039Y370959D03*
X308418Y369010D03*
X305039Y367060D03*
X301659Y369010D03*
X298279Y370959D03*
X318558Y351460D03*
Y355360D03*
X305039Y351460D03*
X301659Y388509D03*
X308418D03*
X318558Y394359D03*
X324458Y399911D03*
X332078Y378760D03*
X318558Y386560D03*
X325318D03*
X311798Y374860D03*
X325318D03*
X294899Y372909D03*
X308418D03*
X321938Y376809D03*
X318558Y382660D03*
Y378760D03*
X298279D03*
X305039D03*
X308418Y384609D03*
X311798Y382660D03*
Y378760D03*
X315178Y376809D03*
X328698D03*
X294899Y384609D03*
X318558Y390460D03*
X320808Y401941D03*
X298279Y386560D03*
Y390460D03*
X315178Y392410D03*
Y388509D03*
X311798Y386560D03*
X298279Y398260D03*
Y394359D03*
X294899Y396309D03*
X325318Y378760D03*
X321938Y380709D03*
X305039Y394359D03*
X302608Y402421D03*
X355737Y353409D03*
X338838Y347560D03*
X335458Y361209D03*
X338838Y359260D03*
Y355360D03*
Y351460D03*
X335458Y349509D03*
X345598Y359260D03*
X348978Y349509D03*
X345598Y343660D03*
X342218Y345609D03*
X355737Y349509D03*
X348978Y365109D03*
X355737D03*
X352357Y370959D03*
X342218Y376809D03*
X345598Y382660D03*
X352357D03*
X348978Y392410D03*
X355737D03*
X335458Y372909D03*
Y384609D03*
Y380709D03*
X294289Y490444D03*
X301092Y490700D03*
X326797Y499767D03*
X317714Y515364D03*
X321061Y512792D03*
X311701Y499136D03*
X331100Y510114D03*
X327754Y518157D03*
X314368Y512792D03*
X311021Y515364D03*
X297835Y497644D03*
X308166Y512794D03*
X300982Y510114D03*
X304278Y515814D03*
X297635D03*
X294289Y510114D03*
X304392Y497300D03*
X337793Y515364D03*
X350882Y509999D03*
X347833Y518157D03*
X341140Y512792D03*
X321061Y536957D03*
X317714Y529014D03*
X331100Y547914D03*
Y536957D03*
X327754Y529014D03*
X321061Y547914D03*
X314368D03*
Y536957D03*
X311021Y529014D03*
X307675Y548200D03*
X304278Y553614D03*
X297635D03*
X300982Y547914D03*
X294289D03*
X307675Y536957D03*
X304328Y530949D03*
X300982Y537049D03*
X297635Y530949D03*
X294289Y537049D03*
X307992Y533100D03*
X308100Y552000D03*
X307992Y570900D03*
X294289Y574849D03*
Y585714D03*
X304328Y568749D03*
X307675Y574757D03*
X300982Y574849D03*
X307848Y588334D03*
X300982Y585714D03*
X297635Y568749D03*
X327754Y555857D03*
X317714D03*
X311021D03*
X327754Y566814D03*
X331100Y574757D03*
Y585714D03*
X314368D03*
Y574757D03*
X317714Y566814D03*
X311021D03*
X321061Y585714D03*
Y574757D03*
X337793Y529014D03*
X351179Y547922D03*
Y536957D03*
X347833Y529022D03*
X341140Y547922D03*
Y536957D03*
X337793Y555857D03*
X347833D03*
X337793Y566814D03*
X341140Y574757D03*
Y585722D03*
X351179Y574757D03*
Y585722D03*
X347833Y566822D03*
X304328Y606549D03*
X297635D03*
X294289Y612249D03*
X300982D03*
X307675Y611600D03*
X307892Y591000D03*
X304278Y591414D03*
X297635D03*
X327754Y607292D03*
X331100Y609864D03*
X327754Y593657D03*
X317714D03*
X311021D03*
X317714Y604614D03*
X311021D03*
X314368Y612457D03*
X321061D03*
X337793Y593657D03*
Y604499D03*
X352109Y609918D03*
X347833Y607292D03*
X341140Y612457D03*
X347833Y593657D03*
X377592Y-10880D03*
X380232Y-10900D03*
X357872Y-9786D03*
X367911D03*
Y-1858D03*
X357872D03*
X367911Y9114D03*
X357672D03*
X357872Y28014D03*
X367911D03*
Y17042D03*
X357872Y17014D03*
X398029Y-4536D03*
X401375Y-7108D03*
X408068Y-1743D03*
X411415Y-9786D03*
X398029Y9107D03*
X408069D03*
X394192Y-9700D03*
X409522Y-20794D03*
X411416Y17057D03*
X401376Y17042D03*
X367911Y46914D03*
Y54842D03*
Y35942D03*
X358619Y36031D03*
X358618Y54842D03*
X357872Y65736D03*
X366992Y65950D03*
X357872Y46914D03*
X357965Y92500D03*
X367911Y87500D03*
X368311Y92500D03*
X367742Y73450D03*
X357872Y87500D03*
X358491Y73479D03*
X408069Y35942D03*
X401376Y54842D03*
X408069Y46907D03*
X398029Y35942D03*
Y46907D03*
X411416Y54857D03*
X401375Y92757D03*
X398029Y84800D03*
Y73742D03*
X408068Y87392D03*
X411415Y89964D03*
X408069Y73742D03*
X408126Y105750D03*
X414820Y105800D03*
X401375D03*
X357987Y193507D03*
X378267D03*
X386157Y207159D03*
X382777Y201309D03*
X365877Y214960D03*
X372637D03*
X379397D03*
X359117D03*
X365877Y203260D03*
X376017Y205211D03*
X362497Y205210D03*
X386157Y214960D03*
X415634Y204496D03*
Y212296D03*
X404392Y199100D03*
X415634Y208397D03*
X392898Y195041D03*
X392916Y214960D03*
Y203260D03*
X396296Y197359D03*
X399676Y203260D03*
Y214960D03*
X386157Y226660D03*
X389537Y232509D03*
X369257Y244209D03*
X362497D03*
X372637Y226660D03*
X365877D03*
X369257Y232509D03*
X362497D03*
X379397Y226660D03*
X382777Y232509D03*
X376017D03*
X359117Y226660D03*
X372637Y250060D03*
X365877Y253960D03*
X362497Y255909D03*
X359117Y257860D03*
X390894Y264899D03*
X369257Y252009D03*
X407706Y240309D03*
Y232509D03*
X415634Y247396D03*
Y235696D03*
Y223996D03*
X392916Y226660D03*
X396296Y232509D03*
X399676Y226660D03*
X397394Y264899D03*
X400394D03*
X393894D03*
X407448Y338641D03*
X416448D03*
X413948D03*
X410948D03*
X370650Y312441D03*
X378156D03*
X375674D03*
X373162Y312400D03*
X368165Y312504D03*
X359117Y339760D03*
X362497Y341709D03*
X403648Y338341D03*
X401148D03*
X398148D03*
X394648D03*
X379397Y347560D03*
Y370959D03*
X372637D03*
X365877D03*
X359117D03*
X386157D03*
X362497Y353409D03*
X376017D03*
X369257D03*
Y345609D03*
X376017D03*
X372637Y347560D03*
X365877Y343660D03*
X389537Y365109D03*
X382777D03*
X369257D03*
X362497D03*
X376017D03*
X390657Y394359D03*
X391787Y402800D03*
X357987D03*
X369257Y392410D03*
X362497D03*
X379397Y382660D03*
X372637D03*
X365877D03*
X359117D03*
X379397Y390460D03*
X378267Y402800D03*
X376017Y392410D03*
X386157Y382660D03*
X392916Y370959D03*
X399676D03*
X396296Y365109D03*
X403056D03*
Y357309D03*
X392916Y382660D03*
Y390460D03*
X399676Y382660D03*
X406568Y402471D03*
X403056Y392410D03*
X386630Y521860D03*
X359042Y515200D03*
X358918Y510114D03*
X366865D03*
Y515152D03*
X401375Y518157D03*
X398029Y509999D03*
X411415Y515364D03*
X408068Y512792D03*
X370080Y555700D03*
X366890Y586000D03*
X367692Y547914D03*
X357672D03*
X357872Y528942D03*
X367911Y529057D03*
X367692Y536200D03*
X357910Y536727D03*
X367211Y555842D03*
X357910D03*
X367192Y566814D03*
X357910D03*
X367192Y574742D03*
X357872D03*
X357025Y585714D03*
X398029Y536942D03*
X408069Y547907D03*
Y536942D03*
X398029Y547907D03*
X401376Y555842D03*
X411416Y555857D03*
X398029Y574742D03*
Y585707D03*
X408069D03*
Y574742D03*
X408068Y612657D03*
X413324Y623559D03*
X399824D03*
X357872Y604614D03*
X367170Y611759D03*
X357872Y612242D03*
X367911Y593642D03*
X357026D03*
X367911Y604614D03*
X398029Y609864D03*
X401376Y593642D03*
X401375Y607292D03*
X411416Y593657D03*
X411415Y604614D03*
X418108Y-4536D03*
X431494D03*
X424801D03*
X428147Y-7108D03*
X434840D03*
X431494Y9107D03*
X424801D03*
X418108D03*
Y-9701D03*
X441533Y-1843D03*
Y9107D03*
X447744Y-7180D03*
X451573Y-1801D03*
Y9114D03*
X436392Y-20760D03*
X422892Y-20789D03*
X434842Y17057D03*
X441533Y17042D03*
X418108D03*
X428149Y17057D03*
X448226Y28100D03*
X448292Y31900D03*
Y13700D03*
X448892Y17000D03*
X418108Y28007D03*
X441533D03*
X458266Y-1751D03*
X460912Y-7700D03*
X454533Y-7851D03*
X458116Y9114D03*
X469832Y-2051D03*
X464732Y-1801D03*
X474998Y-1751D03*
X469845Y-9864D03*
X478344Y-7851D03*
X464758Y-9652D03*
X474998Y9114D03*
X464732Y9098D03*
X478344Y29949D03*
X460912Y30100D03*
Y14814D03*
X469832Y17114D03*
X454569Y14714D03*
X454533Y29949D03*
X469792Y9300D03*
X478344Y14814D03*
X469845Y27936D03*
X464792Y28100D03*
X464692Y16900D03*
X434842Y54857D03*
X441533Y54842D03*
X424801Y46907D03*
X431494D03*
X428149Y54857D03*
X441533Y46907D03*
X448414Y35761D03*
X448973Y54883D03*
X451573Y35999D03*
X448627Y68090D03*
X448517Y46975D03*
X448492Y51000D03*
X451573Y46900D03*
X418108Y65807D03*
Y54842D03*
X441533Y65807D03*
X431494Y35942D03*
X441533D03*
X424801D03*
X418108D03*
Y46907D03*
X428147Y92500D03*
X424801Y84800D03*
X431400D03*
X431494Y73742D03*
X441533Y87392D03*
Y92500D03*
Y73742D03*
X418108Y89964D03*
Y84599D03*
Y73742D03*
X424801D03*
X434840Y92500D03*
X448651Y70896D03*
X451573Y84714D03*
Y73799D03*
X448610Y85296D03*
X448599Y73589D03*
X448692Y89900D03*
X474998Y36049D03*
X464732Y46898D03*
X460912Y52614D03*
X458266Y36049D03*
X458116Y46914D03*
X464758Y65950D03*
X474998Y46914D03*
X454533Y67749D03*
X454569Y52514D03*
X469832Y54914D03*
X469792Y47100D03*
Y35800D03*
X464692Y54700D03*
X464732Y35999D03*
X478344Y52614D03*
X460912Y67900D03*
X478344Y67749D03*
X469845Y65736D03*
X458116Y84714D03*
X464708Y92500D03*
X464732Y84698D03*
X469808Y84700D03*
X474998Y73849D03*
X469858Y73550D03*
X474998Y84714D03*
X478344Y90414D03*
X469832Y92714D03*
X460912Y90314D03*
X464732Y73799D03*
X458266Y73849D03*
X454569Y90314D03*
X427696Y105800D03*
X421503D03*
X441743Y199841D03*
X421464Y199583D03*
X446253Y206446D03*
X425974D03*
X453013Y218147D03*
X449633Y212296D03*
Y216196D03*
X422594D03*
X419214Y214247D03*
X436113Y212296D03*
X432733Y214247D03*
X429354Y216196D03*
X432733Y218147D03*
X425974D03*
X429353Y212296D03*
X446253Y218147D03*
X442873Y216196D03*
X439493Y214247D03*
X436113Y216196D03*
X453013Y214247D03*
X439493Y210346D03*
X434983Y198931D03*
X455263Y198050D03*
X473292Y218147D03*
X469913Y216196D03*
X469912Y212296D03*
X475692Y199900D03*
X466533Y218147D03*
X473292Y214247D03*
X476672Y212296D03*
Y216196D03*
X459773Y214247D03*
X466533Y206446D03*
X456393Y216196D03*
X462023Y198327D03*
X456393Y212296D03*
X463153Y216196D03*
X429354Y251296D03*
X453013Y245447D03*
Y229847D03*
Y237647D03*
X449633Y251296D03*
Y247396D03*
Y227896D03*
Y223996D03*
X436113Y243496D03*
X442873D03*
X422594D03*
X425974Y245447D03*
Y249347D03*
X432733D03*
X436113Y251296D03*
X429354Y247396D03*
X422594Y251296D03*
X446253Y245447D03*
X419214Y249347D03*
X432733Y245447D03*
X439493Y237647D03*
X446253D03*
X422594Y223996D03*
Y231797D03*
X419214Y233746D03*
Y237647D03*
X436113Y231797D03*
X439493Y241547D03*
X419214D03*
X436113Y223996D03*
X429354D03*
Y220096D03*
Y227896D03*
X446253Y229847D03*
X432733D03*
X425974D03*
X439493Y233746D03*
X442873Y231797D03*
Y223996D03*
X425974Y237647D03*
X432733D03*
X449633Y220096D03*
X439493Y253247D03*
X449633Y255196D03*
Y259096D03*
X446253Y257147D03*
X442873Y255196D03*
X453013Y257147D03*
Y261047D03*
X448900Y269600D03*
X469913Y251296D03*
X466533Y245447D03*
X473292D03*
X476672Y223996D03*
Y243496D03*
Y251296D03*
X469913Y247396D03*
Y223996D03*
X473292Y229847D03*
X469913Y227896D03*
X466533Y229847D03*
X473292Y237647D03*
X466533D03*
X469913Y220096D03*
X456393Y243496D03*
Y251296D03*
X459773Y233746D03*
Y241547D03*
Y237647D03*
X456393Y223996D03*
Y231797D03*
X476672D03*
X463153Y243496D03*
Y251296D03*
Y231797D03*
Y223996D03*
X476672Y259096D03*
X463153D03*
X458408Y278940D03*
X477792Y272747D03*
X462023Y271097D03*
X458643Y269146D03*
X456393Y262996D03*
Y259096D03*
X459773Y261047D03*
X469913Y255196D03*
X473292Y257147D03*
X466533D03*
X468783Y274997D03*
X469913Y270796D03*
X466533Y264947D03*
X426494Y338361D03*
X430089Y338428D03*
X419400Y338600D03*
X469913Y305896D03*
X477792Y307851D03*
X469913Y286396D03*
X477792Y303947D03*
Y288347D03*
Y315647D03*
Y319547D03*
X458643Y338746D03*
X477792Y327347D03*
X462948Y315251D03*
X455263Y340697D03*
X462848Y312741D03*
X467653Y340996D03*
X474413D03*
Y337096D03*
X469913Y321496D03*
X443993Y358547D03*
X441743Y348497D03*
X440613Y352696D03*
X437233Y358547D03*
X450753Y366347D03*
Y350747D03*
Y358547D03*
X437233Y362447D03*
X423714D03*
X433854Y368296D03*
X427094D03*
X440613Y364396D03*
X427094Y372197D03*
X447373D03*
Y368296D03*
X440613Y372197D03*
Y368296D03*
X443993Y366347D03*
X427094Y356596D03*
X433854Y352696D03*
X437233Y354647D03*
X423714D03*
X430474D03*
X427094Y360496D03*
X433854D03*
X445123Y346546D03*
X427094Y352696D03*
X430474Y385847D03*
X450753Y397547D03*
X440613Y395595D03*
X429354Y399496D03*
X433854Y379996D03*
X423714Y374146D03*
X437233D03*
X430474Y378047D03*
X433854Y376096D03*
X443993Y397546D03*
Y401447D03*
Y393647D03*
X440613Y391696D03*
X443993Y385847D03*
X427094Y376096D03*
X437233Y381947D03*
X447373Y376096D03*
X440613Y379996D03*
X443993Y378047D03*
X423715Y397548D03*
X430474Y393647D03*
X433854Y391696D03*
X423715Y401449D03*
X450753Y385847D03*
Y393647D03*
Y378047D03*
X437233Y389747D03*
Y385847D03*
X423714D03*
X477792Y342947D03*
Y362447D03*
Y354647D03*
Y358547D03*
X457513Y362447D03*
X454133Y372197D03*
Y364396D03*
Y348796D03*
Y352696D03*
X464273Y366347D03*
X474413Y372197D03*
X471033Y366347D03*
X467653Y372197D03*
X474413Y364396D03*
X464273Y350747D03*
X474413Y348796D03*
X471033Y350747D03*
X474413Y352696D03*
X471033Y358547D03*
X464273D03*
X467653Y368296D03*
Y348796D03*
X460893Y372197D03*
Y364396D03*
Y352696D03*
X457513Y354647D03*
Y358547D03*
Y346847D03*
X477792Y389747D03*
X457513D03*
X471033Y393647D03*
X460893Y395595D03*
X464273Y401447D03*
X471033D03*
X460893Y391696D03*
X457513Y385847D03*
Y381947D03*
X460893Y379996D03*
X477792Y381947D03*
X474413Y391696D03*
X464273Y385847D03*
X454133Y391696D03*
Y379996D03*
X471033Y385847D03*
X464273Y393647D03*
X474413Y379996D03*
X471033Y378047D03*
X467653Y376096D03*
X464273Y378047D03*
Y397546D03*
X477792Y385847D03*
X447091Y407782D03*
X428224Y407800D03*
X443993Y405347D03*
X467653Y407296D03*
X464273Y405347D03*
X441533Y512792D03*
Y518057D03*
X433192Y497650D03*
X434840Y518157D03*
X431494Y509999D03*
X424801Y510114D03*
X418108Y515364D03*
Y509999D03*
X428147Y518157D03*
X451573Y510114D03*
X474998D03*
X464732Y510098D03*
X460912Y515714D03*
X458116Y510114D03*
X454569Y515714D03*
X478344Y515814D03*
X464708Y517900D03*
X469832Y518114D03*
X418108Y536942D03*
Y547907D03*
X431494D03*
X424801D03*
X441533D03*
X418108Y529007D03*
X431494Y536942D03*
X424801D03*
X441533Y536957D03*
Y529007D03*
X451573Y547914D03*
Y536999D03*
X448510Y549843D03*
X448410Y531156D03*
X448432Y536723D03*
X448692Y553100D03*
X448557Y534061D03*
X451573Y585714D03*
Y574799D03*
X448226Y569200D03*
X448291Y574773D03*
X418108Y555842D03*
X428149Y555857D03*
X434842D03*
X441533Y555842D03*
Y585707D03*
Y574742D03*
X418108Y566807D03*
X441533D03*
X424801Y574742D03*
X418108Y585599D03*
Y574742D03*
X431494D03*
Y585707D03*
X424801D03*
X464732Y536999D03*
X460912Y553514D03*
X458116Y547914D03*
X454569Y553514D03*
X454533Y530949D03*
X460912Y531100D03*
X458266Y537049D03*
X469845Y528936D03*
X474998Y537049D03*
X464758Y529150D03*
X469858Y536750D03*
X478344Y553614D03*
X464732Y547898D03*
X474998Y547914D03*
X469808Y547900D03*
X478344Y530949D03*
Y568749D03*
X464732Y574799D03*
X469808Y585700D03*
X469858Y574550D03*
X474998Y574849D03*
Y585714D03*
X464732Y585698D03*
X464758Y566950D03*
X469845Y566736D03*
X458266Y574849D03*
X460912Y568900D03*
X458116Y585714D03*
X454533Y568749D03*
X464708Y555700D03*
X469832Y555914D03*
X441533Y612557D03*
X474998Y612649D03*
X464732Y612599D03*
X458266Y612649D03*
X427324Y623541D03*
X451573Y612599D03*
X441533Y607292D03*
X434840D03*
X428147D03*
X418108Y609864D03*
X424801D03*
X447744Y607220D03*
X448692Y590900D03*
X431494Y609864D03*
X418108Y593642D03*
X434842Y593657D03*
X428149D03*
X441533Y593642D03*
X418108Y604499D03*
X478344Y591414D03*
X464708Y593500D03*
X469832Y593714D03*
X464758Y604750D03*
X469845Y604536D03*
X478344Y606549D03*
X469858Y612350D03*
X460912Y591314D03*
Y606700D03*
X454533Y606549D03*
X454569Y591314D03*
X511809Y-1751D03*
Y9114D03*
X495077Y-1751D03*
X501544Y-1801D03*
X506692Y-2000D03*
X488384Y-1801D03*
X481691Y-1751D03*
X485037Y-7851D03*
X491344D03*
X506657Y-9864D03*
X497723Y-7700D03*
X501592Y-9700D03*
X481691Y9114D03*
X494927D03*
X488384D03*
X501544Y9098D03*
X497723Y14814D03*
X506644Y17114D03*
X506657Y27936D03*
X497723Y30100D03*
X491380Y14714D03*
X506604Y9300D03*
X485037Y14814D03*
X501504Y16900D03*
X485037Y29949D03*
X491344D03*
X501603Y28100D03*
X515155Y-7851D03*
X538355Y9098D03*
X518502Y-1751D03*
X521848Y-7851D03*
X538355Y-1801D03*
X531888Y-1751D03*
X525195Y-1801D03*
X538403Y-9700D03*
X528155Y-7851D03*
X534534Y-7700D03*
X518502Y9114D03*
X531738D03*
X525195D03*
X521848Y14814D03*
Y29949D03*
X528191Y14714D03*
X538315Y16900D03*
X534534Y30100D03*
X515155Y29949D03*
Y14814D03*
X534534D03*
X528155Y29949D03*
X538415Y28100D03*
X488384Y35999D03*
X501492Y54700D03*
X497723Y52614D03*
Y67900D03*
X501544Y46898D03*
X511809Y46914D03*
X491344Y67749D03*
X506657Y65736D03*
X501570Y65950D03*
X481691Y36049D03*
X495077D03*
X506644Y54914D03*
X494927Y46914D03*
X485037Y52614D03*
X481691Y46914D03*
X511809Y36049D03*
X485037Y67749D03*
X488384Y46914D03*
X506603Y35800D03*
X506592Y47000D03*
X501544Y35999D03*
X511809Y84714D03*
X501544Y84698D03*
X494927Y84714D03*
X506670Y73550D03*
X481691Y84714D03*
X488384D03*
X501520Y92500D03*
X506620Y84700D03*
X511809Y73849D03*
X488384Y73799D03*
X481691Y73849D03*
X506644Y92714D03*
X491380Y90314D03*
X497723Y90414D03*
X485037D03*
X495077Y73849D03*
X501544Y73799D03*
X518502Y36049D03*
Y46914D03*
X521848Y67749D03*
X531888Y36049D03*
X538355Y35999D03*
X534534Y52614D03*
X531738Y46914D03*
X525195Y35999D03*
X515155Y67749D03*
Y52614D03*
X521848D03*
X534534Y67900D03*
X538381Y65950D03*
X528155Y67749D03*
X538355Y46898D03*
X538304Y54700D03*
X525195Y46914D03*
X515155Y90414D03*
X534534D03*
X528191Y90314D03*
X521848Y90414D03*
X518502Y73849D03*
Y84714D03*
X531738D03*
X525195D03*
X538355Y84698D03*
X538331Y92500D03*
X531888Y73849D03*
X525195Y73799D03*
X538355D03*
X512024Y104314D03*
X497723Y109564D03*
X501544Y113114D03*
X506670Y112865D03*
X501570Y105265D03*
X491430Y109564D03*
X506657Y105051D03*
X488634Y104314D03*
X495077D03*
X514820Y109564D03*
X521113D03*
X528191Y109914D03*
X534534Y109564D03*
X538355Y113114D03*
X531738Y104314D03*
X525134D03*
X538381Y105265D03*
X518467Y104314D03*
X511592Y206447D03*
Y210346D03*
Y218147D03*
X486812Y214247D03*
Y218147D03*
X498350Y209900D03*
X501452Y212296D03*
X480052Y214247D03*
Y206447D03*
X486812Y210346D03*
X508212Y212296D03*
X518352Y218147D03*
Y206445D03*
X538631Y210346D03*
Y214247D03*
Y206447D03*
X528491Y208397D03*
X525111Y218147D03*
X528491Y216196D03*
X535251Y204496D03*
X525111Y206447D03*
X531871D03*
X521731Y208397D03*
X511592Y241547D03*
Y249347D03*
X486812Y245447D03*
X494692Y247396D03*
X483432Y251296D03*
X501452Y247396D03*
X480052Y237647D03*
X508212Y239596D03*
X498072Y233746D03*
X486812D03*
Y229847D03*
X494692Y235696D03*
X504832Y229847D03*
X486812Y225947D03*
X498072Y222047D03*
Y225947D03*
X486812Y222047D03*
Y237647D03*
X480052Y233746D03*
X504832Y241547D03*
X480052D03*
X486812D03*
X494692Y243496D03*
X483432D03*
X504832Y245447D03*
X501452Y223996D03*
X508212Y231797D03*
Y220096D03*
Y223996D03*
X483432Y235696D03*
Y223996D03*
X494692Y251296D03*
X501452Y274696D03*
X508212Y278596D03*
X484552Y268847D03*
X494692Y255196D03*
X486812Y257147D03*
X504832Y253247D03*
X487932Y278596D03*
Y274696D03*
X494692Y278596D03*
X501452Y266896D03*
Y259096D03*
X483432D03*
X481172Y274696D03*
Y278596D03*
X508212Y270796D03*
X494692D03*
X480052Y261047D03*
X518352Y229847D03*
X521731Y231797D03*
Y235696D03*
Y247396D03*
Y220096D03*
X538631Y225947D03*
Y222047D03*
Y237647D03*
X528491Y247396D03*
Y243496D03*
X538631Y249347D03*
X535251Y235696D03*
X528491Y227896D03*
Y235696D03*
Y220096D03*
X535251Y247396D03*
Y251296D03*
Y239596D03*
X531871Y222047D03*
X525111Y237647D03*
X514972Y247396D03*
Y227896D03*
Y235696D03*
Y239596D03*
Y223996D03*
X535251Y259096D03*
X531871Y261047D03*
X514972Y270796D03*
Y278596D03*
X525111Y253247D03*
X518352D03*
X528491Y274696D03*
X531871Y268847D03*
Y276646D03*
X535251Y266896D03*
X525111Y280547D03*
X521731Y266896D03*
Y259096D03*
Y274696D03*
X538631Y257147D03*
X504832Y307847D03*
X525111Y315647D03*
X494692Y294196D03*
X501452Y290296D03*
Y282496D03*
X491312Y292245D03*
Y300047D03*
X508212Y290296D03*
Y294196D03*
X511592Y307847D03*
Y284447D03*
X481172Y309797D03*
X494692D03*
X481172Y301996D03*
X487932Y309797D03*
X498072Y303947D03*
X487932Y282496D03*
X484552Y300047D03*
Y292245D03*
X494692Y286396D03*
X501452Y298096D03*
X481172Y290296D03*
X508212Y329296D03*
X487932Y317596D03*
X504832Y319547D03*
X484552Y323446D03*
X508212Y317596D03*
Y325396D03*
X491312Y339047D03*
X494692Y337096D03*
X511592Y327347D03*
Y339047D03*
Y331247D03*
Y335147D03*
Y315647D03*
Y323446D03*
X508212Y313696D03*
X481172D03*
X494692Y340996D03*
X504832Y331247D03*
X508212Y337096D03*
Y333196D03*
X504832Y335147D03*
X501452Y333196D03*
X504832Y339047D03*
X501452Y340996D03*
X504832Y315647D03*
X498072Y319547D03*
X504832Y323446D03*
X498072Y327347D03*
X491312Y331247D03*
X511592Y319547D03*
X538631Y311747D03*
X535251Y290296D03*
X514972Y301996D03*
Y290296D03*
Y286396D03*
Y294196D03*
X525111Y284447D03*
X531871Y288347D03*
Y292245D03*
X528491Y294196D03*
X525111Y300047D03*
X531871D03*
X521731Y301996D03*
X528491Y286396D03*
Y298096D03*
X535251Y294196D03*
X538631Y292245D03*
Y288347D03*
Y284447D03*
X531871Y303947D03*
X535251Y301996D03*
X531871Y311747D03*
Y307847D03*
X535251Y309797D03*
X514972Y333196D03*
Y321496D03*
Y317596D03*
Y329296D03*
Y325396D03*
Y337096D03*
X518352Y319547D03*
Y323446D03*
Y315647D03*
X521731Y317596D03*
Y325396D03*
X518352Y327347D03*
Y339047D03*
X531871Y335147D03*
X525111D03*
X528491Y337096D03*
X531871Y327347D03*
X535251Y329296D03*
X538631Y335147D03*
Y339047D03*
X528491Y317596D03*
X531871Y319547D03*
X535251Y321496D03*
X538631Y319547D03*
X504832Y342947D03*
X491312Y370247D03*
X498072Y366347D03*
X494692Y372197D03*
X504832Y366347D03*
X501452Y368296D03*
X487932D03*
X484552Y362447D03*
X498072D03*
X491312D03*
X494692Y360496D03*
X487932D03*
X501452Y344896D03*
X504832Y354647D03*
X494692Y344896D03*
Y348796D03*
X491312Y350747D03*
Y366347D03*
X487932Y372197D03*
X484552Y370247D03*
X481172Y372197D03*
X484552Y366347D03*
X487932Y364396D03*
X494692D03*
X501452D03*
X491312Y358547D03*
X498072Y350747D03*
Y346847D03*
X501452Y360496D03*
X498072Y342947D03*
X491312Y346847D03*
X494692Y356596D03*
X498072Y358547D03*
Y354647D03*
X481172Y344896D03*
Y360496D03*
X484552Y346847D03*
X508212Y352696D03*
Y360496D03*
X504832Y346847D03*
Y358547D03*
X501452Y356596D03*
Y348796D03*
Y352696D03*
X511592Y370247D03*
X481172Y352696D03*
X484552Y393647D03*
X481172Y391696D03*
X484552Y385847D03*
X498072Y393647D03*
X494692Y391696D03*
X491312Y385847D03*
X498072D03*
X508212Y387796D03*
X501452Y391696D03*
Y395597D03*
X491312Y389747D03*
X504832Y381947D03*
Y378047D03*
X501452Y379996D03*
X481172Y395596D03*
X511592Y378047D03*
Y397546D03*
X491312Y378047D03*
X484552D03*
X481172Y379996D03*
X487932Y376096D03*
X491312Y381947D03*
Y374146D03*
X498072Y397546D03*
X487932Y403396D03*
Y399496D03*
X491312Y397546D03*
X487932Y395597D03*
X514972Y372197D03*
Y356596D03*
X521731Y360496D03*
Y356596D03*
Y348796D03*
X518352Y342947D03*
Y362447D03*
X521731Y372197D03*
X518352Y370247D03*
X525111Y354647D03*
X531871Y346847D03*
X535251Y356596D03*
X538631Y366347D03*
X528491Y364396D03*
X525111Y342947D03*
X514972Y403396D03*
Y379996D03*
X531871Y374146D03*
X521731Y399496D03*
X518352Y397546D03*
Y389747D03*
X535251Y383896D03*
X525111Y381947D03*
X538631Y393647D03*
Y378047D03*
X528491Y403396D03*
X531871Y401447D03*
Y389747D03*
X525111Y393647D03*
X484552Y405347D03*
X538750Y406200D03*
X511712Y495800D03*
X488384Y495887D03*
X494777D03*
X491380Y493744D03*
X506644Y490867D03*
X501560D03*
X497723Y493494D03*
X506620Y510100D03*
X506644Y518114D03*
X501544Y510098D03*
X485037Y515814D03*
X481691Y510114D03*
X491380Y515714D03*
X511809Y510114D03*
X497723Y515814D03*
X494927Y510114D03*
X488384D03*
X501520Y517900D03*
X506644Y498867D03*
X501560D03*
X514755Y491044D03*
X521048Y491144D03*
X538370Y490609D03*
X528241Y490944D03*
X534534Y490794D03*
X515155Y515814D03*
X530792Y495787D03*
X524595D03*
X517892Y495800D03*
X534534Y515814D03*
X528191Y515714D03*
X531738Y510114D03*
X525195D03*
X538355Y510098D03*
X538331Y517900D03*
X521848Y515814D03*
X518502Y510114D03*
X538370Y498609D03*
X506670Y536750D03*
X501570Y529150D03*
X506657Y528936D03*
X501544Y536999D03*
X511809Y547914D03*
Y537049D03*
X491380Y553514D03*
X497723Y553614D03*
X485037D03*
X506620Y547900D03*
X501544Y547898D03*
X481691Y547914D03*
X494927D03*
X488384D03*
X481691Y537049D03*
X491344Y530949D03*
X488384Y536999D03*
X495077Y537049D03*
X497723Y531100D03*
X485037Y530949D03*
Y568749D03*
X481691Y574849D03*
Y585714D03*
X501544Y585698D03*
Y574799D03*
X506657Y566736D03*
X501570Y566950D03*
X506670Y574550D03*
X506620Y585700D03*
X488384Y585714D03*
X511809D03*
Y574849D03*
X494927Y585714D03*
X491344Y568749D03*
X501520Y555700D03*
X506644Y555914D03*
X497723Y568900D03*
X488384Y574799D03*
X495077Y574849D03*
X515155Y553614D03*
Y530949D03*
X534534Y531100D03*
X531888Y537049D03*
X528155Y530949D03*
X525195Y536999D03*
X538355D03*
X538381Y529150D03*
X525195Y547914D03*
X531738D03*
X538355Y547898D03*
X534534Y553614D03*
X528191Y553514D03*
X518502Y547914D03*
X521848Y553614D03*
X518502Y537049D03*
X521848Y530949D03*
X515155Y568749D03*
X538331Y555700D03*
X518502Y585714D03*
Y574849D03*
X521848Y568749D03*
X538355Y585698D03*
Y574799D03*
X538381Y566950D03*
X531738Y585714D03*
X525195D03*
X534534Y568900D03*
X525195Y574799D03*
X528155Y568749D03*
X531888Y574849D03*
X525195Y612599D03*
X518502Y612649D03*
X538355Y612599D03*
X531888Y612649D03*
X501544Y612599D03*
X495077Y612649D03*
X488384Y612599D03*
X511809Y612649D03*
X497723Y591414D03*
X486250Y591020D03*
X491380Y591314D03*
X501520Y593500D03*
X506644Y593714D03*
X501570Y604750D03*
X506657Y604536D03*
X491344Y606549D03*
X497723Y606700D03*
X485037Y607230D03*
X506670Y612350D03*
X480950Y612430D03*
X515155Y606549D03*
Y591414D03*
X521848D03*
Y606549D03*
X534534Y591414D03*
X528191Y591314D03*
X538331Y593500D03*
X538381Y604750D03*
X534534Y606700D03*
X528155Y606549D03*
X562006Y9114D03*
X568549D03*
X555313D03*
X548620D03*
X571345Y-7700D03*
X551966Y-7851D03*
X564966D03*
X558659D03*
X562006Y-1801D03*
X555313Y-1751D03*
X568699D03*
X548620D03*
X543503Y-2000D03*
X543468Y-9864D03*
X543455Y17114D03*
X564992Y14714D03*
X543415Y9300D03*
X558659Y14814D03*
Y29949D03*
X551966Y14814D03*
Y29949D03*
X564966D03*
X571345Y14814D03*
Y30100D03*
X543468Y27936D03*
X575166Y9098D03*
X602163Y16999D03*
X575214Y-9700D03*
X575166Y-1801D03*
X580279Y-9864D03*
X580314Y-2000D03*
X588777Y-7851D03*
X598817Y-9901D03*
X595470Y-7851D03*
X592124Y-1751D03*
X598817D03*
X585431D03*
X602163Y-9901D03*
X598817Y9157D03*
X592124Y9114D03*
X585431D03*
X575182Y16900D03*
X575192Y28100D03*
X580192Y9300D03*
X588777Y29949D03*
X580279Y27936D03*
X595470Y29949D03*
Y14814D03*
X598817Y27899D03*
X588777Y14814D03*
X580266Y17114D03*
X562006Y46914D03*
X551966Y52614D03*
X565352Y52864D03*
X548620Y46914D03*
Y36049D03*
X558659Y52614D03*
X568699Y36049D03*
X555313D03*
X562006Y35999D03*
X551966Y67749D03*
X564966D03*
X571345Y52614D03*
Y67900D03*
X558659Y67749D03*
X568549Y46914D03*
X555313D03*
X543468Y65736D03*
X543404Y47000D03*
X543415Y35800D03*
X543455Y54914D03*
Y92714D03*
X548620Y84714D03*
X568549D03*
X555313D03*
X562006D03*
X543481Y73550D03*
X543431Y84700D03*
X548620Y73849D03*
X568699D03*
X562006Y73799D03*
X555313Y73849D03*
X558659Y90414D03*
X551966D03*
X571345D03*
X575166Y46898D03*
Y35999D03*
X575192Y65950D03*
X585431Y46914D03*
X595470Y52614D03*
X588777D03*
X585431Y36049D03*
X592124D03*
X598817D03*
Y46957D03*
X592124Y46914D03*
X598817Y65699D03*
X595470Y67749D03*
X588777D03*
X580266Y54914D03*
X580192Y35750D03*
X580279Y65736D03*
X602163Y65699D03*
X592124Y84714D03*
X585431D03*
X598817Y84757D03*
X580242Y84700D03*
X580266Y92714D03*
X588777Y90414D03*
X602163Y92599D03*
X575166Y73799D03*
X575142Y92500D03*
X575166Y84698D03*
X595470Y90414D03*
X585431Y73849D03*
X592124D03*
X598817D03*
X580292Y73550D03*
X548620Y104314D03*
X555313D03*
X558659Y110014D03*
X551966D03*
X543481Y112865D03*
X543468Y105051D03*
X602100Y109600D03*
X555531Y216196D03*
X557000Y206800D03*
X548771Y212296D03*
X552151Y214247D03*
X547800Y201400D03*
X545391Y210346D03*
X552151Y218147D03*
Y225947D03*
X558911Y222047D03*
X552151Y233746D03*
X548771Y235696D03*
X558911Y229847D03*
X552151D03*
X562591Y220096D03*
X564084Y235685D03*
X545391Y225947D03*
Y222047D03*
Y233746D03*
X542011Y239596D03*
Y247396D03*
X552151Y241547D03*
X548771Y239596D03*
X552151Y249347D03*
X555531Y247396D03*
X562591Y251296D03*
X548771Y243496D03*
X562591D03*
X572930Y232750D03*
Y228130D03*
X552151Y257147D03*
X562591Y255196D03*
X548771D03*
X573200Y262600D03*
X573100Y258600D03*
X548771Y266896D03*
X558911Y264947D03*
X563800Y275900D03*
X559211Y280547D03*
X548771Y278596D03*
X558911Y272747D03*
X555531Y274696D03*
X564500Y264800D03*
Y268800D03*
X552151Y261047D03*
X545391Y272747D03*
Y280547D03*
Y264947D03*
Y268847D03*
X542011Y274696D03*
X580360Y234590D03*
Y230060D03*
X545391Y307847D03*
X555831Y309797D03*
Y305896D03*
X548771Y309797D03*
X555831Y298096D03*
X552151Y284447D03*
X548771Y286396D03*
X552151Y288347D03*
Y296147D03*
X558145Y286727D03*
X545391Y296147D03*
Y288347D03*
Y292245D03*
Y300047D03*
X542011Y294196D03*
Y298096D03*
X545391Y303947D03*
X548771Y313696D03*
X561971Y317320D03*
X548771Y325396D03*
X558911Y335147D03*
X555531Y333196D03*
X562591D03*
X548771Y340996D03*
X561966Y325502D03*
X559211Y319547D03*
X552151Y323446D03*
X545391Y319547D03*
X542011Y321496D03*
X545391Y335147D03*
Y331247D03*
Y315647D03*
X552151Y350747D03*
X558911Y342947D03*
X559212Y370247D03*
X548771Y368296D03*
X562591Y352696D03*
Y344896D03*
X563200Y356596D03*
X545391Y354647D03*
Y346847D03*
X542011Y368296D03*
X545391Y366347D03*
Y358547D03*
X542011Y360496D03*
Y348796D03*
X559212Y374146D03*
X555531Y387797D03*
X559212Y381947D03*
Y393647D03*
X552151Y378047D03*
X545391Y397546D03*
Y385847D03*
X542011Y376096D03*
X573867Y459903D03*
X575614Y461694D03*
X584076Y443828D03*
X588285Y448306D03*
X586136Y446335D03*
X558659Y493444D03*
X551366Y490744D03*
X543455Y490909D03*
X555313Y510114D03*
X548492Y495800D03*
X554792Y495887D03*
X543431Y510100D03*
X543455Y518114D03*
X551966Y515814D03*
X548620Y510114D03*
X543455Y498909D03*
X568549Y510114D03*
X562006D03*
X571345Y515814D03*
X558659D03*
X582912Y468948D03*
X581032Y467202D03*
X575166Y510098D03*
X575142Y517900D03*
X580266Y518114D03*
X580242Y510100D03*
X598817Y510157D03*
X595470Y515814D03*
X588777D03*
X602163Y517999D03*
X592124Y510114D03*
X585431D03*
X543468Y528936D03*
X543481Y536750D03*
X543431Y547900D03*
X548620Y547914D03*
X551966Y553614D03*
X548620Y537049D03*
X551966Y530949D03*
X558659D03*
X555313Y537049D03*
X562006Y536999D03*
X564966Y530949D03*
X568699Y537049D03*
X571345Y553614D03*
Y531100D03*
X558659Y553614D03*
X555313Y547914D03*
X568549D03*
X562006D03*
X543455Y555914D03*
X571345Y568900D03*
X564966Y568749D03*
X562006Y574799D03*
X555313Y585714D03*
Y574849D03*
X558659Y568749D03*
X568549Y585714D03*
X562006D03*
X568699Y574849D03*
X551966Y568749D03*
X548620Y574849D03*
Y585714D03*
X543481Y574550D03*
X543431Y585700D03*
X543468Y566736D03*
X575166Y547898D03*
X575192Y529150D03*
X575166Y536999D03*
X598817Y547957D03*
X592124Y547914D03*
X595470Y530949D03*
X580242Y547900D03*
X580279Y528936D03*
X580292Y536750D03*
X592124Y537049D03*
X588777Y530949D03*
X598817Y528899D03*
Y537049D03*
X602163Y528899D03*
X585431Y547914D03*
Y537049D03*
X588777Y553614D03*
X595470D03*
X580279Y566736D03*
X585431Y574849D03*
Y585714D03*
X598817Y585757D03*
Y574849D03*
Y566699D03*
X592124Y585714D03*
X595470Y568749D03*
X588777D03*
X592124Y574849D03*
X575142Y555700D03*
X575192Y566950D03*
X575166Y585698D03*
Y574799D03*
X580266Y555914D03*
X580292Y574550D03*
X580242Y585700D03*
X575166Y612599D03*
X585431Y612649D03*
X592124D03*
X598817D03*
X555313D03*
X562006Y612599D03*
X568699Y612649D03*
X548620D03*
X571345Y591414D03*
X558659D03*
X571345Y606700D03*
X558659Y606549D03*
X564966D03*
X551966D03*
Y591414D03*
X543455Y593714D03*
X543468Y604536D03*
X543481Y612350D03*
X580292D03*
X580266Y593714D03*
X595470Y591414D03*
X588777D03*
X598817Y604499D03*
X595470Y606549D03*
X588777D03*
X575192Y604750D03*
X575142Y593500D03*
X602163Y593599D03*
Y604499D03*
X580279Y604536D03*
X620092Y13078D03*
X620192Y31978D03*
Y-5822D03*
X647317Y-1310D03*
X660676Y-2600D03*
X651300Y20000D03*
X659200Y31500D03*
X651300Y17500D03*
X620070Y50878D03*
X620192Y69778D03*
X620092Y88678D03*
X663500Y48000D03*
X663700Y65600D03*
X663476Y45296D03*
X616115Y108339D03*
X622200Y112200D03*
X616167Y118627D03*
X605300Y124600D03*
X630000Y126572D03*
X624500Y129400D03*
X626900Y128300D03*
X633580Y125560D03*
X661700Y142300D03*
X636481Y124951D03*
X635951Y127419D03*
X661053Y115971D03*
X658490Y115432D03*
X650307Y115518D03*
X647809Y116121D03*
X645311Y116724D03*
X650120Y122700D03*
X660900Y123650D03*
Y126650D03*
X647120Y122700D03*
X657900Y126650D03*
Y123650D03*
X651920Y125750D03*
X656111Y121550D03*
X653111D03*
X654558Y115101D03*
X640043Y117728D03*
X639100Y124200D03*
X638800Y126700D03*
X648690Y125590D03*
X643674Y123573D03*
X644950Y125750D03*
X641950D03*
X642899Y117112D03*
X632500Y238500D03*
Y235000D03*
X632692Y248172D03*
X632532Y241717D03*
X630200Y248100D03*
X633308Y263808D03*
X662800Y248600D03*
X643500Y272262D03*
X659900Y256900D03*
Y269200D03*
X652000Y284500D03*
X663200Y298600D03*
X644800Y292150D03*
X654500Y298600D03*
X652100Y288300D03*
X639045Y299555D03*
X639100Y309500D03*
X649000Y339400D03*
X638790Y329500D03*
X639350Y339980D03*
X639100Y319500D03*
X655900Y307700D03*
X656300Y312300D03*
X660700Y307700D03*
X655900Y316500D03*
X656000Y329800D03*
X655900Y320500D03*
X656000Y325100D03*
X660900Y329800D03*
X664100Y348000D03*
X648800D03*
X658900D03*
X662936Y367171D03*
X659936Y364171D03*
X662936D03*
X654000Y348000D03*
X634200Y436800D03*
X637300Y437200D03*
X625430Y490100D03*
X607012Y465997D03*
X623660Y466746D03*
X632113Y496892D03*
X619392Y514700D03*
X656900Y482290D03*
X649600Y492400D03*
X660500Y492000D03*
X652000Y513900D03*
X655000D03*
X661500D03*
X658500D03*
X620192Y532978D03*
X618892Y555800D03*
X618292Y574300D03*
X651750Y584150D03*
X653100Y587000D03*
X618192Y593600D03*
X620033Y608878D03*
X660230Y598170D03*
X674300Y9847D03*
X671800D03*
X669300D03*
X673900Y23100D03*
X671400D03*
X668900D03*
X690000Y15300D03*
X683800Y24856D03*
X670430Y29253D03*
X716858Y-14448D03*
X717720Y23279D03*
X715114Y26395D03*
X704500Y26300D03*
X714337Y7852D03*
Y5352D03*
Y2852D03*
X718555Y-16147D03*
X666500Y48000D03*
X665100Y68600D03*
X668100D03*
X666700Y65600D03*
X678020Y69870D03*
X678300Y92630D03*
Y95130D03*
X675630Y94988D03*
X681300Y95130D03*
Y92630D03*
X684300D03*
X687400Y93900D03*
X673830Y83050D03*
X676430D03*
X676500Y80500D03*
X673900D03*
X674010Y77970D03*
X676610D03*
X692200Y83800D03*
X695000Y67000D03*
X699880Y66840D03*
X724200Y64730D03*
X722460Y69550D03*
X713680Y60910D03*
X700360Y72160D03*
X694910Y72220D03*
X713050Y63650D03*
X710440Y63710D03*
X704880Y66750D03*
X697747Y72184D03*
X723700Y67400D03*
X713620Y58270D03*
X715800Y59490D03*
Y57000D03*
X713590Y53260D03*
X713610Y55730D03*
X700640Y69500D03*
X703120Y69380D03*
X702380Y66840D03*
X697440Y66900D03*
X699800Y89100D03*
X713830Y82730D03*
X692000Y45000D03*
Y48500D03*
X697500D03*
Y45000D03*
X664700Y142800D03*
X675600Y144900D03*
Y150000D03*
X679900Y128200D03*
X682400Y127085D03*
X684900D03*
X673566Y116724D03*
X676494Y116940D03*
X668665Y118185D03*
X671249Y118744D03*
X677896Y119093D03*
X674896D03*
X715505Y155076D03*
X720700Y154750D03*
X725650Y155000D03*
X691583Y200124D03*
X689033D03*
X686533D03*
Y196624D03*
X689033D03*
X691583D03*
X715550Y158880D03*
X705550D03*
X710550D03*
X709200Y198700D03*
X720369Y205199D03*
X716557Y198557D03*
X692513Y213800D03*
X692673Y206200D03*
X692500Y210100D03*
X690861Y211917D03*
Y215717D03*
X692400Y218100D03*
X690861Y204317D03*
Y208117D03*
X706500Y217400D03*
Y214900D03*
X719315Y239104D03*
X669900Y224000D03*
X672500Y224100D03*
X678454Y278000D03*
X675380Y246340D03*
X678000Y246400D03*
X668100Y232200D03*
X667240Y246600D03*
X672530Y246300D03*
X677400Y232300D03*
X674300Y232200D03*
X675200Y224100D03*
X667600Y250200D03*
X688643Y225980D03*
X688388Y231280D03*
X678400Y224100D03*
X690380Y252240D03*
X690939Y266630D03*
X693530Y261240D03*
X690660Y264000D03*
X690704Y271324D03*
X671100Y232200D03*
X701800Y246480D03*
X669750Y246350D03*
X710572Y244773D03*
X719360Y241504D03*
X710627Y242061D03*
X702000Y243900D03*
X722050Y221150D03*
X707653Y226347D03*
X718300Y227400D03*
X700900Y264100D03*
X694361Y223317D03*
Y220817D03*
X690861D03*
Y223317D03*
X672300Y269200D03*
X672200Y256800D03*
X706561Y219917D03*
X719900Y269300D03*
X725500Y279300D03*
X725300Y269400D03*
X719600Y279400D03*
X704175Y287275D03*
X704214Y290775D03*
X680000Y281900D03*
X672150Y288350D03*
X695300Y338100D03*
X695400Y328000D03*
X684100Y338200D03*
X695400Y318000D03*
X695800Y308000D03*
X696088Y297069D03*
X704500Y293800D03*
X707130Y310150D03*
X718200Y295000D03*
X706300Y318400D03*
X678200Y307800D03*
X672700Y307700D03*
X667100D03*
X678100Y324800D03*
X672200Y329800D03*
X678100Y329600D03*
X666900Y329700D03*
X678200Y313700D03*
Y319300D03*
X679000Y348000D03*
X688600Y365100D03*
X671936Y367171D03*
X665936Y370171D03*
X684900Y348000D03*
X674600D03*
X671936Y370171D03*
X665936Y367171D03*
X668936Y370171D03*
Y367171D03*
X665936Y364171D03*
X668936D03*
X669093Y348120D03*
X671936Y373171D03*
X668936D03*
X670300Y375600D03*
X713900Y347800D03*
X698560Y374430D03*
X713900Y342800D03*
Y352800D03*
Y350300D03*
Y345300D03*
X690040Y412030D03*
X685600Y432500D03*
X690600D03*
Y437500D03*
X703876Y414949D03*
X705850Y417093D03*
X710600Y420267D03*
X710423Y417423D03*
X708346Y415859D03*
X708011Y419078D03*
X712980Y417900D03*
X713493Y420449D03*
X723748Y499091D03*
X676900Y489400D03*
X666500Y487600D03*
Y484600D03*
X669500D03*
Y481600D03*
X664610Y512810D03*
X685050Y503970D03*
X704500Y512850D03*
X716267Y522020D03*
X703028Y495600D03*
X709028D03*
X706028D03*
X703028Y492600D03*
X706028D03*
X674200Y588900D03*
X690100Y575860D03*
X689193Y573493D03*
X693126Y581380D03*
X671599Y573493D03*
X671791Y588920D03*
X674099Y573493D03*
X669099D03*
X668891Y588900D03*
X713650Y540750D03*
X715650Y542250D03*
Y545250D03*
X713650Y546750D03*
X708000Y553250D03*
X720200Y551750D03*
X715650Y551250D03*
X696000Y553250D03*
X715650Y548250D03*
X713650Y549750D03*
X723200Y551750D03*
X699000Y553250D03*
X702000D03*
X705000D03*
X713650Y543750D03*
X723200Y554750D03*
X706500Y555750D03*
X703500D03*
X700500D03*
X720200Y554750D03*
X709500Y555750D03*
X712600Y571900D03*
X716300Y569400D03*
X707500Y587800D03*
X691900Y531350D03*
Y534850D03*
X697500Y534750D03*
Y531250D03*
X725173Y598171D03*
X724106Y609550D03*
X721106D03*
X708900Y589850D03*
X706100D03*
X732600Y3600D03*
X755500Y8700D03*
X753600Y-4300D03*
X736715Y33487D03*
X734201Y33510D03*
X726250Y23550D03*
X731457Y8471D03*
X732335Y6000D03*
X786414Y-9650D03*
X779771Y9114D03*
X773228D03*
Y-1801D03*
X779921Y-1751D03*
X776188Y-7851D03*
X769881Y-9901D03*
X782567Y-7700D03*
X786388Y9098D03*
Y-1801D03*
X786414Y28150D03*
X769881Y27899D03*
X782567Y14814D03*
Y30100D03*
X769881Y16839D03*
X776224Y14714D03*
X776188Y29949D03*
X786364Y16900D03*
X736631Y36122D03*
X736655Y38531D03*
X731887Y40916D03*
X734155Y38531D03*
X734131Y36122D03*
X731843Y43571D03*
X756100Y36200D03*
X755500Y46700D03*
X737800Y55800D03*
X751708Y73800D03*
X755500Y84361D03*
X786388Y35999D03*
X786364Y54700D03*
X786388Y46898D03*
X773228Y46914D03*
X779771D03*
X776188Y67749D03*
X769881Y66000D03*
X782567Y67900D03*
Y52614D03*
X769881Y54839D03*
X779921Y35983D03*
X773228D03*
X776224Y52514D03*
X769881Y92500D03*
X773228Y84714D03*
X779771D03*
X776224Y90314D03*
X782567Y90414D03*
X779921Y73849D03*
X773228Y73799D03*
X786414Y65950D03*
X786388Y73799D03*
X786364Y92500D03*
X786388Y84698D03*
X730600Y154984D03*
X746000Y150500D03*
X740718Y150957D03*
X769100Y102900D03*
X758400Y156200D03*
X747600Y161450D03*
X740650Y164800D03*
X735600Y164900D03*
X740650Y158800D03*
X754726Y205037D03*
X752226D03*
X749726D03*
X754726Y207537D03*
X752226D03*
X749726D03*
X742937Y218574D03*
X758400Y159200D03*
X774582Y212033D03*
X770200Y208600D03*
X775171Y218616D03*
X787371Y215216D03*
Y217716D03*
X777700Y218600D03*
X727969Y236770D03*
X736612Y237908D03*
X727997Y239195D03*
X736625Y240308D03*
X742897Y229573D03*
X746303Y243122D03*
X746321Y240569D03*
X760304Y235827D03*
X768560Y244055D03*
X769019Y276400D03*
X762616Y270113D03*
X761480Y242720D03*
X731100Y269300D03*
Y279300D03*
X787371Y247216D03*
Y249716D03*
X775232Y221133D03*
X777700Y250600D03*
X775232Y223633D03*
X775171Y250616D03*
X775232Y253133D03*
Y255633D03*
X787371Y279216D03*
X774347Y339983D03*
X762760Y339500D03*
X727300Y302910D03*
X727474Y338363D03*
Y335363D03*
X732474D03*
Y338363D03*
X756114Y316209D03*
X729974Y338363D03*
Y335363D03*
X771278Y307918D03*
X762842Y302434D03*
X765730Y335064D03*
X777700Y282600D03*
X775232Y287633D03*
Y285133D03*
X775171Y282616D03*
X787371Y281716D03*
Y311216D03*
X777800Y314700D03*
X775171Y314616D03*
X787371Y313716D03*
X775232Y317133D03*
Y319633D03*
X727474Y344663D03*
Y367463D03*
X732474D03*
X729974D03*
X727474Y364863D03*
X732474D03*
X729974D03*
Y347663D03*
X727474D03*
X732474D03*
Y344663D03*
X727574Y373463D03*
X732574D03*
X730074D03*
X732574Y376063D03*
X730074D03*
X729974Y344663D03*
X731100Y362300D03*
X772443Y371976D03*
X760140Y362819D03*
X758952Y384100D03*
X763333Y400212D03*
X772300Y403520D03*
X775171Y346616D03*
X787371Y343216D03*
Y345716D03*
X775232Y349133D03*
X777600Y346600D03*
X775232Y351633D03*
X787321Y374916D03*
Y377316D03*
X775182Y383633D03*
Y381133D03*
X778000Y378700D03*
X775121Y378616D03*
X749640Y431797D03*
X728940Y457806D03*
X775417Y435799D03*
X777979Y436516D03*
X752496Y515974D03*
X732522Y526808D03*
Y524308D03*
X750518Y522108D03*
X734922Y526808D03*
X776224Y515714D03*
X779771Y510114D03*
X773228D03*
X769881Y517900D03*
X782567Y515814D03*
X786388Y510098D03*
X786364Y517900D03*
X732442Y529300D03*
X734842D03*
X736300Y541500D03*
X756000Y537000D03*
X737400Y529400D03*
X734900Y531800D03*
X732400D03*
X726200Y551750D03*
X754910Y556400D03*
X726200Y554750D03*
X727400Y571300D03*
X755000Y574800D03*
X752500Y585150D03*
X727106Y586550D03*
X773228Y536999D03*
X763677Y547783D03*
X776188Y530949D03*
X782567Y531100D03*
X769818Y529200D03*
X779921Y537049D03*
X782567Y553614D03*
X773228Y547914D03*
X779771D03*
X776224Y553514D03*
X786388Y536999D03*
X786414Y529150D03*
X786388Y547898D03*
X786364Y555700D03*
X769881D03*
X773228Y574799D03*
X782567Y568900D03*
X769700Y566900D03*
X776188Y568749D03*
X779921Y574849D03*
X773228Y585714D03*
X779771D03*
X786388Y574799D03*
Y585698D03*
X786414Y566950D03*
X779921Y612649D03*
X773228Y612599D03*
X786388D03*
X755000Y614500D03*
X727000Y606600D03*
X766600Y590700D03*
X769700Y604900D03*
X776188Y606549D03*
X782567Y606700D03*
Y591414D03*
X776224Y591314D03*
X786414Y604750D03*
X786364Y593500D03*
X803346Y-1751D03*
X810039Y-1801D03*
X791514Y-2050D03*
X791501Y-9864D03*
X812999Y-7851D03*
X806692D03*
X799999D03*
X816582Y9114D03*
X796653D03*
X791464Y9100D03*
X810039Y9114D03*
X803346D03*
X816732Y-1751D03*
X796653D03*
X799999Y29949D03*
X806692D03*
X812999D03*
X791501Y27936D03*
X791488Y17114D03*
X799999Y14814D03*
X813035Y14714D03*
X806692Y14814D03*
X828275Y9100D03*
X833464Y9114D03*
X840157D03*
X819378Y-7700D03*
X823199Y9098D03*
Y-1801D03*
X823225Y-9650D03*
X828312Y-9864D03*
X843503Y-7851D03*
X836810D03*
X846850Y-1801D03*
X828325Y-2050D03*
X833464Y-1751D03*
X840157D03*
X846850Y9114D03*
X819378Y14814D03*
Y30100D03*
X843503Y14814D03*
X823175Y16900D03*
X823225Y28150D03*
X828312Y27936D03*
X836810Y29949D03*
X828299Y17114D03*
X836810Y14814D03*
X843503Y29949D03*
X791488Y54914D03*
X799999Y52614D03*
X796653Y46914D03*
X791464Y46900D03*
X810039Y35999D03*
X803346Y36049D03*
X799999Y90414D03*
X791488Y92714D03*
X806692Y90414D03*
X816582Y46914D03*
X816732Y36049D03*
X799999Y67749D03*
X812999D03*
X806692D03*
X791501Y65736D03*
X803346Y46914D03*
X806692Y52614D03*
X813035Y52514D03*
X810039Y46914D03*
X791514Y35750D03*
X796653Y36049D03*
X816582Y73849D03*
X791514Y73550D03*
X796653Y73849D03*
X810039Y73799D03*
X803346Y73849D03*
X816582Y84714D03*
X813035Y90314D03*
X803346Y84714D03*
X810039D03*
X796653D03*
X791464Y84700D03*
X819378Y67900D03*
Y52614D03*
X846850Y35999D03*
X833464Y36049D03*
X840157D03*
X823225Y65950D03*
X823175Y54700D03*
X823199Y46898D03*
Y35999D03*
X828299Y54914D03*
X828275Y46900D03*
X828325Y35750D03*
X833464Y46914D03*
X836810Y52614D03*
X840157Y46914D03*
X828312Y65736D03*
X836810Y67749D03*
X843503D03*
X846850Y46914D03*
X843503Y52614D03*
X823175Y92500D03*
X823199Y84698D03*
X846850Y73799D03*
X843503Y90414D03*
X846850Y84714D03*
X828325Y73550D03*
X840157Y73849D03*
X833464D03*
X828299Y92714D03*
X836810Y90414D03*
X840157Y84714D03*
X833464D03*
X828275Y84700D03*
X819378Y90364D03*
X823199Y73799D03*
X790871Y215216D03*
Y217716D03*
X845100Y268200D03*
X847600D03*
X842600D03*
X847600Y243400D03*
X841400Y243300D03*
X847600Y238400D03*
X841400Y238300D03*
X847600Y240900D03*
X841400Y240800D03*
X789500Y231800D03*
X790900Y234000D03*
Y229700D03*
X790846Y225774D03*
X790882Y221723D03*
X790871Y247216D03*
Y249716D03*
X789471Y227742D03*
X789576Y223737D03*
X789554Y219723D03*
X790900Y253900D03*
X789432Y252000D03*
X790871Y266216D03*
X789432Y255800D03*
X790867Y257724D03*
X789432Y259800D03*
X789500Y263900D03*
X790885Y261711D03*
X790871Y279216D03*
X842600Y299900D03*
X845100D03*
X847600D03*
X845100Y331500D03*
X842600D03*
X847600D03*
X790871Y311216D03*
X789432Y284200D03*
Y288300D03*
Y292400D03*
X789400Y296200D03*
X790871Y298216D03*
X790937Y294270D03*
X790900Y290300D03*
Y286200D03*
X790871Y281716D03*
Y313716D03*
X789432Y319900D03*
Y323900D03*
X790900Y322000D03*
Y326000D03*
X790871Y330216D03*
X789500Y328000D03*
X789478Y315671D03*
X790800Y317700D03*
X847600Y363000D03*
X845100D03*
X842600D03*
X847577Y381842D03*
X789432Y348100D03*
Y352100D03*
X789597Y356105D03*
X789500Y360200D03*
X790900Y358200D03*
X790835Y354048D03*
X790867Y350024D03*
X790871Y345716D03*
Y343216D03*
Y362216D03*
X790821Y374916D03*
X790900Y389300D03*
X789500Y391300D03*
X790900Y393400D03*
Y381100D03*
X789582Y383200D03*
X790900Y385300D03*
X789500Y387300D03*
X790821Y377316D03*
X789282Y379200D03*
X816582Y510114D03*
X806692Y515814D03*
X813035Y515714D03*
X810039Y510114D03*
X791488Y518114D03*
X791464Y510100D03*
X799999Y515814D03*
X796653Y510114D03*
X803346D03*
X819378Y515764D03*
X843503Y515814D03*
X846850Y510114D03*
X823175Y517900D03*
X823199Y510098D03*
X828299Y518114D03*
X840157Y510114D03*
X833464D03*
X836810Y515814D03*
X816582Y537049D03*
Y547914D03*
X810039Y536999D03*
X806692Y530949D03*
X812999D03*
X803346Y537049D03*
X796653D03*
X799999Y530949D03*
X791501Y528936D03*
X791514Y536750D03*
X799999Y553614D03*
X810039Y547914D03*
X796653D03*
X803346D03*
X791464Y547900D03*
X806692Y553614D03*
X813035Y553514D03*
X791488Y555914D03*
X810039Y585714D03*
X806692Y568749D03*
X810039Y574799D03*
X812999Y568749D03*
X803346Y585714D03*
X796653D03*
X791514Y574550D03*
X791464Y585700D03*
X799999Y568749D03*
X796653Y574849D03*
X803346D03*
X791501Y566736D03*
X816582Y585714D03*
Y574849D03*
X819378Y553564D03*
Y531100D03*
X836810Y530949D03*
X833464Y537049D03*
X846850Y547914D03*
X833464D03*
X840157D03*
X828275Y547900D03*
X843503Y553614D03*
X836810D03*
X846850Y536999D03*
X843503Y530949D03*
X823199Y547898D03*
Y536999D03*
X823225Y529150D03*
X828325Y536750D03*
X840157Y537049D03*
X828312Y528936D03*
X819378Y568900D03*
X823175Y555700D03*
X828299Y555914D03*
X828275Y585700D03*
X823225Y566950D03*
X823199Y585698D03*
Y574799D03*
X828312Y566736D03*
X840157Y585714D03*
X833464D03*
X828325Y574550D03*
X840157Y574849D03*
X833464D03*
X836810Y568749D03*
X846850Y585714D03*
Y574799D03*
X843503Y568749D03*
X846850Y612599D03*
X840157Y612649D03*
X833464D03*
X823199Y612599D03*
X810039D03*
X803346Y612649D03*
X796653D03*
X816582D03*
X791514Y612350D03*
X806692Y606549D03*
X812999D03*
X799999D03*
X791501Y604536D03*
X806692Y591414D03*
X813035Y591314D03*
X799999Y591414D03*
X791488Y593714D03*
X819378Y606700D03*
Y591364D03*
X823225Y604750D03*
X823175Y593500D03*
X843503Y591414D03*
X828312Y604536D03*
X843503Y606549D03*
X836810D03*
X828325Y612350D03*
X836810Y591414D03*
X828299Y593714D03*
X870275Y9114D03*
X865086Y9100D03*
X860010Y9098D03*
X876968Y9114D03*
Y-1751D03*
X873621Y-7851D03*
X865123Y-9864D03*
X860036Y-9650D03*
X849810Y-7851D03*
X856189Y-7700D03*
X860010Y-1801D03*
X865136Y-2050D03*
X853543Y-1751D03*
X870275D03*
X853393Y9114D03*
X860036Y28150D03*
X859986Y16900D03*
X865110Y17114D03*
X856189Y14814D03*
X849846Y14714D03*
X873621Y14814D03*
Y29949D03*
X865123Y27936D03*
X849810Y29949D03*
X856189Y30100D03*
X896847Y-9650D03*
X910432Y-7851D03*
X883661Y-1801D03*
X880314Y-7851D03*
X886621D03*
X907086Y-1751D03*
X890354D03*
X896821Y-1801D03*
X901947Y-2050D03*
X901934Y-9864D03*
X893000Y-7700D03*
X883661Y9114D03*
X907086D03*
X896821Y9098D03*
X901897Y9100D03*
X890204Y9114D03*
X910432Y29949D03*
X896797Y16900D03*
X893000Y14814D03*
X901921Y17114D03*
X901934Y27936D03*
X893000Y30100D03*
X880314Y14814D03*
X886657Y14714D03*
X886621Y29949D03*
X880314D03*
X896847Y28150D03*
X910432Y14814D03*
X859986Y54700D03*
X870275Y36049D03*
X865136Y35750D03*
X865086Y46900D03*
X876968Y46914D03*
Y36049D03*
X873621Y67749D03*
Y52614D03*
X860010Y46898D03*
X860036Y65950D03*
X865123Y65736D03*
X849810Y67749D03*
X856189Y67900D03*
X853393Y46914D03*
X870275D03*
X865110Y54914D03*
X860010Y35999D03*
X856189Y52614D03*
X853543Y36049D03*
X849846Y52514D03*
X876968Y84714D03*
Y73849D03*
X873621Y90414D03*
X870275Y73849D03*
X853543D03*
X860010Y73799D03*
X849846Y90314D03*
X856189Y90414D03*
X865110Y92714D03*
X870275Y84714D03*
X865086Y84700D03*
X853393Y84714D03*
X860010Y84698D03*
X859986Y92500D03*
X865136Y73550D03*
X910432Y67749D03*
X893000Y67900D03*
X901934Y65736D03*
X896847Y65950D03*
X910432Y52614D03*
X890204Y46914D03*
X896821Y35999D03*
X901921Y54914D03*
X896797Y54700D03*
X883661Y35999D03*
X886621Y67749D03*
X880314D03*
X883661Y46914D03*
X880314Y52614D03*
X886657Y52514D03*
X901947Y35750D03*
X901897Y46900D03*
X896821Y46898D03*
X893000Y52614D03*
X890354Y36049D03*
X907086D03*
X883661Y73799D03*
X910432Y90414D03*
X907086Y84714D03*
X901897Y84700D03*
X907086Y46914D03*
X896821Y84698D03*
X893000Y90414D03*
X890204Y84714D03*
X896797Y92500D03*
X901921Y92714D03*
X890354Y73849D03*
X896821Y73799D03*
X901947Y73550D03*
X907086Y73849D03*
X883661Y84714D03*
X886657Y90314D03*
X880314Y90414D03*
X886657Y109884D03*
X907086Y104284D03*
X901934Y105051D03*
X896847Y105265D03*
X890204Y104284D03*
X893000Y109534D03*
X896821Y113114D03*
X901947Y112865D03*
X910432Y109984D03*
X883661Y104284D03*
X873621Y515814D03*
X876968Y510114D03*
X870275D03*
X859986Y517900D03*
X865086Y510100D03*
X860010Y510098D03*
X865110Y518114D03*
X853393Y510114D03*
X856189Y515814D03*
X849846Y515714D03*
X907000Y495800D03*
X882900Y495900D03*
X893000Y493094D03*
X886500Y493400D03*
X910432Y491044D03*
X901921Y490514D03*
X896785D03*
X901921Y498514D03*
X896785D03*
X889100Y498500D03*
X901897Y510100D03*
X893000Y515814D03*
X890204Y510114D03*
X896821Y510098D03*
X901921Y518114D03*
X896797Y517900D03*
X880314Y515814D03*
X886657Y515714D03*
X883661Y510114D03*
X910432Y515814D03*
X907086Y510114D03*
X860010Y536999D03*
X865123Y528936D03*
X873621Y530949D03*
Y553614D03*
X876968Y537049D03*
Y547914D03*
X860010Y547898D03*
X870275Y547914D03*
X853393D03*
X865086Y547900D03*
X856189Y553614D03*
X849846Y553514D03*
X870275Y537049D03*
X853543D03*
X856189Y531100D03*
X849810Y530949D03*
X865136Y536750D03*
X860036Y529150D03*
X849810Y568749D03*
X865086Y585700D03*
X860010Y585698D03*
X865136Y574550D03*
X859986Y555700D03*
X865110Y555914D03*
X860010Y574799D03*
X853393Y585714D03*
X870275D03*
X873621Y568749D03*
X876968Y574849D03*
Y585714D03*
X860036Y566950D03*
X865123Y566736D03*
X870275Y574849D03*
X853543D03*
X856189Y568900D03*
X890354Y537049D03*
X893000Y531100D03*
X896821Y536999D03*
X901934Y528936D03*
X901947Y536750D03*
X910432Y530949D03*
X907086Y537049D03*
X886621Y530949D03*
X883661Y536999D03*
X880314Y530949D03*
Y553614D03*
X886657Y553514D03*
X883661Y547914D03*
X893000Y553614D03*
X910432D03*
X890204Y547914D03*
X896821Y547898D03*
X901897Y547900D03*
X907086Y547914D03*
X880314Y568749D03*
X886621D03*
X883661Y574799D03*
Y585714D03*
X901921Y555914D03*
X896797Y555700D03*
X901934Y566736D03*
X896847Y566950D03*
X901897Y585700D03*
X890354Y574849D03*
X896821Y574799D03*
X893000Y568900D03*
X901947Y574550D03*
X896821Y585698D03*
X890204Y585714D03*
X910432Y568749D03*
X907086Y574849D03*
Y585714D03*
X890354Y612649D03*
X896821Y612599D03*
X883661D03*
X907086Y612649D03*
X870275D03*
X876968D03*
X860010Y612599D03*
X853543Y612649D03*
X859986Y593500D03*
X865110Y593714D03*
X856189Y591414D03*
X849846Y591314D03*
X860036Y604750D03*
X865123Y604536D03*
X856189Y606700D03*
X849810Y606549D03*
X865136Y612350D03*
X873621Y606549D03*
Y591414D03*
X886657Y591314D03*
X896847Y604750D03*
X901934Y604536D03*
X901947Y612350D03*
X896797Y593500D03*
X901921Y593714D03*
X893000Y591414D03*
X910432D03*
Y606549D03*
X893000Y606700D03*
X880314Y606549D03*
X886621D03*
X880314Y591414D03*
X923432Y-7851D03*
X929811Y-7700D03*
X933658Y-9650D03*
X917125Y-7851D03*
X913779Y-1751D03*
X933632Y-1801D03*
X927165Y-1751D03*
X920472Y-1801D03*
X927015Y9114D03*
X933632Y9098D03*
X913779Y9114D03*
X920472D03*
X923432Y29949D03*
X917125D03*
Y14814D03*
X929811D03*
X933608Y16900D03*
X923468Y14714D03*
X933658Y28150D03*
X929811Y30100D03*
X938745Y-9864D03*
X938758Y-2050D03*
X938708Y9100D03*
X947243Y-7851D03*
X950590Y-1751D03*
X957283Y-1843D03*
X953936Y-7851D03*
X943897Y-1751D03*
Y9114D03*
X950590D03*
X960629Y-9786D03*
X963976Y-1843D03*
X970669Y-1743D03*
X967322Y-9786D03*
X963976Y9114D03*
X970669D03*
X967322Y28014D03*
X960629Y17057D03*
Y28014D03*
X967322Y17057D03*
X938745Y27936D03*
X938732Y17114D03*
X957283Y9300D03*
X953936Y14814D03*
Y29949D03*
X957600Y13200D03*
X957700Y32100D03*
X947243Y29949D03*
Y14814D03*
X933658Y65950D03*
X923432Y67749D03*
X929811Y67900D03*
X917125Y67749D03*
X920472Y35999D03*
X917125Y52614D03*
X913779Y46914D03*
Y36049D03*
X927015Y73849D03*
X913779D03*
X920472Y73799D03*
X933632D03*
X913779Y84714D03*
X920472D03*
X933608Y92500D03*
X920472Y46914D03*
X933632Y35999D03*
X927165Y36049D03*
X927015Y46914D03*
X933608Y54700D03*
X933632Y46898D03*
X929811Y52614D03*
X933632Y84698D03*
X927015Y84714D03*
X923468Y90314D03*
X929811Y90414D03*
X917125D03*
X953936Y52614D03*
X957558Y50729D03*
X967322Y65814D03*
X960629D03*
X970669Y35957D03*
Y46914D03*
X967322Y54857D03*
X963976Y35957D03*
Y46914D03*
X960629Y54857D03*
X938758Y35750D03*
X938708Y46900D03*
X938732Y54914D03*
X938745Y65736D03*
X950590Y36049D03*
X953936Y67749D03*
X950590Y46914D03*
X947243Y67749D03*
X943897Y36049D03*
Y46914D03*
X947243Y52614D03*
X957283Y35957D03*
X963976Y73757D03*
X960629Y89964D03*
X963976Y87392D03*
X967322Y89964D03*
X970669Y87392D03*
Y73757D03*
X938708Y84700D03*
X938732Y92714D03*
X938758Y73550D03*
X957600Y70400D03*
X943897Y84714D03*
X947243Y90414D03*
X943897Y73849D03*
X950590D03*
X953886Y90414D03*
X950590Y84714D03*
X957774Y87394D03*
X957200Y73800D03*
X933658Y105265D03*
X929811Y109534D03*
X933632Y113114D03*
X923468Y109884D03*
X917125Y109984D03*
X920472Y104284D03*
X913779D03*
X927015D03*
X963245Y105725D03*
X938758Y112865D03*
X938745Y105051D03*
X947250Y107700D03*
X950600Y112300D03*
X953800Y105000D03*
X927607Y203260D03*
Y207159D03*
X934367D03*
Y199360D03*
X930987Y201309D03*
X934367Y214960D03*
X930987Y213009D03*
X920847Y211060D03*
X927607Y214960D03*
Y211060D03*
X937747Y216909D03*
X924227D03*
Y213009D03*
X968166Y218860D03*
X951256Y194841D03*
X958026Y201309D03*
X967036Y193507D03*
X947887Y203260D03*
Y207159D03*
X944507Y213009D03*
Y201309D03*
X947887Y199360D03*
X941127D03*
Y207159D03*
X947887Y211060D03*
Y218860D03*
X941127D03*
Y214960D03*
X962526Y205210D03*
X961406Y214960D03*
Y211060D03*
Y218860D03*
X951267Y209109D03*
X958026Y213009D03*
X954647Y211060D03*
Y218860D03*
X964786Y213009D03*
Y216909D03*
Y209109D03*
X934367Y226660D03*
X924227Y236409D03*
X920847Y238360D03*
X913787Y226660D03*
X913700Y222710D03*
X913787Y238360D03*
X924227Y232509D03*
X927607Y230559D03*
Y234460D03*
X930987Y232509D03*
X934367Y234460D03*
X924227Y228610D03*
X930987Y220809D03*
X924227Y224709D03*
X937747Y232509D03*
Y236409D03*
X924227Y240309D03*
X917467D03*
X930987D03*
X924227Y248109D03*
Y244209D03*
X917467D03*
X913787Y250060D03*
X934367Y246160D03*
X927607Y250060D03*
X924227Y220809D03*
X913787Y253960D03*
X927607D03*
X934367D03*
X937747Y252009D03*
X930987D03*
X924227D03*
X917467D03*
Y259809D03*
X924227D03*
X930987D03*
X920847Y265660D03*
X930987Y275409D03*
X937747D03*
Y271509D03*
Y255909D03*
X934367Y277360D03*
X930987Y271509D03*
X934367Y273460D03*
X927607Y269560D03*
X917467Y263709D03*
X913787Y265660D03*
X924227Y267609D03*
X934367Y265660D03*
X924227Y263709D03*
Y275409D03*
X927607Y277360D03*
X920847Y273460D03*
Y269560D03*
X924227Y255909D03*
X951267Y248109D03*
X958026Y244209D03*
X968166Y242260D03*
X944507Y228610D03*
Y224709D03*
Y244209D03*
Y248109D03*
X941127Y242260D03*
Y250060D03*
Y246160D03*
X947887D03*
X941127Y222760D03*
X947887Y226660D03*
Y234460D03*
X941127Y238360D03*
Y234460D03*
Y230559D03*
Y226660D03*
X971546Y248109D03*
X968166Y246160D03*
X951267Y240309D03*
X958026D03*
X964786D03*
X954647Y246160D03*
Y250060D03*
X958026Y228610D03*
Y236409D03*
X961406Y238360D03*
X951267Y228610D03*
X954647Y226660D03*
X958026Y224709D03*
Y232509D03*
X954647Y230559D03*
X961406Y222760D03*
X968166Y226660D03*
X971546Y236409D03*
X968166Y238360D03*
X971546Y220809D03*
X964786Y232509D03*
Y220809D03*
X947887Y253960D03*
X941127D03*
X958026Y252009D03*
X968166Y277360D03*
X951267Y275409D03*
X961406Y277360D03*
X958026Y263709D03*
X968166Y269560D03*
X961406Y261760D03*
X958026Y255909D03*
X951267Y259809D03*
X958026D03*
X954647Y277360D03*
Y265660D03*
X951267Y267609D03*
X954647Y273460D03*
X958026Y275409D03*
X954647Y269560D03*
X961406D03*
X971546Y275409D03*
Y263709D03*
X941127Y277360D03*
Y265660D03*
X944507Y275409D03*
Y263709D03*
X941127Y269560D03*
Y257860D03*
Y261760D03*
X947887Y277360D03*
Y265660D03*
X971546Y259809D03*
Y255909D03*
X964786Y279310D03*
X934367Y285160D03*
Y300760D03*
X927607D03*
Y308560D03*
X934367D03*
X927607Y285160D03*
Y292959D03*
X934367D03*
X937747Y318309D03*
Y341709D03*
Y326110D03*
X917467Y333909D03*
Y341709D03*
X913787Y339760D03*
X924227Y333909D03*
Y337809D03*
Y341709D03*
X913787Y328060D03*
X924227Y330009D03*
X920847Y328060D03*
X917467Y330009D03*
X930987Y326110D03*
X934367Y331960D03*
X927607Y328060D03*
X934367Y324160D03*
X924227Y322209D03*
X927607Y320260D03*
X930987Y318309D03*
X934367Y316360D03*
X927607D03*
X930987Y337809D03*
X924227Y326110D03*
X961406Y292959D03*
Y285160D03*
X954647Y292959D03*
Y285160D03*
X968166Y292959D03*
Y300760D03*
X971546Y310509D03*
X964786D03*
X954647Y308560D03*
X961406D03*
X954647Y300760D03*
X961406D03*
X964786Y283209D03*
X971546D03*
X947887Y308560D03*
X941127D03*
Y300760D03*
X947887D03*
X941127Y285160D03*
Y292959D03*
X947887D03*
Y285160D03*
X968166Y281260D03*
X958026Y333909D03*
Y337809D03*
Y341709D03*
Y318309D03*
X951267D03*
X954647Y316360D03*
X961406D03*
Y324160D03*
X971546Y337809D03*
X964786Y330009D03*
X971546D03*
X951267D03*
X958026D03*
X968166Y312460D03*
X964786Y314409D03*
X951267Y337809D03*
X954647Y331960D03*
Y328060D03*
X971546Y322209D03*
X968166Y320260D03*
X964786Y322209D03*
X958026Y326110D03*
X947887Y316360D03*
X941127D03*
X944507Y322209D03*
Y318309D03*
X947887Y331960D03*
Y328060D03*
X941127Y331960D03*
Y328060D03*
Y339760D03*
Y335860D03*
X944507Y333909D03*
X937747Y365109D03*
Y345609D03*
Y361209D03*
X924227Y365109D03*
X930987D03*
X927607Y367060D03*
X934367Y370959D03*
Y363160D03*
X927607D03*
X924227Y369010D03*
X913787Y343660D03*
X934367D03*
X927607D03*
Y347560D03*
X934367Y351460D03*
X930987Y357309D03*
Y345609D03*
X917467Y353409D03*
Y349509D03*
X913787Y355360D03*
X924227Y349509D03*
Y345609D03*
Y353409D03*
Y361209D03*
Y357309D03*
X920847Y355360D03*
X917167Y361209D03*
Y369010D03*
X934367Y382660D03*
X930987Y384609D03*
Y376809D03*
X934367Y390460D03*
X927607Y386560D03*
Y390460D03*
X930987Y396309D03*
X934367Y398260D03*
X927607Y394359D03*
X917467Y388509D03*
X924227Y392410D03*
X920847Y390460D03*
X924227Y372909D03*
X937747Y400209D03*
X917100Y380709D03*
X937747D03*
X924227D03*
X920847Y382660D03*
X924227Y376809D03*
X927607Y382660D03*
X968166Y370959D03*
X958026Y361209D03*
X954647Y347560D03*
X961406Y359260D03*
X958026Y357309D03*
X951267D03*
X941127Y355360D03*
Y347560D03*
Y351460D03*
X958026Y345609D03*
X951267Y349509D03*
X954647Y351460D03*
X958026Y353409D03*
X968166Y355360D03*
Y351460D03*
X964786Y357309D03*
X971546Y361209D03*
X968166Y359260D03*
X958026Y365109D03*
X964786D03*
X954647Y370959D03*
Y367060D03*
X958026Y369010D03*
X951267D03*
X971546Y349509D03*
X947887Y363160D03*
X941127D03*
X947887Y370959D03*
X941127D03*
Y367060D03*
X944507Y369010D03*
X947887Y343660D03*
X941127Y359260D03*
X944507Y349509D03*
Y353409D03*
X941127Y343660D03*
X947887Y351460D03*
X958026Y372909D03*
X941127Y374860D03*
X961406D03*
X944507Y372909D03*
X941127Y382660D03*
Y378760D03*
X947887D03*
X944507Y384609D03*
X947887Y390460D03*
Y386560D03*
X941127Y390460D03*
X947887Y398260D03*
X941127D03*
X944507Y396309D03*
X947887Y394359D03*
X964786Y376809D03*
X971546D03*
X968166Y378760D03*
Y386560D03*
X964786Y392410D03*
X968166Y390460D03*
Y394359D03*
X964786Y388509D03*
X961406Y378760D03*
X954647D03*
X958026Y384609D03*
X961406Y382660D03*
X951267Y388509D03*
X958026D03*
X954647Y394359D03*
X961406Y386560D03*
X952216Y402421D03*
X970416Y401941D03*
X971546Y380709D03*
X968166Y382660D03*
X920700Y495944D03*
X913800Y495800D03*
X927165Y495944D03*
X929811Y515814D03*
X933632Y510098D03*
X923600Y491144D03*
X917192Y491219D03*
X933632Y490644D03*
X929811D03*
X933632Y498644D03*
X933608Y517900D03*
X913779Y510114D03*
X917125Y515814D03*
X923468Y515714D03*
X920472Y510114D03*
X927015D03*
X938732Y490644D03*
X950700Y490700D03*
X943897Y490444D03*
X970669Y512792D03*
X967322Y515364D03*
X963976Y512792D03*
X960629Y515364D03*
X938708Y510100D03*
X938732Y518114D03*
Y498644D03*
X954000Y497300D03*
X953886Y515814D03*
X950590Y510114D03*
X943897D03*
X947243Y515814D03*
X947443Y497644D03*
X957774Y512794D03*
X961309Y499136D03*
X933632Y536999D03*
X929811Y531100D03*
X933658Y529150D03*
X913779Y537049D03*
X917125Y530949D03*
X927015Y537049D03*
X923432Y530949D03*
X920472Y536999D03*
X923468Y553514D03*
X917125Y553614D03*
X913779Y547914D03*
X927015D03*
X920472D03*
X933632Y547898D03*
X929811Y553614D03*
X933608Y555700D03*
X933632Y585698D03*
X933658Y566950D03*
X929811Y568900D03*
X933632Y574799D03*
X920472D03*
X927015Y585714D03*
X920472D03*
X913779Y574849D03*
X917125Y568749D03*
X913779Y585714D03*
X923432Y568749D03*
X927015Y574849D03*
X960629Y529014D03*
X963976Y536957D03*
X970669D03*
X967322Y529014D03*
X963976Y547914D03*
X970669D03*
X938745Y528936D03*
X938758Y536750D03*
X938708Y547900D03*
X957600Y533100D03*
X957701Y552000D03*
X950590Y537049D03*
X957283Y536957D03*
X953936Y530949D03*
X957283Y548200D03*
X953886Y553614D03*
X950590Y547914D03*
X947243Y530949D03*
X943897Y537049D03*
Y547914D03*
X947243Y553614D03*
X967322Y555857D03*
X960629D03*
X970669Y585714D03*
Y574757D03*
X960629Y566814D03*
X963976Y585714D03*
Y574757D03*
X967322Y566814D03*
X938732Y555914D03*
X938745Y566736D03*
X938758Y574550D03*
X938708Y585700D03*
X957600Y570900D03*
X950590Y574849D03*
Y585714D03*
X957283Y574757D03*
X957456Y588334D03*
X953936Y568749D03*
X943897Y574849D03*
X947243Y568749D03*
X943897Y585714D03*
X933632Y612599D03*
X923432Y606549D03*
X917125D03*
X933658Y604750D03*
X923468Y591314D03*
X917125Y591414D03*
X933608Y593500D03*
X929811Y591414D03*
X927015Y612449D03*
X920472Y612399D03*
X913779Y612449D03*
X929811Y606700D03*
X967322Y593657D03*
X963976Y612457D03*
X970669D03*
X960629Y604614D03*
X967322D03*
X960629Y593657D03*
X938758Y612350D03*
X938745Y604536D03*
X938732Y593714D03*
X957500Y591000D03*
X953936Y606549D03*
X957283Y611600D03*
X950590Y612249D03*
X953886Y591414D03*
X947243Y606549D03*
X943897Y612249D03*
X947243Y591414D03*
X980708Y-4536D03*
X987401Y-9901D03*
X997441Y-7108D03*
X990748Y-1743D03*
X977362Y-7108D03*
X980708Y9114D03*
X990748Y9122D03*
X977362Y28014D03*
X987401D03*
Y17057D03*
X977362D03*
X997441Y28022D03*
Y17057D03*
X1030407Y-8938D03*
X1000787Y-4536D03*
Y9122D03*
X1017519Y-1858D03*
Y-9786D03*
X1007480Y-1858D03*
X1007280Y9114D03*
X1017519D03*
X1007480Y-9786D03*
Y17014D03*
Y28014D03*
X1017519D03*
Y17042D03*
X987401Y65814D03*
X977362D03*
X987401Y54857D03*
X977362D03*
X990748Y46922D03*
Y35957D03*
X980708D03*
Y46914D03*
X997441Y65822D03*
Y54857D03*
Y92757D03*
X990748Y73757D03*
Y87392D03*
X977362Y92757D03*
X987401Y89964D03*
X980708Y84714D03*
Y73757D03*
X1000787Y35957D03*
Y46922D03*
X1017519Y54842D03*
X1007480Y46914D03*
X1008226Y54842D03*
X1008217Y35942D03*
X1007480Y65736D03*
X1016600Y65950D03*
X1017519Y35942D03*
Y46914D03*
X1017919Y92500D03*
X1017519Y87500D03*
X1000787Y84599D03*
Y73757D03*
X1007480Y87500D03*
X1007573Y92500D03*
X1008099Y73479D03*
X1017350Y73450D03*
X976200Y105600D03*
X983936Y199108D03*
X973808Y201308D03*
X995206Y203260D03*
Y214960D03*
X981686Y218860D03*
X974926Y211060D03*
X985066Y216909D03*
X988446Y211058D03*
X979426Y214958D03*
X1001965Y214960D03*
X1027875Y193507D03*
X1032385Y201309D03*
X1015485Y203260D03*
Y214960D03*
X1022245D03*
X1012105Y205210D03*
X1025625Y205211D03*
X1029005Y214960D03*
X1007595Y193507D03*
X1005345Y205210D03*
X1008725Y214960D03*
X988446Y234460D03*
X985066Y248109D03*
X981686Y250060D03*
X974926D03*
X988446Y246160D03*
X981686Y242260D03*
X974926D03*
X988446D03*
X998586Y244209D03*
Y232509D03*
X995206Y226660D03*
X988446Y238360D03*
X985066Y236409D03*
X981686Y234460D03*
X974926Y226660D03*
X991826Y220809D03*
X974926Y230559D03*
Y234460D03*
Y222760D03*
X985066Y224709D03*
X978306Y232509D03*
Y220809D03*
X974926Y253960D03*
X988446D03*
X978306Y252009D03*
X985066D03*
X974926Y265660D03*
X991826Y259809D03*
X985066D03*
X981686Y269560D03*
X995206D03*
X985066Y267609D03*
X991826Y263709D03*
X988446Y265660D03*
X998586Y263709D03*
X991826Y271509D03*
X995206Y273460D03*
X991826Y279310D03*
Y275409D03*
X974926Y269560D03*
X978306Y267609D03*
Y259809D03*
X991826Y255909D03*
X995206Y265660D03*
X991826Y267609D03*
X974926Y273460D03*
X1032385Y232509D03*
X1018865Y244209D03*
X1012105D03*
X1018865Y232509D03*
X1015485Y226660D03*
X1022245D03*
X1012105Y232509D03*
X1025625D03*
X1029005Y226660D03*
X1005345Y244209D03*
X1008725Y226660D03*
X1005345Y232509D03*
X1001965Y226660D03*
X1022245Y250060D03*
X1001965Y261760D03*
X1012105Y255909D03*
X1015485Y253960D03*
X1018865Y252009D03*
X1005345Y259809D03*
X1008725Y257860D03*
X981686Y281260D03*
Y292959D03*
Y300760D03*
X988446D03*
X978306Y310509D03*
X991826D03*
X985066D03*
X974926Y300760D03*
X988446Y292959D03*
X991826Y283209D03*
X988446Y281260D03*
X985066Y283209D03*
X978306D03*
X974926Y292959D03*
Y281260D03*
X991826Y333909D03*
X995206Y335860D03*
Y339760D03*
Y328060D03*
X991826Y326110D03*
X981686Y339760D03*
X978306Y333909D03*
Y330009D03*
Y326110D03*
X981686Y331960D03*
X985066Y330009D03*
X974926Y324160D03*
X988446Y339760D03*
X974926Y312460D03*
X981686D03*
X988446D03*
X991826Y314409D03*
Y330009D03*
X995206Y331960D03*
X988446D03*
X995206Y324160D03*
X988446Y316360D03*
X991826Y318309D03*
X995206Y320260D03*
X991826Y322209D03*
X998586Y333909D03*
X974926Y339760D03*
Y335860D03*
X1017957Y312421D03*
X1025438Y312381D03*
X1022915Y312372D03*
X1020404Y312408D03*
X1028039Y312414D03*
X1008725Y339760D03*
X1005345Y337809D03*
X1001965Y335860D03*
X1012105Y341709D03*
X995206Y343660D03*
X985066Y361209D03*
X974926Y355360D03*
Y347560D03*
X981686D03*
X978306Y345609D03*
X981686Y355360D03*
X985066Y349509D03*
X998586D03*
X978306Y365109D03*
X981686Y363160D03*
X974926D03*
Y367060D03*
Y370959D03*
X998586Y365109D03*
Y353409D03*
X974926Y343660D03*
X995206Y359260D03*
X988446D03*
Y347560D03*
X991826Y345609D03*
X988446Y351460D03*
Y355360D03*
X998586Y392410D03*
X995206Y382660D03*
X985066Y372909D03*
X974926Y374860D03*
X985066Y384609D03*
X974926Y386560D03*
X991826Y376809D03*
X974066Y399911D03*
X978306Y376809D03*
X974926Y378760D03*
X981686D03*
X985066Y380709D03*
X1005345Y365109D03*
X1008725Y370959D03*
X1001965D03*
X1005345Y353409D03*
X1018865Y365109D03*
X1012105D03*
X1025625D03*
X1022245Y370959D03*
X1015485D03*
X1018865Y353409D03*
X1012105D03*
X1025625D03*
X1029005Y370959D03*
X1032385Y365109D03*
X1005345Y349509D03*
X1018865Y345609D03*
X1015485Y343660D03*
X1007595Y402800D03*
X1008725Y382660D03*
X1001965D03*
X1005345Y392410D03*
X1029005Y390460D03*
X1025625Y392410D03*
X1022245Y382660D03*
X1015485D03*
X1012105Y392410D03*
X1018865D03*
X1029005Y382660D03*
X1027875Y402800D03*
X987401Y515364D03*
X990748Y512792D03*
X997441Y518157D03*
X976421Y499768D03*
X980708Y510114D03*
X977362Y518157D03*
X1000490Y509999D03*
X1016473Y515152D03*
Y510114D03*
X1008650Y515200D03*
X1008526Y510114D03*
X990748Y536957D03*
X977362Y529014D03*
X980708Y536957D03*
X987401Y529014D03*
X990748Y547922D03*
X980708Y547914D03*
X997441Y529022D03*
X977362Y555857D03*
X987401D03*
X997441D03*
X977362Y566814D03*
X990748Y574757D03*
Y585722D03*
X980708Y585714D03*
Y574757D03*
X997441Y566822D03*
X987401Y566814D03*
X1000787Y536957D03*
Y547922D03*
X1017300Y536200D03*
X1017519Y529057D03*
X1017300Y547914D03*
X1007518Y536727D03*
X1007480Y528942D03*
X1007280Y547914D03*
X1016800Y566814D03*
X1019277Y585714D03*
X1016800Y574742D03*
X1000787Y585722D03*
Y574757D03*
X1016819Y555842D03*
X1007518D03*
Y566814D03*
X1007480Y574742D03*
X1006633Y585714D03*
X977362Y593657D03*
X987401D03*
X997441D03*
Y607292D03*
X977362D03*
X990748Y612457D03*
X980708Y609864D03*
X987401Y604499D03*
X1016778Y611759D03*
X1017519Y604614D03*
Y593642D03*
X1007480Y612242D03*
X1000787Y609864D03*
X1007480Y604614D03*
X1006634Y593642D03*
X1043800Y-9700D03*
X1047637Y-4536D03*
X1057676Y-1743D03*
X1047637Y9107D03*
X1057677D03*
X1050984Y17042D03*
X1067716Y-4536D03*
X1081102D03*
X1074409D03*
X1084448Y-7108D03*
X1077755D03*
X1091141Y-1843D03*
X1067716Y9107D03*
X1091141D03*
X1074409D03*
X1081102D03*
X1061024Y17057D03*
X1067716Y28007D03*
Y17042D03*
X1091141D03*
X1084450Y17057D03*
X1077757D03*
X1091141Y28007D03*
X1050984Y54842D03*
X1047637Y35942D03*
Y46907D03*
X1057677Y35942D03*
Y46907D03*
X1057676Y87392D03*
X1050983Y92757D03*
X1047637Y84599D03*
X1035000Y81200D03*
X1057677Y73742D03*
X1047637D03*
X1061024Y54857D03*
X1067716Y54842D03*
Y35942D03*
Y46907D03*
Y65807D03*
X1091141Y54842D03*
Y35942D03*
X1084450Y54857D03*
X1081102Y35942D03*
X1074409D03*
X1077757Y54857D03*
X1081102Y46907D03*
X1074409D03*
X1091141D03*
Y65807D03*
X1067716Y89964D03*
Y84599D03*
X1081102D03*
X1091141Y87392D03*
Y92657D03*
X1077755Y92757D03*
X1074409Y84714D03*
X1084448Y92757D03*
X1061023Y89964D03*
X1067716Y73742D03*
X1074409D03*
X1081102D03*
X1091141D03*
X1050983Y105800D03*
X1057734Y105750D03*
X1077304Y105800D03*
X1071111D03*
X1064428D03*
X1035765Y214960D03*
X1042524D03*
X1042506Y195041D03*
X1045904Y197359D03*
X1054000Y199100D03*
X1035765Y207159D03*
X1042524Y203260D03*
X1049284Y214960D03*
Y203260D03*
X1072202Y216196D03*
X1065242Y208397D03*
X1068822Y214247D03*
X1065242Y212296D03*
Y204496D03*
X1071072Y199583D03*
X1095861Y218147D03*
X1089101Y214247D03*
Y210346D03*
X1092481Y216196D03*
X1095861Y206446D03*
X1091351Y199841D03*
X1075582Y206446D03*
Y218147D03*
X1082341D03*
X1078962Y216196D03*
X1078961Y212296D03*
X1082341Y214247D03*
X1085721Y212296D03*
Y216196D03*
X1084591Y198931D03*
X1042524Y226660D03*
X1039145Y232509D03*
X1035765Y226660D03*
X1057314Y240309D03*
X1049284Y226660D03*
X1045904Y232509D03*
X1057314D03*
X1050002Y264899D03*
X1047002D03*
X1043502D03*
X1040502D03*
X1095861Y229847D03*
X1068822Y233746D03*
X1065242Y235696D03*
Y223996D03*
X1068822Y237647D03*
Y249347D03*
X1065242Y247396D03*
X1068822Y241547D03*
X1072202Y243496D03*
Y251296D03*
X1092481Y223996D03*
Y231797D03*
X1089101Y233746D03*
Y237647D03*
X1095861D03*
Y245447D03*
X1078962Y251296D03*
X1082341Y245447D03*
Y249347D03*
X1078962Y247396D03*
X1092481Y243496D03*
X1075582Y245447D03*
X1085721Y251296D03*
X1075582Y249347D03*
X1085721Y243496D03*
X1089101Y241547D03*
X1085721Y223996D03*
X1075582Y229847D03*
X1082341D03*
X1078962Y227896D03*
Y220096D03*
Y223996D03*
X1085721Y231797D03*
X1082341Y237647D03*
X1075582D03*
X1072202Y231797D03*
Y223996D03*
X1089101Y253247D03*
X1092481Y255196D03*
X1095861Y257147D03*
X1047756Y338341D03*
X1044256D03*
X1050756D03*
X1053702Y338404D03*
X1052664Y357309D03*
X1049284Y370959D03*
X1035765D03*
X1042524D03*
X1045904Y365109D03*
X1039145D03*
X1052664D03*
Y392410D03*
X1040265Y394359D03*
X1049284Y382660D03*
X1035765D03*
X1042524D03*
Y390460D03*
X1056176Y402471D03*
X1041395Y402800D03*
X1086841Y358547D03*
X1094731Y346546D03*
X1086841Y354647D03*
X1090221Y352696D03*
X1091351Y348497D03*
X1073322Y354647D03*
X1076702Y356596D03*
X1080082Y354647D03*
X1083462Y368296D03*
X1076702Y372197D03*
Y368296D03*
X1073322Y362447D03*
X1086841D03*
X1090221Y372197D03*
Y364396D03*
X1093601Y366347D03*
X1090221Y368296D03*
X1076702Y360496D03*
X1083462D03*
Y352696D03*
X1076702D03*
X1093601Y358547D03*
X1090221Y379996D03*
X1073323Y401449D03*
X1078962Y399496D03*
X1093601Y401447D03*
X1060694Y374860D03*
X1073322Y374146D03*
X1086841D03*
X1073323Y397548D03*
X1073322Y385847D03*
X1080082Y393647D03*
X1083462Y391696D03*
X1080082Y385847D03*
X1083462Y376096D03*
X1080082Y378047D03*
X1083462Y379996D03*
X1076702Y376096D03*
X1090221Y395595D03*
X1086841Y389747D03*
X1093601Y393647D03*
X1090221Y391696D03*
X1093601Y385847D03*
X1086841D03*
X1093601Y397546D03*
Y378047D03*
X1086841Y381947D03*
X1093601Y405347D03*
X1077832Y407800D03*
X1047637Y509999D03*
X1057676Y512792D03*
X1035000Y521556D03*
X1050983Y518157D03*
X1067716Y509999D03*
X1074409Y510114D03*
X1061023Y515364D03*
X1091141Y518057D03*
X1077755Y518157D03*
X1081102Y509999D03*
X1084448Y518157D03*
X1082800Y497650D03*
X1091141Y512792D03*
X1067716Y515364D03*
X1057677Y547907D03*
Y536942D03*
X1047637Y547907D03*
Y536942D03*
X1057677Y574742D03*
Y585707D03*
X1047637Y574742D03*
Y585707D03*
X1050984Y555842D03*
X1074409Y547907D03*
X1081102D03*
X1091141D03*
Y529007D03*
Y536942D03*
X1074409D03*
X1081102D03*
X1067716D03*
Y529007D03*
X1061024Y555857D03*
X1077757D03*
X1084450D03*
X1091141Y555842D03*
X1067716D03*
X1081102Y574742D03*
Y585707D03*
X1074409D03*
X1091141Y574742D03*
Y585707D03*
X1067716Y574742D03*
Y585599D03*
Y566807D03*
X1091141D03*
X1074409Y574742D03*
X1091141Y612557D03*
X1057676Y612657D03*
X1050984Y593642D03*
X1047637Y609864D03*
X1061024Y593657D03*
X1061023Y604614D03*
X1077757Y593657D03*
X1084450D03*
X1067716Y593642D03*
Y609864D03*
Y604499D03*
X1081102Y609864D03*
X1091141Y593642D03*
Y607292D03*
X1084448D03*
X1077755D03*
X1050983D03*
X1074409Y609864D03*
X1119453Y-9864D03*
X1097352Y-7180D03*
X1104141Y-7851D03*
X1110520Y-7700D03*
X1114340Y-1801D03*
X1107874Y-1751D03*
X1101181Y-1801D03*
X1107724Y9114D03*
X1101181D03*
X1114340Y9098D03*
X1114400Y28100D03*
X1110520Y14814D03*
X1104177Y14714D03*
X1098500Y17000D03*
X1114300Y16900D03*
X1119400Y9300D03*
X1119453Y27936D03*
X1119440Y17114D03*
X1097900Y13700D03*
Y31900D03*
X1110520Y30100D03*
X1097834Y28100D03*
X1104141Y29949D03*
X1156300Y-2000D03*
X1151152Y-1801D03*
X1131299Y9114D03*
X1124606D03*
X1151152Y9098D03*
X1137992Y9114D03*
X1144535D03*
X1127952Y-7851D03*
X1124606Y-1751D03*
X1131299D03*
X1134645Y-7851D03*
X1156265Y-9864D03*
X1151200Y-9700D03*
X1147331Y-7700D03*
X1140952Y-7851D03*
X1137992Y-1801D03*
X1144685Y-1751D03*
X1156212Y9300D03*
X1127952Y14814D03*
X1151211Y28100D03*
X1156252Y17114D03*
X1151112Y16900D03*
X1147331Y30100D03*
Y14814D03*
X1134645Y29949D03*
X1140952D03*
X1140988Y14714D03*
X1134645Y14814D03*
X1156265Y27936D03*
X1127952Y29949D03*
X1114340Y35999D03*
X1098235Y68090D03*
X1110520Y67900D03*
X1104141Y67749D03*
X1114366Y65950D03*
X1119440Y54914D03*
X1119400Y47100D03*
Y35800D03*
X1098100Y51000D03*
X1119453Y65736D03*
X1107874Y36049D03*
X1098022Y35761D03*
X1101181Y35999D03*
X1107724Y46914D03*
X1110520Y52614D03*
X1098581Y54883D03*
X1104177Y52514D03*
X1101181Y46900D03*
X1098125Y46975D03*
X1114300Y54700D03*
X1114340Y46898D03*
X1098259Y70896D03*
X1101181Y84714D03*
X1098218Y85296D03*
X1114340Y73799D03*
X1107874Y73849D03*
X1101181Y73799D03*
X1098207Y73589D03*
X1110520Y90314D03*
X1114340Y84698D03*
X1114316Y92500D03*
X1107724Y84714D03*
X1119440Y92714D03*
X1119416Y84700D03*
X1119466Y73550D03*
X1098300Y89900D03*
X1104177Y90314D03*
X1127952Y67749D03*
X1156211Y35800D03*
X1156200Y47000D03*
X1151152Y35999D03*
Y46898D03*
X1151100Y54700D03*
X1147331Y52614D03*
X1134645D03*
X1137992Y46914D03*
Y35999D03*
X1144535Y46914D03*
X1144685Y36049D03*
X1156252Y54914D03*
X1134645Y67749D03*
X1140952D03*
X1156265Y65736D03*
X1151178Y65950D03*
X1147331Y67900D03*
X1131299Y46914D03*
X1124606D03*
X1127952Y52614D03*
X1131299Y36049D03*
X1124606D03*
X1131299Y73849D03*
X1124606D03*
X1127952Y90414D03*
X1131299Y84714D03*
X1124606D03*
X1147331Y90414D03*
X1137992Y73799D03*
X1144535Y84714D03*
X1140988Y90314D03*
X1137992Y84714D03*
X1134645Y90414D03*
X1144685Y73849D03*
X1156252Y92714D03*
X1151128Y92500D03*
X1151152Y84698D03*
X1156228Y84700D03*
X1156278Y73550D03*
X1151152Y73799D03*
X1138242Y104314D03*
X1144685D03*
X1156278Y112865D03*
X1151152Y113114D03*
X1141038Y109564D03*
X1147331D03*
X1156265Y105051D03*
X1151178Y105265D03*
X1116141Y206446D03*
X1136420Y210346D03*
X1099241Y216196D03*
Y212296D03*
X1109381Y214247D03*
X1116141Y218147D03*
X1106001Y212296D03*
X1102621Y218147D03*
Y214247D03*
X1119521Y216196D03*
X1119520Y212296D03*
X1104871Y198050D03*
X1106001Y216196D03*
X1112761D03*
X1129660Y206447D03*
X1126280Y216196D03*
Y212296D03*
X1125300Y199900D03*
X1122900Y214247D03*
Y218147D03*
X1129660Y214247D03*
X1147950Y209900D03*
X1136420Y218147D03*
Y214247D03*
X1151060Y212296D03*
X1157820D03*
X1099241Y227896D03*
Y220096D03*
X1102621Y229847D03*
X1099241Y223996D03*
X1109381Y233746D03*
X1112761Y231797D03*
Y223996D03*
X1116141Y237647D03*
X1109381D03*
X1106001Y223996D03*
X1102621Y237647D03*
Y245447D03*
X1112761Y251296D03*
X1116141Y245447D03*
X1106001Y243496D03*
X1112761D03*
X1109381Y241547D03*
X1106001Y251296D03*
X1099241D03*
Y247396D03*
X1119521Y223996D03*
Y220096D03*
Y227896D03*
Y247396D03*
Y251296D03*
X1106001Y231797D03*
X1116141Y229847D03*
X1107561Y269038D03*
X1116141Y264947D03*
X1111631Y271300D03*
X1106001Y262996D03*
Y259096D03*
X1099241Y255196D03*
Y259096D03*
X1119521Y270796D03*
X1118391Y274997D03*
X1119521Y255196D03*
X1102621Y261047D03*
Y257147D03*
X1109381Y261047D03*
X1116141Y257147D03*
X1112761Y259096D03*
X1110648Y276899D03*
X1100200Y273300D03*
X1129660Y237647D03*
X1126280Y223996D03*
Y231797D03*
X1122900Y229847D03*
Y237647D03*
X1129660Y233746D03*
Y241547D03*
X1126280Y251296D03*
Y243496D03*
X1122900Y245447D03*
X1144300Y243496D03*
X1151060Y247396D03*
X1154440Y245447D03*
X1144300Y247396D03*
Y251296D03*
X1136420Y245447D03*
X1154440Y241547D03*
X1136420D03*
X1157820Y239596D03*
X1147680Y222047D03*
X1144300Y235696D03*
X1136420Y229847D03*
Y233746D03*
Y222047D03*
Y225947D03*
Y237647D03*
X1133040Y223996D03*
Y235696D03*
Y243496D03*
Y251296D03*
X1147680Y225947D03*
X1151060Y223996D03*
X1147680Y233746D03*
X1154440Y229847D03*
X1157820Y220096D03*
Y223996D03*
Y231797D03*
X1154440Y253247D03*
X1130780Y278596D03*
X1129660Y261047D03*
X1130780Y274696D03*
X1126280Y259096D03*
X1122900Y257147D03*
X1157820Y278596D03*
Y270796D03*
X1151060Y266896D03*
Y274696D03*
X1137540D03*
X1151060Y259096D03*
X1144300Y255196D03*
X1133040Y259096D03*
X1134160Y268847D03*
X1136420Y257147D03*
X1144300Y278596D03*
Y270796D03*
X1137540Y278596D03*
X1119521Y286396D03*
Y305896D03*
X1108251Y338746D03*
X1117261Y340996D03*
X1104871Y340697D03*
X1119521Y321496D03*
X1130780Y290296D03*
X1127400Y288347D03*
X1130780Y309797D03*
Y301996D03*
X1127400Y303947D03*
Y307847D03*
X1157820Y290296D03*
X1151060Y298096D03*
Y290296D03*
Y282496D03*
X1144300Y286396D03*
Y294196D03*
X1157820D03*
X1140920Y300047D03*
X1134160Y292247D03*
Y300047D03*
X1140920Y292247D03*
X1137540Y282496D03*
X1144300Y309797D03*
X1137540D03*
X1147680Y303947D03*
X1154440Y307847D03*
X1130780Y313696D03*
X1157820D03*
X1124021Y340996D03*
Y337096D03*
X1127400Y327347D03*
X1157820Y337096D03*
Y333196D03*
X1134160Y323446D03*
X1151060Y340996D03*
Y333196D03*
X1154440Y319547D03*
X1157820Y317596D03*
X1137540D03*
X1157820Y329296D03*
X1147680Y327347D03*
X1154440Y335147D03*
X1144300Y340996D03*
Y337096D03*
X1140920Y339047D03*
Y331247D03*
X1154440Y323446D03*
Y315647D03*
X1147680Y319547D03*
X1157820Y325396D03*
X1154440Y339047D03*
Y331247D03*
X1127400Y319547D03*
Y315647D03*
X1100361Y350747D03*
X1113881D03*
Y358547D03*
X1117261Y348796D03*
X1100361Y358547D03*
X1103741Y348796D03*
Y352696D03*
X1110501D03*
X1107121Y346847D03*
Y354647D03*
Y358547D03*
Y362447D03*
X1103741Y372197D03*
X1110501Y364396D03*
X1103741D03*
X1113881Y366347D03*
X1117261Y372197D03*
Y368296D03*
X1110501Y372197D03*
X1096981Y368296D03*
Y372197D03*
X1100361Y366347D03*
X1113881Y401447D03*
X1110501Y391696D03*
Y395595D03*
X1107121Y389747D03*
X1100361Y385847D03*
X1107121D03*
X1100361Y393647D03*
X1103741Y391696D03*
X1100361Y397547D03*
X1113881Y385847D03*
Y397546D03*
Y393647D03*
X1103741Y379996D03*
X1113881Y378047D03*
X1117261Y376096D03*
X1110501Y379996D03*
X1107121Y381947D03*
X1096981Y376096D03*
X1100361Y378047D03*
X1151060Y368296D03*
X1147680Y366347D03*
X1120641Y350747D03*
Y358547D03*
Y366347D03*
X1127400Y362447D03*
X1124021Y348796D03*
Y352696D03*
X1127400Y354647D03*
Y358547D03*
X1130780Y360496D03*
X1127400Y342947D03*
X1134160Y346847D03*
Y362447D03*
Y366347D03*
Y370247D03*
X1147680Y342947D03*
X1151060Y356596D03*
Y360496D03*
X1144300D03*
X1137540D03*
X1144300Y356596D03*
X1140920Y358547D03*
X1147680Y346847D03*
Y350747D03*
X1151060Y352696D03*
Y348796D03*
X1147680Y358547D03*
X1157820Y360496D03*
X1154440Y358547D03*
Y342947D03*
Y354647D03*
X1157820Y352696D03*
X1147680Y354647D03*
X1144300Y348796D03*
X1140920Y346847D03*
Y350747D03*
X1144300Y344896D03*
X1151060D03*
X1154440Y346847D03*
X1140920Y362447D03*
X1154440Y366347D03*
X1144300Y372197D03*
X1137540D03*
Y368296D03*
X1140920Y366347D03*
Y370247D03*
X1151060Y364396D03*
X1144300D03*
X1137540D03*
X1147680Y362447D03*
X1130780Y352696D03*
Y344896D03*
X1124021Y372197D03*
X1130780D03*
X1124021Y364396D03*
X1137540Y403396D03*
Y399496D03*
X1124021Y391696D03*
X1130780Y395596D03*
X1127400Y385847D03*
Y389747D03*
X1130780Y391696D03*
X1124021Y379996D03*
X1127400Y381947D03*
X1130780Y379996D03*
X1137540Y395597D03*
X1140920Y397546D03*
X1137540Y376096D03*
X1157820Y387796D03*
X1140920Y378047D03*
Y381947D03*
X1147680Y393647D03*
X1120641Y385847D03*
Y393647D03*
Y378047D03*
Y401447D03*
X1140920Y374146D03*
X1151060Y395597D03*
Y391696D03*
X1147680Y385847D03*
Y397546D03*
X1151060Y379996D03*
X1154440Y378047D03*
Y381947D03*
X1140920Y389747D03*
X1134160Y393647D03*
Y385847D03*
Y378047D03*
X1140920Y385847D03*
X1144300Y391696D03*
X1117261Y407296D03*
X1113881Y405347D03*
X1096699Y407782D03*
X1134160Y405347D03*
X1119440Y518114D03*
X1114316Y517900D03*
X1114340Y510098D03*
X1110520Y515714D03*
X1097343Y512794D03*
X1104177Y515714D03*
X1101181Y510114D03*
X1098300Y515300D03*
X1107724Y510114D03*
X1137992Y495887D03*
X1144385D03*
X1140988Y493744D03*
X1156252Y490867D03*
X1147331Y493494D03*
X1151168Y490867D03*
X1127952Y515814D03*
X1124606Y510114D03*
X1131299D03*
X1156252Y518114D03*
X1147331Y515814D03*
X1151128Y517900D03*
X1156252Y498867D03*
X1151168D03*
X1151152Y510098D03*
X1134645Y515814D03*
X1137992Y510114D03*
X1140988Y515714D03*
X1144535Y510114D03*
X1156228Y510100D03*
X1104141Y530949D03*
X1098040Y536723D03*
X1098160Y533809D03*
X1119416Y547900D03*
X1119466Y536750D03*
X1119453Y528936D03*
X1098300Y553100D03*
X1114340Y547898D03*
X1107724Y547914D03*
X1101181D03*
X1110520Y553514D03*
X1104177D03*
X1098118Y549843D03*
X1098018Y531156D03*
X1114366Y529150D03*
X1114340Y536999D03*
X1110520Y531100D03*
X1107874Y537049D03*
X1101181Y536999D03*
X1119440Y555914D03*
X1114316Y555700D03*
X1119416Y585700D03*
X1119466Y574550D03*
X1119453Y566736D03*
X1104141Y568749D03*
X1097899Y574773D03*
X1101181Y585714D03*
X1097834Y569200D03*
X1107724Y585714D03*
X1107874Y574849D03*
X1110520Y568900D03*
X1101181Y574799D03*
X1114340D03*
Y585698D03*
X1114366Y566950D03*
X1140988Y553514D03*
X1151152Y547898D03*
X1156228Y547900D03*
X1137992Y547914D03*
X1144535D03*
X1127952Y553614D03*
X1131299Y547914D03*
X1124606D03*
X1131299Y537049D03*
X1124606D03*
X1127952Y530949D03*
X1151178Y529150D03*
X1151152Y536999D03*
X1147331Y531100D03*
X1156278Y536750D03*
X1156265Y528936D03*
X1134645Y530949D03*
X1140952D03*
X1137992Y536999D03*
X1144685Y537049D03*
X1147331Y553614D03*
X1134645D03*
X1156252Y555914D03*
X1151128Y555700D03*
X1156265Y566736D03*
X1151178Y566950D03*
X1134645Y568749D03*
X1137992Y585714D03*
X1144535D03*
X1140952Y568749D03*
X1137992Y574799D03*
X1144685Y574849D03*
X1151152Y585698D03*
Y574799D03*
X1147331Y568900D03*
X1156228Y585700D03*
X1156278Y574550D03*
X1131299Y585714D03*
X1124606D03*
X1131299Y574849D03*
X1127952Y568749D03*
X1124606Y574849D03*
X1137992Y612599D03*
X1144685Y612649D03*
X1151152Y612599D03*
X1124606Y612649D03*
X1131299D03*
X1114340Y612599D03*
X1107874Y612649D03*
X1101181Y612599D03*
X1097352Y607220D03*
X1110520Y606700D03*
X1119453Y604536D03*
X1119466Y612350D03*
X1119440Y593714D03*
X1104177Y591314D03*
X1110520D03*
X1114316Y593500D03*
X1098300Y590900D03*
X1114366Y604750D03*
X1104141Y606549D03*
X1156265Y604536D03*
X1147331Y606700D03*
X1134645Y606549D03*
X1140952D03*
X1156278Y612350D03*
X1134645Y591414D03*
X1140988Y591314D03*
X1151128Y593500D03*
X1147331Y591414D03*
X1156252Y593714D03*
X1151178Y604750D03*
X1127952Y606549D03*
Y591414D03*
X1161417Y9114D03*
X1168110D03*
X1174803D03*
X1171456Y-7851D03*
X1164763D03*
X1177763D03*
X1168110Y-1751D03*
X1161417D03*
X1174803Y-1801D03*
X1171456Y14814D03*
X1164763Y29949D03*
X1171456D03*
X1164763Y14814D03*
X1177799Y14714D03*
X1177763Y29949D03*
X1181496Y-1751D03*
X1181346Y9114D03*
X1187963Y9098D03*
X1204921Y9114D03*
X1198228D03*
X1188011Y-9700D03*
X1193076Y-9864D03*
X1184142Y-7700D03*
X1193111Y-2000D03*
X1187963Y-1801D03*
X1201574Y-7851D03*
X1204921Y-1751D03*
X1198228D03*
X1218307D03*
X1211614Y-1801D03*
X1214574Y-7851D03*
X1208267D03*
X1218157Y9114D03*
X1211614D03*
X1193023Y9300D03*
X1184142Y30100D03*
Y14814D03*
X1188023Y28100D03*
X1187923Y16900D03*
X1193063Y17114D03*
X1193076Y27936D03*
X1201574Y14814D03*
Y29949D03*
X1208267Y14814D03*
Y29949D03*
X1214600Y14714D03*
X1214574Y29949D03*
X1161417Y36049D03*
X1164763Y52614D03*
X1168110Y36049D03*
Y46914D03*
X1161417D03*
X1174803D03*
X1171456Y52614D03*
X1174803Y35999D03*
X1177763Y67749D03*
X1171456D03*
X1164763D03*
X1177799Y90314D03*
X1174803Y84714D03*
X1168110D03*
Y73849D03*
X1161417D03*
X1174803Y73799D03*
X1161417Y84714D03*
X1164763Y90414D03*
X1171456D03*
X1181346Y46914D03*
X1181496Y36049D03*
X1184142Y52614D03*
X1193012Y47000D03*
X1187963Y46898D03*
Y35999D03*
X1187912Y54700D03*
X1187989Y65950D03*
X1193076Y65736D03*
X1193063Y54914D03*
X1193023Y35800D03*
X1204921Y36049D03*
X1198228D03*
Y46914D03*
X1204921D03*
X1201574Y52614D03*
X1184142Y67900D03*
X1201574Y67749D03*
X1218307Y36049D03*
X1211614Y35999D03*
X1214960Y52864D03*
X1211614Y46914D03*
X1218157D03*
X1208267Y52614D03*
X1211614Y73799D03*
X1218307Y73849D03*
X1208267Y90414D03*
X1218157Y84714D03*
X1211614D03*
X1214574Y67749D03*
X1208267D03*
X1181346Y84714D03*
X1181496Y73849D03*
X1184142Y90414D03*
X1193039Y84700D03*
X1193063Y92714D03*
X1187939Y92500D03*
X1187963Y84698D03*
Y73799D03*
X1193089Y73550D03*
X1198228Y73849D03*
X1204921D03*
X1198228Y84714D03*
X1204921D03*
X1201574Y90414D03*
X1177799Y109914D03*
X1161632Y104314D03*
X1170721Y109564D03*
X1164428D03*
X1168075Y104314D03*
X1174742D03*
X1208267Y110014D03*
X1181346Y104314D03*
X1187963Y113114D03*
X1193089Y112865D03*
X1184142Y109564D03*
X1193076Y105051D03*
X1187989Y105265D03*
X1201574Y110014D03*
X1198228Y104314D03*
X1204921D03*
X1161200Y206446D03*
X1167960Y206447D03*
Y218147D03*
X1171339Y208397D03*
X1174719Y218147D03*
Y206447D03*
X1178099Y208397D03*
Y216196D03*
X1161200Y210346D03*
Y218147D03*
X1181479Y206447D03*
X1188239Y210346D03*
Y206447D03*
X1201759Y218147D03*
X1205759Y206682D03*
X1197492Y201356D03*
X1198379Y212296D03*
X1194999Y210346D03*
X1184859Y204496D03*
X1188239Y214247D03*
X1164580Y235696D03*
X1167960Y229847D03*
X1164580Y223996D03*
Y227896D03*
Y239596D03*
X1178099Y247396D03*
X1161200Y241547D03*
X1164580Y247396D03*
X1161200Y249347D03*
X1171339Y247396D03*
X1178099Y243496D03*
X1171339Y235696D03*
Y220096D03*
Y231797D03*
X1178099Y227896D03*
Y235696D03*
Y220096D03*
X1174719Y237647D03*
X1167960Y253247D03*
X1174719D03*
X1164580Y270796D03*
X1171339Y274696D03*
X1174719Y280547D03*
X1171339Y266896D03*
X1164580Y278596D03*
X1159578Y265117D03*
X1171339Y259096D03*
X1178099Y274696D03*
X1181479Y222047D03*
X1188239D03*
X1191619Y239596D03*
X1188239Y225947D03*
X1184859Y235696D03*
X1188239Y237647D03*
X1184859Y247396D03*
X1188239Y249347D03*
X1201759Y229847D03*
Y225947D03*
Y233746D03*
X1198379Y235696D03*
Y243496D03*
X1201759Y241547D03*
Y249347D03*
X1198379Y239596D03*
X1194999Y225947D03*
Y222047D03*
Y233746D03*
X1184859Y239596D03*
Y251296D03*
X1212199D03*
Y243496D03*
X1208519Y233746D03*
X1215700Y223600D03*
X1194999Y264947D03*
Y268847D03*
Y272747D03*
Y280547D03*
X1188239Y257147D03*
X1208519Y272747D03*
X1208819Y280547D03*
X1181479Y261047D03*
Y268847D03*
Y276646D03*
X1212199Y274696D03*
X1217200Y270500D03*
X1213808Y264800D03*
X1208519Y264947D03*
X1184859Y259096D03*
X1191619Y274696D03*
X1205139D03*
X1198379Y278596D03*
X1201759Y261047D03*
X1198379Y255196D03*
X1201759Y257147D03*
X1174719Y300047D03*
Y284447D03*
X1164580Y294196D03*
Y290296D03*
Y286396D03*
X1161200Y284447D03*
X1178099Y294196D03*
Y298096D03*
Y286396D03*
X1164580Y301996D03*
X1171339D03*
X1161200Y307847D03*
Y335147D03*
Y339047D03*
X1164580Y329296D03*
Y333196D03*
Y337096D03*
X1167960Y339047D03*
Y327347D03*
X1161200Y331247D03*
Y327347D03*
X1178099Y337096D03*
Y317596D03*
X1164580Y321496D03*
Y317596D03*
X1161200Y323446D03*
Y319547D03*
Y315647D03*
X1167960Y323446D03*
Y315647D03*
Y319547D03*
X1174719Y315647D03*
X1171339Y317596D03*
X1164580Y325396D03*
X1171339D03*
X1174719Y335147D03*
X1205500Y309797D03*
X1198379D03*
X1194999Y288347D03*
Y292247D03*
Y296147D03*
Y300047D03*
Y307847D03*
Y303947D03*
X1191619Y298096D03*
X1181479Y300047D03*
Y288347D03*
Y292247D03*
Y311747D03*
Y307847D03*
Y303947D03*
X1188239Y288347D03*
Y284447D03*
Y292247D03*
X1184859Y294196D03*
Y290296D03*
X1191619Y294196D03*
X1184859Y309797D03*
X1188239Y311747D03*
X1184859Y301996D03*
X1201759Y284447D03*
Y288347D03*
X1205439Y298096D03*
X1198379Y286396D03*
X1205439Y305896D03*
X1194999Y335147D03*
Y331247D03*
X1212200Y333196D03*
X1208519Y339047D03*
X1208826Y319544D03*
X1181479Y327347D03*
Y319547D03*
Y335147D03*
X1198379Y313696D03*
X1188239Y319547D03*
X1184859Y321496D03*
X1188239Y339047D03*
Y335147D03*
X1184859Y329296D03*
X1191619Y321496D03*
X1198379Y325396D03*
Y340996D03*
X1201759Y323446D03*
X1205139Y333196D03*
X1194999Y319547D03*
Y315647D03*
X1167960Y370247D03*
X1164580Y372197D03*
X1171339Y356596D03*
Y360496D03*
X1164580Y356596D03*
X1167960Y342947D03*
X1171339Y348796D03*
X1174719Y354647D03*
Y342947D03*
X1161200Y370247D03*
X1171339Y372197D03*
X1167960Y362447D03*
X1178099Y364396D03*
X1171339Y399496D03*
X1164580Y403396D03*
X1178099D03*
X1167960Y389747D03*
X1161200Y397546D03*
X1167960Y397547D03*
X1174719Y393647D03*
X1161200Y378047D03*
X1164580Y379996D03*
X1174719Y381947D03*
X1194999Y346847D03*
Y354647D03*
X1209219Y370247D03*
X1212199Y356597D03*
Y344896D03*
Y352696D03*
X1181479Y346847D03*
X1188239Y366347D03*
X1194999D03*
X1191619Y348796D03*
X1184859Y356596D03*
X1191619Y360496D03*
X1201759Y350747D03*
X1205139Y360496D03*
X1181479Y374146D03*
Y389747D03*
X1209769Y374146D03*
X1184859Y383896D03*
X1188239Y393647D03*
X1201759Y389747D03*
X1197258Y397546D03*
X1194999Y385847D03*
X1188239Y378047D03*
X1201759D03*
X1208819Y393647D03*
Y381897D03*
X1195555Y405773D03*
X1192200Y409550D03*
X1185989Y407800D03*
X1180400Y495787D03*
X1167500Y495800D03*
X1174203Y495787D03*
X1161320Y495800D03*
X1170656Y491144D03*
X1164363Y491044D03*
X1177849Y490944D03*
X1168110Y510114D03*
X1164763Y515814D03*
X1161417Y510114D03*
X1177799Y515714D03*
X1171456Y515814D03*
X1174803Y510114D03*
X1208267Y493444D03*
X1200974Y490744D03*
X1193063Y490909D03*
X1187978Y490609D03*
X1184142Y490794D03*
X1181346Y510114D03*
X1204400Y495887D03*
X1198100Y495800D03*
X1208267Y515814D03*
X1211614Y510114D03*
X1218157D03*
X1187963Y510098D03*
X1204921Y510114D03*
X1198228D03*
X1201574Y515814D03*
X1184142D03*
X1187939Y517900D03*
X1193039Y510100D03*
X1193063Y518114D03*
X1187978Y498609D03*
X1193063Y498909D03*
X1161417Y547914D03*
X1168110D03*
X1174803D03*
X1177799Y553514D03*
X1177763Y530949D03*
X1168110Y537049D03*
X1164763Y530949D03*
X1161417Y537049D03*
X1171456Y530949D03*
X1174803Y536999D03*
X1164763Y553614D03*
X1171456D03*
X1174803Y574799D03*
X1161417Y574849D03*
X1171456Y568749D03*
X1168110Y585714D03*
X1161417D03*
X1168110Y574849D03*
X1164763Y568749D03*
X1174803Y585714D03*
X1177763Y568749D03*
X1181496Y537049D03*
X1181346Y547914D03*
X1211614Y536999D03*
X1214574Y530949D03*
X1184142Y531100D03*
X1193076Y528936D03*
X1198228Y547914D03*
X1204921D03*
X1201574Y553614D03*
Y530949D03*
X1204921Y537049D03*
X1198228D03*
X1193039Y547900D03*
X1187963Y547898D03*
X1184142Y553614D03*
X1193089Y536750D03*
X1187989Y529150D03*
X1187963Y536999D03*
X1218307Y537049D03*
X1211614Y547914D03*
X1208267Y553614D03*
Y530949D03*
X1218157Y547914D03*
X1181346Y585714D03*
X1181496Y574849D03*
X1193063Y555914D03*
X1187939Y555700D03*
X1218157Y585714D03*
X1218307Y574849D03*
X1208267Y568749D03*
X1214574D03*
X1211614Y574799D03*
Y585714D03*
X1184142Y568900D03*
X1187989Y566950D03*
X1193076Y566736D03*
X1193039Y585700D03*
X1187963Y585698D03*
X1193089Y574550D03*
X1187963Y574799D03*
X1198228Y585714D03*
Y574849D03*
X1204921Y585714D03*
Y574849D03*
X1201574Y568749D03*
X1181496Y612649D03*
X1218307D03*
X1211614Y612599D03*
X1187963D03*
X1204921Y612649D03*
X1198228D03*
X1168110D03*
X1161417D03*
X1174803Y612599D03*
X1171456Y606549D03*
X1164763D03*
Y591414D03*
X1171456D03*
X1177799Y591314D03*
X1177763Y606549D03*
X1208267Y591414D03*
X1214574Y606549D03*
X1208267D03*
X1187939Y593500D03*
X1184142Y591414D03*
X1193063Y593714D03*
X1187989Y604750D03*
X1193076Y604536D03*
X1193089Y612350D03*
X1184142Y606700D03*
X1201574Y591414D03*
Y606549D03*
X1238385Y29949D03*
Y14814D03*
X1245078Y29949D03*
Y14814D03*
X1251771Y16999D03*
X1248425Y27899D03*
X1269700Y13078D03*
X1267960Y28494D03*
X1241732Y-1751D03*
X1238385Y-7851D03*
X1241732Y9114D03*
X1248425Y-1751D03*
Y-9901D03*
X1251771D03*
X1245078Y-7851D03*
X1248425Y9157D03*
X1269800Y-5822D03*
X1235039Y9114D03*
X1224774Y9098D03*
X1224822Y-9700D03*
X1229887Y-9864D03*
X1224774Y-1801D03*
X1235039Y-1751D03*
X1229922Y-2000D03*
X1220953Y-7700D03*
X1229800Y9300D03*
X1224790Y16900D03*
X1229874Y17114D03*
X1229887Y27936D03*
X1220953Y30100D03*
X1224800Y28100D03*
X1220953Y14814D03*
X1241732Y36049D03*
Y46914D03*
X1238385Y52614D03*
Y67749D03*
X1245078Y52614D03*
X1251771Y65699D03*
X1248425D03*
Y36049D03*
Y46957D03*
X1245078Y67749D03*
X1267976Y73676D03*
X1268022Y54443D03*
X1241732Y84714D03*
Y73849D03*
X1238385Y90414D03*
X1251771Y92599D03*
X1245078Y90414D03*
X1248425Y84757D03*
Y73849D03*
X1268581Y92706D03*
X1224774Y84698D03*
X1224750Y92500D03*
X1224774Y73799D03*
X1235039Y84714D03*
Y73849D03*
X1229800Y35750D03*
X1229874Y54914D03*
X1235039Y46914D03*
Y36049D03*
X1224774Y46898D03*
X1220953Y52614D03*
X1224774Y35999D03*
X1229887Y65736D03*
X1224800Y65950D03*
X1220953Y67900D03*
X1229900Y73550D03*
X1229850Y84700D03*
X1229874Y92714D03*
X1220953Y90414D03*
X1240927Y154932D03*
X1266200Y122500D03*
X1254024Y128013D03*
X1246251Y130066D03*
X1257800Y110900D03*
X1260500Y117500D03*
X1247326Y122802D03*
X1254300Y105200D03*
X1277660Y109450D03*
X1277230Y117570D03*
X1237400Y103100D03*
X1241712Y187710D03*
X1220167Y194407D03*
X1220017Y220323D03*
X1220194Y243384D03*
X1223100Y258600D03*
X1223508Y262600D03*
X1259800Y463300D03*
X1255530Y474770D03*
X1269050Y486650D03*
X1269600Y480800D03*
X1272830Y471660D03*
X1257720Y493060D03*
X1255388Y483557D03*
X1256130Y467820D03*
X1241732Y510114D03*
X1238385Y515814D03*
X1269000Y514700D03*
X1245078Y515814D03*
X1251771Y517999D03*
X1248425Y510157D03*
X1235039Y510114D03*
X1220953Y515814D03*
X1229874Y518114D03*
X1229850Y510100D03*
X1224750Y517900D03*
X1224774Y510098D03*
X1241732Y547914D03*
Y537049D03*
X1238385Y530949D03*
Y553614D03*
X1269800Y532978D03*
X1251771Y528899D03*
X1248425Y537049D03*
Y528899D03*
X1245078Y553614D03*
Y530949D03*
X1248425Y547957D03*
X1241732Y574849D03*
Y585714D03*
X1238385Y568749D03*
X1268500Y555800D03*
X1267900Y574300D03*
X1248425Y585757D03*
Y574849D03*
Y566699D03*
X1245078Y568749D03*
X1220953Y531100D03*
X1229887Y528936D03*
X1229900Y536750D03*
X1224800Y529150D03*
X1224774Y536999D03*
X1235039Y537049D03*
Y547914D03*
X1229850Y547900D03*
X1224774Y547898D03*
X1220953Y553614D03*
X1229874Y555914D03*
X1224750Y555700D03*
X1220953Y568900D03*
X1229900Y574550D03*
X1224774Y574799D03*
X1229850Y585700D03*
X1224774Y585698D03*
X1229887Y566736D03*
X1224800Y566950D03*
X1235039Y585714D03*
Y574849D03*
X1241732Y612649D03*
X1238385Y606549D03*
Y591414D03*
X1263800Y606800D03*
X1267800Y593600D03*
X1248425Y612649D03*
X1251771Y604499D03*
X1248425D03*
X1245078Y606549D03*
X1251771Y593599D03*
X1245078Y591414D03*
X1224774Y612599D03*
X1235039Y612649D03*
X1220953Y591414D03*
X1229874Y593714D03*
X1224750Y593500D03*
X1224800Y604750D03*
X1229887Y604536D03*
X1220953Y606700D03*
X1229900Y612350D03*
X1304940Y32350D03*
X1296928Y48700D03*
X1301000Y62000D03*
X1323500Y68000D03*
X1318341Y60000D03*
X1321841Y63000D03*
X1304000Y62000D03*
X1318341Y63000D03*
X1341400Y46100D03*
X1336900Y89896D03*
X1323500Y75000D03*
Y71500D03*
X1286000Y134500D03*
Y139500D03*
Y137000D03*
X1298400Y144500D03*
X1288500Y137000D03*
Y139500D03*
Y134500D03*
X1286000Y132000D03*
X1288500D03*
X1322628Y100134D03*
X1323800Y104250D03*
X1326800D03*
Y107250D03*
X1323800D03*
X1326600Y123450D03*
X1323600D03*
X1326600Y126450D03*
X1323600D03*
X1340100Y145000D03*
X1335100Y155000D03*
Y145000D03*
X1330100Y150000D03*
X1340100D03*
Y155000D03*
X1315100Y145000D03*
X1335100Y150000D03*
X1330100Y145000D03*
Y155000D03*
Y160000D03*
X1340100D03*
X1306363Y169928D03*
X1335100Y160000D03*
X1324938Y209251D03*
X1322500D03*
X1320390Y216824D03*
X1303838Y169922D03*
X1320400Y234959D03*
X1325900D03*
X1314900D03*
X1336900D03*
X1331400D03*
X1342400D03*
X1334113Y273115D03*
X1340866Y268795D03*
X1327625Y275971D03*
X1336480Y309755D03*
X1336793Y303784D03*
X1342500Y312100D03*
X1316300Y282000D03*
X1325300Y282600D03*
X1341920Y309755D03*
X1342480Y303852D03*
X1319906Y338025D03*
X1338500Y319600D03*
X1326626Y464400D03*
X1300100Y442500D03*
X1301000Y460900D03*
X1305100Y432500D03*
X1320100Y427500D03*
Y432500D03*
X1325100Y427500D03*
Y432500D03*
X1305181Y427834D03*
X1310100Y427500D03*
Y432500D03*
X1315100Y427500D03*
Y432500D03*
X1340100Y427500D03*
X1330100Y432500D03*
Y427500D03*
X1335100Y457500D03*
Y452500D03*
Y447500D03*
Y442500D03*
X1330100D03*
X1305100D03*
X1310100D03*
X1320100D03*
X1315100D03*
X1325100D03*
X1340100Y457500D03*
Y452500D03*
Y447500D03*
Y442500D03*
X1319738Y477497D03*
X1326877Y469279D03*
X1319699Y472327D03*
X1301000Y466500D03*
X1319300Y525450D03*
X1321800D03*
X1311772Y501000D03*
X1319075D03*
X1316675Y500983D03*
X1314272Y501000D03*
X1343100Y566300D03*
X1340700D03*
X1338000D03*
X1340526Y563337D03*
X1343026D03*
X1338026D03*
X1333026D03*
X1335526D03*
Y566237D03*
X1321800Y532750D03*
X1319300Y532650D03*
X1321800Y527850D03*
X1319300D03*
Y530250D03*
X1321800D03*
X1333026Y566237D03*
X1298100Y598300D03*
Y595800D03*
Y590000D03*
Y592500D03*
X1307600Y620100D03*
X1357400Y-19800D03*
X1360400Y10600D03*
X1350654Y-18411D03*
X1348154Y-15911D03*
Y-18411D03*
X1357600Y5140D03*
X1345518Y-18476D03*
X1353154Y-18411D03*
X1375676Y7630D03*
X1385608Y-17485D03*
X1388294Y-5675D03*
X1389523Y4966D03*
X1355950Y-16507D03*
X1359450Y-7D03*
X1355950D03*
X1357489Y-1924D03*
X1359450Y2493D03*
X1355950D03*
X1357489Y-14424D03*
Y-10524D03*
Y-6124D03*
X1355889Y-8524D03*
X1355847Y-12275D03*
X1355989Y-3924D03*
X1356261Y32017D03*
X1356300Y20100D03*
X1356376Y24167D03*
X1356200Y28200D03*
X1357900Y30200D03*
X1357800Y26100D03*
X1357803Y22200D03*
X1356261Y15517D03*
X1357700Y17800D03*
X1359761Y32317D03*
X1371650Y-907D03*
X1371589Y-3424D03*
Y-5924D03*
X1371900Y28600D03*
Y26100D03*
Y31100D03*
X1369408Y50479D03*
X1375500Y76000D03*
X1397500Y51000D03*
X1365855Y46972D03*
X1359800Y37300D03*
X1357300D03*
X1344000Y83000D03*
X1402700Y51100D03*
X1381817Y46484D03*
X1388627Y35032D03*
X1380500Y54500D03*
X1380900Y59820D03*
X1372400Y37785D03*
X1389138Y58499D03*
X1370100Y82500D03*
X1366100D03*
X1364700Y86550D03*
X1389068Y78556D03*
X1389100Y74600D03*
X1350830Y60730D03*
X1356261Y34517D03*
X1356950Y54370D03*
X1356760Y66660D03*
X1357000Y60500D03*
X1359761Y34817D03*
X1350800Y66600D03*
X1351190Y54710D03*
X1363170Y54280D03*
X1362900Y60500D03*
X1363040Y66660D03*
X1380500Y50500D03*
X1356230Y126500D03*
X1359230D03*
X1360730Y129000D03*
X1362230Y126500D03*
X1355100Y155000D03*
Y145000D03*
Y150000D03*
X1360100Y155000D03*
Y145000D03*
Y150000D03*
X1345100D03*
X1350100Y155000D03*
Y150000D03*
Y145000D03*
X1345100D03*
Y155000D03*
X1397994Y103350D03*
X1397952Y105998D03*
X1395326Y100913D03*
Y103413D03*
X1395347Y106040D03*
X1386700Y125450D03*
Y128450D03*
X1383700Y125450D03*
Y128450D03*
X1380700Y125450D03*
Y128450D03*
X1376100Y116100D03*
X1376669Y121763D03*
Y118763D03*
X1376100Y124950D03*
X1373850Y114450D03*
X1369730Y129000D03*
X1363730D03*
X1366730D03*
X1373850Y117450D03*
X1368230Y126500D03*
X1373850Y123450D03*
X1365230Y126500D03*
X1397193Y112602D03*
X1394253Y116989D03*
X1385100Y155000D03*
X1375100D03*
X1365100D03*
X1380100D03*
Y145000D03*
X1385100D03*
X1380100Y150000D03*
X1385100D03*
X1365100Y145000D03*
Y150000D03*
X1375100D03*
X1370100Y155000D03*
Y145000D03*
X1375100D03*
X1370100Y150000D03*
X1352200Y104950D03*
Y108400D03*
X1357700D03*
Y104950D03*
X1373850Y120450D03*
X1380100Y160000D03*
X1360100D03*
X1355100D03*
X1345100D03*
X1350100D03*
X1390100D03*
X1370100D03*
X1390100Y170000D03*
X1385100Y160000D03*
Y165000D03*
Y170000D03*
X1365100Y160000D03*
X1375100D03*
X1390100Y165000D03*
X1383753Y265548D03*
X1397400Y234959D03*
X1391900D03*
X1386400D03*
X1358900D03*
X1353400D03*
X1347900D03*
X1349500Y265500D03*
X1359100Y265600D03*
X1380900Y234959D03*
X1369900D03*
X1364400D03*
X1375400Y235100D03*
X1369100Y265500D03*
X1374864Y265629D03*
X1398062Y315743D03*
X1403100Y321350D03*
X1383639Y315274D03*
X1389600Y315200D03*
X1384024Y320225D03*
X1386048Y310310D03*
X1386265Y304310D03*
X1389600Y320100D03*
X1397640Y310631D03*
X1397880Y304640D03*
X1392380D03*
X1392340Y310625D03*
X1403260Y310623D03*
X1403300Y304640D03*
X1388208Y341489D03*
X1348080Y309825D03*
X1353142Y309761D03*
X1358792Y309760D03*
X1358800Y303700D03*
X1353359Y303767D03*
X1348190Y303810D03*
X1346550Y322350D03*
X1350650Y315050D03*
X1357452Y319395D03*
X1369540Y310125D03*
X1374900Y310130D03*
X1381100Y304360D03*
X1380910Y310300D03*
X1364044Y309691D03*
X1364213Y303694D03*
X1375040Y304135D03*
X1369540D03*
X1371000Y322400D03*
X1363059Y314514D03*
X1368947Y313993D03*
X1358500Y338400D03*
X1370200D03*
X1364300Y338300D03*
X1392144Y364617D03*
X1389450Y372250D03*
X1384700Y359700D03*
X1392500Y344600D03*
X1392805Y360466D03*
X1388500Y350864D03*
X1391200Y386300D03*
X1384531Y382957D03*
X1394760Y394720D03*
X1362510Y360717D03*
X1354024Y398985D03*
X1352338Y404153D03*
X1351379Y399227D03*
X1352239Y401593D03*
X1358512Y371792D03*
X1360450Y402100D03*
X1359360Y398810D03*
X1357880Y403760D03*
X1356560Y398910D03*
X1362250Y399160D03*
X1354681Y401444D03*
X1354982Y404154D03*
X1357542Y401381D03*
X1364856Y366666D03*
X1382017Y367584D03*
X1363250Y401700D03*
X1371200Y402100D03*
X1381500Y396200D03*
X1375201Y396303D03*
X1365731Y360698D03*
X1358500Y374500D03*
X1360200Y377400D03*
X1358655Y379352D03*
X1362068Y393385D03*
X1360300Y381100D03*
X1360200Y384700D03*
Y389000D03*
X1358700Y386700D03*
X1358568Y390885D03*
Y393385D03*
X1358600Y382800D03*
X1362068Y390885D03*
X1374268Y389985D03*
X1374207Y384968D03*
Y387468D03*
X1370300Y350200D03*
X1358300Y344200D03*
X1358400Y350100D03*
X1370200Y343900D03*
X1364100Y350200D03*
X1385416Y410502D03*
X1404558Y416575D03*
X1402725Y408136D03*
X1402520Y413246D03*
X1388085Y410479D03*
X1403998Y429775D03*
X1404558Y421575D03*
X1398275Y453561D03*
X1397975Y457561D03*
X1403998Y434775D03*
X1382849Y410471D03*
X1380449Y410479D03*
X1358990Y411040D03*
X1358910Y408480D03*
X1358980Y406060D03*
X1355100Y427500D03*
Y432500D03*
X1361558Y410527D03*
X1345100Y442500D03*
X1350100D03*
X1345100Y437500D03*
X1350100D03*
X1355100D03*
Y442500D03*
X1369034Y458075D03*
X1369907Y410513D03*
X1372535Y410512D03*
X1375239Y410590D03*
X1377928Y410451D03*
X1366984Y410481D03*
X1364403Y410496D03*
X1380100Y447500D03*
X1370100Y442500D03*
X1365100Y452500D03*
X1379857Y458108D03*
X1365100Y442500D03*
X1375100D03*
X1380100Y452500D03*
X1365100Y447500D03*
X1388900Y525230D03*
X1395581Y525357D03*
X1383600Y482504D03*
X1386041Y493723D03*
X1383519Y487445D03*
X1390330Y516690D03*
X1385033Y516848D03*
X1387568Y516892D03*
X1388865Y519788D03*
X1388850Y522266D03*
X1386033Y498811D03*
X1344073Y508263D03*
X1363800Y481600D03*
X1363662Y486636D03*
X1365741Y492723D03*
X1382578Y516805D03*
X1377492Y516892D03*
X1369757Y517465D03*
X1365719Y497545D03*
X1352490Y515470D03*
X1346870Y515450D03*
X1352590Y519170D03*
X1346970Y519150D03*
X1401777Y557632D03*
X1385033Y544267D03*
X1390623Y574986D03*
X1400830Y564090D03*
X1400288Y570099D03*
X1404420Y576330D03*
X1404519Y560280D03*
Y557380D03*
X1361600Y559400D03*
X1358529Y537492D03*
X1361163Y540052D03*
X1358518Y540073D03*
X1356018D03*
X1356029Y537492D03*
X1363674Y537471D03*
X1355548Y559959D03*
X1361926Y584037D03*
Y586537D03*
X1359100Y586200D03*
X1357400Y588400D03*
X1360100D03*
X1344613Y556376D03*
Y561376D03*
Y558876D03*
X1347700Y554100D03*
X1353520Y537480D03*
X1344613Y553876D03*
X1361174Y537471D03*
X1358439Y559959D03*
X1375479Y540117D03*
X1375500Y537717D03*
X1366265Y537437D03*
X1363663Y540052D03*
X1363568Y550589D03*
X1380521Y535276D03*
X1378021D03*
X1375621Y535254D03*
X1371265Y537437D03*
X1368765D03*
X1366459Y550589D03*
X1377979Y537717D03*
Y540117D03*
X1380479Y537717D03*
X1368596Y539889D03*
X1371096D03*
X1366096D03*
X1380479Y540117D03*
X1376800Y584328D03*
X1364426Y586637D03*
Y584137D03*
X1360500Y570900D03*
Y574700D03*
X1360261Y578873D03*
X1360247Y567390D03*
X1360261Y562373D03*
Y581373D03*
X1362000Y576700D03*
Y572800D03*
X1362100Y569100D03*
X1362000Y565600D03*
X1363761Y581373D03*
X1375961Y577973D03*
X1376000Y575456D03*
Y572956D03*
X1387050Y615350D03*
X1392500Y592000D03*
X1376556Y615756D03*
X1357726Y591037D03*
X1360226D03*
X1363761Y612573D03*
X1360261D03*
X1360200Y597800D03*
X1361600Y599900D03*
X1361500Y595700D03*
X1360100Y610100D03*
X1360200Y606300D03*
Y602000D03*
X1361900Y608200D03*
X1361500Y604200D03*
X1360261Y593573D03*
X1363761Y610073D03*
X1375961Y609173D03*
X1375900Y604156D03*
Y606656D03*
X1454715Y2784D03*
X1450508Y2756D03*
X1410571Y13170D03*
X1420019Y13466D03*
X1448367Y13533D03*
X1438918D03*
X1429469Y13466D03*
X1457814D03*
X1436131Y5248D03*
X1432661Y5220D03*
X1406674Y46120D03*
X1411254Y46018D03*
X1412250Y65359D03*
X1407150Y58859D03*
X1410150D03*
X1407150Y52859D03*
X1410150D03*
X1409250Y65359D03*
X1407150Y55859D03*
X1410150D03*
X1413721Y36749D03*
X1412250Y68359D03*
X1409250D03*
X1409150Y71259D03*
X1412150D03*
X1442067Y34830D03*
X1423170Y36635D03*
X1432619Y34830D03*
X1451516D03*
X1460965D03*
X1452648Y103788D03*
X1451273Y148905D03*
X1449847Y202322D03*
X1439000Y208500D03*
X1442251Y180818D03*
X1418300Y199900D03*
X1440150Y175550D03*
X1440124Y166180D03*
X1451427Y167818D03*
X1434800Y248900D03*
X1462700Y221700D03*
X1464200Y231400D03*
X1458800Y254882D03*
X1410800Y316100D03*
X1408580Y310632D03*
X1408760Y304637D03*
X1410550Y320800D03*
X1419343Y310652D03*
X1419283Y304570D03*
X1413983Y304645D03*
X1413943Y310628D03*
X1417656Y367547D03*
X1420101Y396236D03*
X1418138Y386361D03*
X1415000Y399000D03*
X1412220Y388360D03*
X1417217Y379129D03*
X1417349Y382137D03*
X1417773Y374107D03*
X1464124Y353776D03*
X1465500Y395400D03*
X1456750Y381850D03*
X1459033Y395334D03*
X1446700Y387900D03*
X1437897Y402315D03*
X1443100Y368950D03*
X1439934Y403730D03*
X1411900Y429775D03*
X1405375Y453561D03*
X1405608Y456761D03*
X1411900Y434775D03*
X1435479Y423107D03*
X1439350Y406900D03*
X1459200Y459800D03*
Y454100D03*
X1459000Y449997D03*
X1451400Y454100D03*
Y459800D03*
X1445000Y437000D03*
X1429000Y437059D03*
X1444800Y442500D03*
X1444500Y448000D03*
X1429100Y453400D03*
X1429000Y448000D03*
Y442600D03*
X1448800Y427800D03*
X1412447Y416368D03*
X1412545Y421974D03*
X1413300Y454400D03*
X1413075Y457561D03*
X1448800Y416500D03*
X1464300Y404900D03*
X1439000Y423000D03*
X1464600Y428000D03*
X1459300Y430000D03*
X1464525Y420014D03*
X1464731Y432942D03*
X1445100Y431500D03*
X1459200Y465500D03*
X1451400D03*
X1408753Y527518D03*
X1415541Y489523D03*
X1416100Y483500D03*
X1415800Y477500D03*
Y495200D03*
X1420200Y520500D03*
X1447749Y485395D03*
X1439314Y477723D03*
X1439400Y483600D03*
X1439341Y489323D03*
X1453700Y501600D03*
X1458357Y523271D03*
X1461100Y523600D03*
X1439400Y494700D03*
X1409693Y560343D03*
X1412093D03*
X1410850Y564210D03*
X1410340Y570370D03*
X1407019Y557380D03*
X1412019D03*
X1409519D03*
X1406993Y560343D03*
X1447852Y575687D03*
X1445800Y574300D03*
X1445750Y539000D03*
X1461500Y540000D03*
X1439861Y540497D03*
X1461653Y580762D03*
X1461707Y583162D03*
X1461878Y585556D03*
X1441805Y570887D03*
X1443797Y572482D03*
X1422500Y579800D03*
X1414800D03*
X1461930Y587956D03*
X1409500Y538000D03*
X1420500Y549800D03*
X1420400Y538000D03*
X1462039Y590354D03*
X1462155Y592761D03*
X1465334Y618564D03*
X1451314Y623298D03*
X1458000Y623400D03*
X1455000D03*
X1461000D03*
X1442200D03*
X1445200D03*
X1448200D03*
X1463419Y606912D03*
X1527700Y6963D03*
X1506900Y3500D03*
X1469807Y2967D03*
X1473674Y2953D03*
X1476712Y13466D03*
X1467264Y13533D03*
X1492900Y4000D03*
X1489600D03*
X1495611Y13466D03*
X1486162Y13500D03*
X1470414Y34830D03*
X1479863D03*
X1497711Y34427D03*
X1489311Y34830D03*
X1499613Y84046D03*
X1515294Y91306D03*
X1523563Y93565D03*
X1511700Y84600D03*
X1482300Y118400D03*
X1469747Y148276D03*
X1483093Y130796D03*
X1523950Y104050D03*
X1523889Y99033D03*
X1523557Y116165D03*
X1523813Y120546D03*
X1523756Y108762D03*
X1501603Y108500D03*
X1499618Y124520D03*
X1497699Y112140D03*
X1511634Y121195D03*
X1511635Y114535D03*
X1511650Y109400D03*
Y103400D03*
X1511651Y98675D03*
X1500775Y98101D03*
X1501700Y103300D03*
X1513023Y140630D03*
X1511664Y133603D03*
X1488350Y149450D03*
X1523719Y149488D03*
X1499800Y199300D03*
X1491196Y218527D03*
X1523400Y217900D03*
X1483523Y181100D03*
X1517328Y186208D03*
X1527500Y167726D03*
X1502192Y164871D03*
X1494783Y177907D03*
X1469150Y242931D03*
X1479500Y238500D03*
X1498685Y224715D03*
X1491700Y241661D03*
X1491407Y258353D03*
X1523470Y242580D03*
X1472500Y341074D03*
X1526722Y295400D03*
X1501583Y339389D03*
X1521817Y330937D03*
X1526000Y341000D03*
X1517600Y320940D03*
X1487426Y330100D03*
X1514722Y293257D03*
X1515482Y280800D03*
X1512300Y280847D03*
X1511900Y287500D03*
X1472550Y397500D03*
X1470800Y402250D03*
X1472680Y380630D03*
X1483172Y351806D03*
X1474500Y365500D03*
X1478500D03*
X1483500D03*
X1482000Y395098D03*
Y399035D03*
Y383287D03*
Y387224D03*
X1473255Y376254D03*
X1528146Y349842D03*
X1519626Y365817D03*
X1488394Y365466D03*
X1497275Y401174D03*
X1508975D03*
X1483950Y401650D03*
X1491425Y391034D03*
X1503125Y377514D03*
X1491425D03*
X1526525D03*
X1514825D03*
X1526525Y384274D03*
Y391034D03*
X1514825Y384274D03*
X1520675Y387654D03*
Y380894D03*
X1514825Y391034D03*
X1508975Y387654D03*
Y380894D03*
X1503125Y384274D03*
Y391034D03*
X1497275Y380894D03*
X1491425Y384274D03*
X1497275Y387654D03*
Y394414D03*
X1491425Y397794D03*
X1503125D03*
X1508975Y394414D03*
X1514825Y397794D03*
X1524575Y401174D03*
X1491425Y418074D03*
X1487525D03*
X1472449Y439421D03*
X1467000Y454100D03*
Y459800D03*
X1466800Y449997D03*
X1467401Y411557D03*
X1471900Y406900D03*
X1472530Y432731D03*
X1472400Y428063D03*
X1472800Y420689D03*
X1467000Y465500D03*
X1482000Y418720D03*
Y406909D03*
Y410846D03*
Y414783D03*
Y422658D03*
Y426595D03*
X1483400Y438100D03*
X1482603Y442418D03*
X1482000Y462028D03*
X1483115Y454379D03*
X1483200Y450455D03*
X1482500Y434600D03*
X1503125Y404554D03*
X1509200Y413600D03*
X1510925Y404554D03*
X1497275Y414694D03*
X1503125Y424834D03*
X1497275Y428214D03*
X1495325Y424834D03*
X1503125Y433406D03*
X1491425D03*
X1495325D03*
X1524950Y419900D03*
X1518650D03*
X1483818Y430597D03*
X1528100Y410550D03*
X1501219Y416596D03*
X1487525Y404554D03*
X1526525D03*
X1515500Y416750D03*
X1518700Y406500D03*
X1491425Y404554D03*
X1495325Y411314D03*
X1512350Y445100D03*
X1509200D03*
Y454550D03*
X1512400Y454500D03*
X1503125Y440166D03*
X1501175Y436786D03*
X1495325Y440166D03*
X1497275Y436786D03*
X1510925Y460446D03*
X1505442Y443900D03*
X1507025Y460446D03*
X1503125Y453786D03*
Y460446D03*
X1501175Y457066D03*
X1487525Y453686D03*
X1497275Y457066D03*
Y450306D03*
X1495325Y446926D03*
Y453686D03*
X1497275Y443546D03*
X1501175Y463826D03*
X1493375D03*
X1515500Y445100D03*
X1514825Y460446D03*
X1520675Y457066D03*
X1518725Y460446D03*
X1521800Y441950D03*
Y448250D03*
X1526525Y460446D03*
X1522625D03*
X1524950Y441950D03*
X1473140Y525407D03*
X1482000Y481713D03*
Y469902D03*
X1476800Y498900D03*
X1482300D03*
X1476800Y507300D03*
X1481700Y524200D03*
X1473800Y495800D03*
X1499225Y480726D03*
X1508975Y477346D03*
X1510925Y480726D03*
X1508975Y470586D03*
X1510925Y473966D03*
X1505075Y470586D03*
X1501175D03*
X1503125Y467206D03*
X1507025Y487486D03*
X1487525Y473966D03*
X1491425D03*
X1489475Y470586D03*
X1490100Y489700D03*
X1487525Y487486D03*
X1489475Y484106D03*
X1516775D03*
X1514825Y480726D03*
Y473966D03*
X1516775Y470586D03*
X1518725Y487486D03*
Y480726D03*
Y473966D03*
Y467206D03*
X1522625D03*
Y473966D03*
Y487486D03*
X1526525D03*
Y473966D03*
Y467206D03*
X1514825Y487486D03*
X1511752Y498780D03*
X1490929Y507104D03*
X1506060Y508180D03*
X1501490Y504988D03*
X1501934Y513047D03*
X1505743Y516117D03*
X1511215Y507781D03*
X1512400Y519020D03*
X1493930Y522800D03*
X1488410Y517810D03*
X1497267Y505323D03*
X1496174Y514221D03*
X1509000Y498750D03*
X1488500Y498900D03*
X1526500Y498671D03*
Y506400D03*
X1485300Y498962D03*
X1483804Y509928D03*
X1484200Y524200D03*
X1475316Y527194D03*
X1468101Y573963D03*
X1527698Y578870D03*
X1474776Y572315D03*
X1491776Y573571D03*
X1479893Y572315D03*
X1482293D03*
X1477493D03*
X1487093D03*
X1489493D03*
X1484693D03*
X1518000Y562330D03*
X1510740Y557860D03*
X1494422Y574000D03*
X1481400Y539700D03*
X1494200Y530600D03*
X1497106Y531368D03*
X1511388Y531045D03*
X1503200Y530500D03*
X1505600D03*
X1508772Y530416D03*
X1514118Y530411D03*
X1483900Y539700D03*
X1525500Y582674D03*
Y580184D03*
X1525837Y574700D03*
X1523416Y573949D03*
X1527822Y576130D03*
X1525500Y577684D03*
X1499900Y574000D03*
X1496900D03*
X1469701Y599554D03*
X1470353Y592128D03*
X1469767Y596353D03*
X1503008Y620018D03*
X1472412Y596032D03*
Y599532D03*
X1479029Y596132D03*
X1477129Y597656D03*
X1474912Y596032D03*
X1480760Y611602D03*
X1485429Y597571D03*
X1491412Y596032D03*
X1489229Y597571D03*
X1487329Y596032D03*
X1512500Y598639D03*
X1510450Y597300D03*
X1507950D03*
X1510450Y600800D03*
X1508031Y599922D03*
X1524800Y598778D03*
X1522900Y597300D03*
X1526950D03*
X1518800Y597200D03*
X1520813Y598508D03*
X1516800Y598639D03*
X1514500Y597300D03*
X1511350Y613000D03*
X1513867Y612939D03*
X1516367D03*
X1475812Y611732D03*
X1474912Y599532D03*
X1478329Y611671D03*
X1483104Y596072D03*
X1481229Y597571D03*
X1584447Y-6702D03*
X1579447D03*
X1570200Y12900D03*
X1579773Y13257D03*
X1589259Y10241D03*
X1541400Y12500D03*
X1528384Y28040D03*
X1551309Y12792D03*
X1560700Y13000D03*
X1589500Y-600D03*
X1589900Y84422D03*
X1583621Y87213D03*
X1588700Y94288D03*
X1573473Y37216D03*
X1582923D03*
X1532800Y78590D03*
X1542179Y39695D03*
X1554573Y37216D03*
X1564023D03*
X1578000Y113000D03*
X1585500Y101000D03*
X1555000Y139000D03*
X1548955Y101358D03*
X1558189Y107067D03*
X1554800Y129100D03*
Y98200D03*
X1558100D03*
X1558383Y121500D03*
X1554945Y133400D03*
X1583600Y207495D03*
X1535399Y190920D03*
X1533132Y158068D03*
X1531565Y176645D03*
X1537298Y162703D03*
X1557634Y175948D03*
X1562079Y163580D03*
X1530200Y257200D03*
X1528460Y244371D03*
X1563440Y250955D03*
X1559577Y236300D03*
X1547000Y263500D03*
Y269400D03*
X1541000Y263500D03*
Y269500D03*
X1544000Y266500D03*
X1578630Y293430D03*
X1580150Y329483D03*
X1528250Y311900D03*
X1530033Y340799D03*
X1539400Y320200D03*
X1544904Y334008D03*
X1557250Y315410D03*
X1554800Y290600D03*
X1586400Y392900D03*
X1567475Y380894D03*
Y387654D03*
X1582420Y377830D03*
X1582350Y374567D03*
X1582124Y381164D03*
X1573000Y391161D03*
X1571366Y401154D03*
X1582000Y396250D03*
X1567475Y394414D03*
X1570672Y362134D03*
X1567121Y365817D03*
X1576380Y362890D03*
X1582500Y369600D03*
X1573521Y365500D03*
X1532375Y380894D03*
Y387654D03*
Y394414D03*
X1538225Y377514D03*
Y384274D03*
X1544075Y380894D03*
Y387654D03*
X1538225Y391034D03*
Y397794D03*
X1544075Y394414D03*
X1558996Y365817D03*
X1555775Y394414D03*
X1549925Y397794D03*
X1561625D03*
X1555775Y401174D03*
X1549925Y377514D03*
X1561625D03*
Y391034D03*
Y384274D03*
X1549925Y391034D03*
Y384274D03*
X1555775Y387654D03*
Y380894D03*
X1571375Y421454D03*
X1569425Y418074D03*
X1571375Y414694D03*
X1559675Y463826D03*
X1563575Y421454D03*
X1557725Y424834D03*
X1567475Y450306D03*
X1565525Y440166D03*
X1571375Y457066D03*
X1567475D03*
X1569425Y460446D03*
X1582200Y456200D03*
X1565525Y431594D03*
X1569425D03*
Y404554D03*
X1583208Y412815D03*
X1569425Y411314D03*
X1571390Y464480D03*
X1567475Y421454D03*
X1531250Y419900D03*
Y451400D03*
Y441950D03*
X1530425Y460446D03*
X1551875Y407934D03*
Y414694D03*
X1563575Y407934D03*
X1559675Y414694D03*
X1546025Y404554D03*
X1561625Y424834D03*
X1551990Y421158D03*
X1551875Y428214D03*
X1561625Y431594D03*
X1563575Y428214D03*
X1555775Y443546D03*
Y436786D03*
X1563575Y457066D03*
X1549938Y453714D03*
X1547975Y457066D03*
X1549925Y446926D03*
X1557725D03*
X1561625Y460446D03*
X1555775Y457066D03*
X1551875D03*
X1557725Y453686D03*
X1559675Y443546D03*
Y436786D03*
X1547975Y463826D03*
X1551875D03*
X1555775D03*
X1534400Y419900D03*
X1540700D03*
X1543850Y429350D03*
Y426200D03*
X1537550Y419900D03*
X1534325Y404554D03*
X1538225D03*
X1542125D03*
X1540700Y410450D03*
X1534400Y451400D03*
Y441950D03*
X1537550D03*
X1534325Y460446D03*
X1537550Y451400D03*
X1544075Y457066D03*
X1540175D03*
X1540700Y451400D03*
Y441950D03*
X1540175Y463826D03*
X1543850Y435650D03*
X1537550D03*
X1582644Y495077D03*
X1568600Y494500D03*
X1565210Y509160D03*
X1567817Y499735D03*
X1569425Y473966D03*
X1571375Y470586D03*
X1565525Y480726D03*
X1570062Y487039D03*
X1587970Y472370D03*
X1587433Y490425D03*
X1567475Y470586D03*
X1532375D03*
X1530425Y473966D03*
X1528475Y470586D03*
Y477346D03*
X1534180Y498580D03*
X1534039Y502906D03*
X1531580Y510790D03*
X1534325Y487486D03*
X1536275Y484106D03*
X1544075Y470586D03*
X1542125Y473966D03*
X1540175Y477346D03*
X1536275Y470586D03*
X1544075Y477346D03*
X1538225Y473966D03*
X1542475Y504400D03*
X1542425Y512200D03*
X1546025Y467206D03*
X1553825Y487486D03*
Y480726D03*
X1557725D03*
X1549925Y473966D03*
X1547975Y470586D03*
X1553825Y473966D03*
Y467206D03*
X1555775Y470586D03*
X1557725Y473966D03*
X1555775Y477346D03*
Y484106D03*
X1549925Y487486D03*
X1546025Y480726D03*
X1548300Y499000D03*
X1564600Y500414D03*
X1555424Y504609D03*
X1555832Y512288D03*
X1548300Y506600D03*
X1580360Y565524D03*
X1580400Y568000D03*
X1580300Y563000D03*
Y560500D03*
X1566000Y575820D03*
X1565940Y573120D03*
X1565800Y570600D03*
X1565600Y568100D03*
Y565700D03*
X1529944Y574725D03*
X1529894Y577342D03*
X1532354Y577283D03*
X1532642Y579853D03*
X1529600Y582300D03*
X1532400D03*
X1529942Y579853D03*
X1563800Y564100D03*
X1561300Y564000D03*
X1558800Y563900D03*
X1563448Y566766D03*
X1563432Y569340D03*
X1589604Y585896D03*
X1581704D03*
X1587504Y605496D03*
Y607996D03*
X1563827Y621376D03*
X1554800Y620910D03*
X1537711Y613397D03*
X1538679Y615641D03*
X1534928Y610532D03*
X1538337Y601097D03*
X1534948Y613302D03*
X1545000Y591100D03*
X1581704Y590196D03*
X1589604D03*
X1558800Y599300D03*
X1560400Y611600D03*
X1564300Y599400D03*
X1564400Y605500D03*
X1561700Y602200D03*
X1552400Y607600D03*
X1554900Y607100D03*
X1556200Y602400D03*
X1554400Y599300D03*
X1564300Y611500D03*
X1602504Y-17346D03*
X1646200Y5300D03*
X1646400Y13400D03*
X1597700Y9000D03*
X1615000Y12000D03*
X1634200Y9700D03*
X1627500Y11700D03*
X1608123Y13302D03*
X1619100Y6500D03*
X1626400Y4600D03*
X1606700D03*
X1636500D03*
X1591270Y93940D03*
X1592200Y37700D03*
X1590464Y77962D03*
X1637700Y67400D03*
X1639623Y38100D03*
X1649073Y38200D03*
X1620050Y35550D03*
X1608500Y72688D03*
X1606730Y84230D03*
X1632000Y83000D03*
X1625451Y84288D03*
X1605184Y61044D03*
X1610450Y37300D03*
X1627380Y36652D03*
X1630121Y37609D03*
X1595943Y71522D03*
X1603138Y65890D03*
X1602840Y37382D03*
X1635900Y83000D03*
X1595335Y98135D03*
X1641600Y96500D03*
X1638500D03*
X1595522Y127278D03*
X1650300Y195251D03*
X1648400Y214100D03*
X1643887Y181841D03*
X1604401Y213500D03*
X1618500Y181680D03*
X1625524Y184531D03*
X1635100Y182800D03*
X1620036Y196186D03*
X1635112Y195181D03*
X1605250Y197250D03*
X1591174Y225017D03*
X1640871Y235210D03*
X1608489Y252095D03*
X1635503Y340146D03*
X1629503D03*
X1603307Y393224D03*
X1591912Y391052D03*
X1650624Y357884D03*
X1650480Y368215D03*
X1642126Y357894D03*
X1642114Y368142D03*
X1601060Y401010D03*
X1599100Y399100D03*
X1610828Y381387D03*
X1596151D03*
X1596168Y375135D03*
X1609761Y372584D03*
X1613474Y391105D03*
X1620447Y373926D03*
X1610642Y375135D03*
X1608020Y356500D03*
X1619889Y352841D03*
X1607443Y398649D03*
X1629503Y346146D03*
X1635503Y346046D03*
X1632503Y343146D03*
X1621010Y435870D03*
X1620500Y463727D03*
X1634500Y418500D03*
X1603650Y415469D03*
X1646540Y441240D03*
X1604200Y464387D03*
X1594880Y494880D03*
X1646700Y480300D03*
X1639394Y507798D03*
X1627032Y510226D03*
X1627068Y512626D03*
X1606200Y487100D03*
X1623814Y471400D03*
X1614000Y469500D03*
X1617700Y489700D03*
X1615200D03*
X1611506Y474768D03*
X1620500Y475000D03*
X1603500Y495300D03*
X1597178Y472226D03*
X1599900Y487100D03*
X1603802Y487205D03*
X1629530Y496374D03*
X1644800Y532800D03*
X1636848Y533794D03*
X1649900Y583500D03*
X1638674Y556178D03*
X1622040Y554827D03*
X1609829Y556599D03*
X1624293Y561747D03*
X1615030Y584260D03*
X1610080Y561367D03*
X1603060Y582920D03*
X1603120Y578020D03*
X1599170Y572780D03*
X1602000Y565700D03*
X1590004Y605496D03*
Y607996D03*
X1601504Y591526D03*
X1613721Y592325D03*
X1614700Y597000D03*
X1615862Y605507D03*
X1601489Y602812D03*
X1601270Y597200D03*
X1602150Y610720D03*
X1654800Y13518D03*
X1711863Y13276D03*
X1672427Y9700D03*
X1664200Y5400D03*
X1656600Y6300D03*
X1664823Y13287D03*
X1685500Y3000D03*
X1682985Y2901D03*
X1675800Y4100D03*
X1702421Y13231D03*
X1684902Y13472D03*
X1691541Y13226D03*
X1700710Y73292D03*
X1700300Y94703D03*
X1672000Y51500D03*
X1669350Y69962D03*
X1709600Y45800D03*
X1692573Y85833D03*
X1702513Y79885D03*
X1668009Y37000D03*
X1706500D03*
X1678000D03*
X1687500D03*
X1696795Y38260D03*
X1658559Y37890D03*
X1659038Y95111D03*
X1659000Y85500D03*
X1670250Y87873D03*
X1674455Y169991D03*
X1677605Y169986D03*
X1687950Y186150D03*
X1708250Y164950D03*
X1671556Y208379D03*
X1657498Y277300D03*
Y267100D03*
X1657949Y257240D03*
X1653091Y331618D03*
X1652991Y318741D03*
Y323941D03*
X1657500Y287800D03*
X1657600Y304500D03*
X1681192Y454286D03*
X1668000Y416200D03*
X1695658Y486945D03*
X1694410Y499830D03*
X1692120Y501410D03*
X1699900Y512300D03*
X1709400Y513000D03*
X1652500Y575600D03*
X1667277Y535221D03*
X1698600Y584800D03*
X1664113Y548380D03*
X1658466D03*
X1661880Y583900D03*
X1686036Y548251D03*
X1677300Y550200D03*
X1680007Y547917D03*
X1669121Y547923D03*
X1708140Y547538D03*
X1697839Y545759D03*
X1709183Y588700D03*
X1654100Y615790D03*
X1653970Y607340D03*
X1652700Y591300D03*
Y600850D03*
X1662580Y593200D03*
X1661200Y601300D03*
Y607300D03*
X1730550Y21160D03*
X1721559Y13500D03*
X1730768Y13313D03*
X1763100Y21500D03*
X1768807Y21512D03*
X1753903Y22116D03*
X1749941Y21163D03*
X1741000Y21200D03*
X1715259Y35602D03*
X1715100Y46100D03*
X1713550Y56000D03*
X1716900Y87900D03*
X1753059Y35300D03*
X1735150Y60650D03*
X1748500Y79500D03*
X1748854Y58533D03*
X1717600Y46100D03*
X1724758Y38600D03*
X1720600Y70200D03*
X1733910Y38233D03*
X1757054Y66059D03*
X1758100Y37000D03*
X1749364Y38971D03*
X1743500Y39300D03*
X1768450Y77376D03*
X1765900Y83700D03*
X1754703Y84053D03*
X1771459Y52695D03*
X1733900Y92200D03*
X1754600Y109200D03*
X1767250Y99500D03*
Y104500D03*
X1770850Y109500D03*
X1714189Y159550D03*
X1714528Y190189D03*
X1758650Y158650D03*
X1750189Y159550D03*
X1745689D03*
X1741189D03*
X1727689D03*
X1723189D03*
X1718689D03*
X1732189D03*
X1736689D03*
X1745777Y179574D03*
X1751975Y179374D03*
X1739377D03*
X1733178Y179574D03*
X1758375D03*
X1764673Y179374D03*
X1770973Y179574D03*
X1726700Y179400D03*
X1740900Y198800D03*
X1744000D03*
X1769100Y209700D03*
X1765950Y209600D03*
X1769016Y198872D03*
X1765866Y198772D03*
X1731260Y209600D03*
X1740709D03*
X1756000Y210000D03*
X1753400Y209900D03*
X1743900Y209700D03*
X1728616Y198872D03*
X1753311Y198700D03*
X1756600Y198800D03*
X1731216Y198872D03*
X1763554Y237712D03*
X1762795Y232106D03*
X1772244D03*
X1752554Y237712D03*
X1771451D03*
X1724944Y250324D03*
X1727444D03*
X1771243Y250100D03*
X1729944Y250324D03*
X1768516Y249983D03*
X1744603Y232489D03*
X1753347Y232106D03*
X1763300Y250100D03*
X1766100Y447900D03*
X1762992Y447938D03*
X1740963Y448476D03*
X1753543Y448100D03*
X1750393Y448037D03*
X1737795Y448100D03*
X1722000Y513000D03*
X1742900Y485000D03*
X1734000Y488100D03*
X1755000Y485000D03*
X1748600D03*
X1749396Y493969D03*
X1751868Y494045D03*
X1770325Y490255D03*
X1773500Y472100D03*
X1767300Y472700D03*
X1765325Y490255D03*
X1758500Y493800D03*
X1760900Y472800D03*
X1772459Y467005D03*
X1769309D03*
X1759860D03*
X1756710D03*
X1747262D03*
X1744112D03*
X1734663D03*
X1729200Y519000D03*
X1733830Y502650D03*
X1768900Y521124D03*
X1749090Y513790D03*
X1740400Y496300D03*
X1726600Y519000D03*
X1728700Y502600D03*
X1713600Y513000D03*
X1756417Y563840D03*
X1746000Y574000D03*
X1718000Y587723D03*
X1749000Y552863D03*
X1769000Y576378D03*
X1742381Y585530D03*
X1730814Y568814D03*
X1733000Y560000D03*
X1767455Y571695D03*
X1767000Y563500D03*
X1728245Y585244D03*
X1746052Y614796D03*
X1724092Y618700D03*
X1772158Y610960D03*
X1750739Y618718D03*
X1742509Y595869D03*
X1742381Y591530D03*
X1763500Y599100D03*
X1727843Y597142D03*
X1732443Y592342D03*
Y597142D03*
X1727743Y592342D03*
X1832449Y-8950D03*
X1785612Y10729D03*
X1782371Y26832D03*
X1804508Y11858D03*
X1798676Y11726D03*
X1830344Y13397D03*
X1828824Y3699D03*
X1816693Y13331D03*
X1819800Y35500D03*
X1790700Y34900D03*
X1799774Y34890D03*
X1808444Y37152D03*
X1800000Y80000D03*
X1827000Y87000D03*
X1834300Y41100D03*
X1788200Y93000D03*
Y89000D03*
Y85000D03*
X1818383Y133277D03*
X1788448Y98820D03*
X1788648Y101490D03*
X1807745Y104500D03*
X1803400Y114000D03*
X1796059Y104402D03*
X1801366Y151937D03*
X1811348Y143448D03*
X1800264Y143789D03*
X1800000Y132627D03*
X1820648Y155537D03*
X1816348D03*
X1777172Y179374D03*
X1778466Y198772D03*
X1783572Y179574D03*
X1802369Y179374D03*
X1808769Y179574D03*
X1815000Y179300D03*
X1789870Y179374D03*
X1796170Y179574D03*
X1795348Y172037D03*
X1797848D03*
X1792748Y171937D03*
X1821367Y179574D03*
X1827565Y179174D03*
X1833388Y179500D03*
X1791150Y209600D03*
X1794300Y209700D03*
X1794216Y198872D03*
X1791066Y198772D03*
X1819457Y198872D03*
X1828700Y198800D03*
X1820349Y209586D03*
X1828950Y209600D03*
X1832274Y209734D03*
X1816266Y198772D03*
X1804166Y198472D03*
X1807751Y209586D03*
X1803072Y209728D03*
X1806821Y198600D03*
X1815670Y209728D03*
X1781700Y209700D03*
X1778550Y209600D03*
X1781616Y198872D03*
X1816348Y163437D03*
X1818500Y159500D03*
X1820648Y163437D03*
X1782452Y237712D03*
X1820281Y250498D03*
X1809281D03*
X1801384D03*
X1790383D03*
X1791141Y232106D03*
X1828936Y249900D03*
X1819488Y232106D03*
X1810040D03*
X1800591D03*
X1781693D03*
X1775590Y448100D03*
X1778740D03*
X1828600Y450100D03*
X1825984Y448030D03*
X1816535Y448300D03*
X1813385Y447945D03*
X1804000Y447900D03*
X1800787Y447943D03*
X1791338Y448400D03*
X1788189Y448300D03*
X1779700Y472100D03*
X1784525Y491830D03*
X1781907Y467005D03*
X1785057D03*
X1779303Y497246D03*
X1832301Y467005D03*
X1835550Y466870D03*
X1789774Y476403D03*
X1801500Y471055D03*
X1795164Y476406D03*
X1789525Y491830D03*
X1801125D03*
X1796125D03*
X1817325Y481320D03*
X1806600Y471055D03*
X1812325Y481320D03*
X1806975Y491630D03*
X1830220Y479950D03*
X1824960Y473980D03*
X1824125Y491830D03*
X1822852Y467005D03*
X1819702D03*
X1819125Y491830D03*
X1807104Y467005D03*
X1810254D03*
X1811975Y491630D03*
X1797655Y467005D03*
X1794505D03*
X1810508Y515900D03*
X1804000Y498176D03*
X1834540Y519600D03*
X1796400Y498000D03*
X1781510Y546362D03*
X1786500Y562200D03*
X1783700Y579200D03*
X1828800Y546500D03*
X1828700Y540252D03*
X1828900Y552300D03*
X1834000Y534900D03*
X1811704Y554341D03*
X1807600Y552047D03*
X1806200Y549200D03*
X1786900Y552500D03*
X1801200Y529800D03*
X1806200Y582900D03*
X1810387Y571435D03*
X1794000Y568800D03*
X1793320Y557968D03*
X1828700Y569474D03*
X1836281Y589122D03*
X1828800Y575600D03*
X1828875Y563674D03*
X1828824Y557663D03*
X1810385Y568821D03*
X1807958Y565690D03*
X1812452Y538501D03*
Y533601D03*
X1807852D03*
X1807752Y538501D03*
X1779000Y598900D03*
X1787500Y597791D03*
X1825014Y593695D03*
X1811500Y603500D03*
X1808152Y591601D03*
X1812852Y596401D03*
X1808252D03*
X1812852Y591601D03*
X1893094Y-10142D03*
X1838100Y3900D03*
X1889218Y43530D03*
Y53530D03*
X1846800Y95400D03*
X1847000Y86500D03*
X1848000Y56500D03*
X1850500D03*
X1890803Y63189D03*
X1884500Y79300D03*
X1882000D03*
X1895330Y64390D03*
X1877270Y63473D03*
X1880230Y76820D03*
X1879500Y79300D03*
X1880986Y53299D03*
X1860995Y84509D03*
X1856873Y91200D03*
X1856778Y87397D03*
X1864208Y87724D03*
X1864195Y84509D03*
X1864153Y91241D03*
X1860815Y91184D03*
X1875100Y51300D03*
X1872340Y147236D03*
X1895800Y149200D03*
X1885400Y147000D03*
X1878550Y99470D03*
X1882550D03*
X1894834Y139286D03*
X1863908Y140992D03*
X1878950Y137400D03*
X1871855Y104188D03*
X1856700Y110167D03*
X1869000Y153900D03*
X1887830Y102227D03*
X1852600Y97500D03*
X1887300Y121500D03*
X1850700Y156000D03*
X1875700Y115700D03*
Y121500D03*
X1881500Y115700D03*
Y121500D03*
Y127300D03*
X1887300D03*
X1875700D03*
X1887300Y115700D03*
X1846663Y153748D03*
X1839500Y212700D03*
X1857044Y186292D03*
X1863750Y163750D03*
X1868375Y171900D03*
X1846163Y168448D03*
X1886800Y210600D03*
X1871708Y213442D03*
X1854663Y158248D03*
X1846663D03*
X1852300Y252000D03*
X1858400Y251200D03*
X1843700Y253400D03*
X1839400Y450440D03*
X1838768Y454120D03*
X1847185Y454368D03*
X1860158Y450322D03*
X1864300Y447900D03*
X1882677Y447930D03*
X1895275Y454422D03*
X1898425Y447930D03*
Y454422D03*
X1845330Y466870D03*
X1843000Y505000D03*
X1857480Y466800D03*
X1861300D03*
X1881285Y467049D03*
X1849795Y493379D03*
X1850290Y486610D03*
X1872908Y471338D03*
X1870138Y485732D03*
X1852340Y509140D03*
X1877518Y527560D03*
X1889800Y580200D03*
X1878000Y539000D03*
X1861080Y537090D03*
X1842500Y534500D03*
X1844100Y551000D03*
X1848900Y545500D03*
X1878450Y548650D03*
X1870250Y541950D03*
X1896500Y555300D03*
X1879800Y579000D03*
X1858000Y574000D03*
X1870892Y583245D03*
X1874825Y564125D03*
X1859167Y559350D03*
X1894299Y557790D03*
X1906438Y-15968D03*
X1909406Y76790D03*
X1907986Y82393D03*
X1907929Y84793D03*
X1907907Y87223D03*
X1918379Y84788D03*
X1905501Y79790D03*
X1902796Y79820D03*
X1900100Y145100D03*
X1921199Y140499D03*
X1929711Y155759D03*
X1904136Y140160D03*
X1937000Y150000D03*
X1906871Y106049D03*
X1911231Y137097D03*
X1908715Y104512D03*
X1912100Y142600D03*
X1915030Y147250D03*
X1911440Y128840D03*
X1952440Y98520D03*
X1942637Y100877D03*
X1914152Y115928D03*
X1950983Y147344D03*
X1928100Y136078D03*
X1953200Y195530D03*
X1937100Y206800D03*
X1908967Y201609D03*
X1909186Y211906D03*
X1944500Y183900D03*
X1903524Y208156D03*
X1905074Y198163D03*
X1943200Y214800D03*
X1928400Y212500D03*
X1926000Y212400D03*
X1933898Y216707D03*
X1945156Y160236D03*
X1950994Y173745D03*
X1939316Y173600D03*
X1900740Y178720D03*
X1900700Y172990D03*
Y167290D03*
X1906440Y178720D03*
X1906500Y173100D03*
X1906400Y167290D03*
X1912190Y178870D03*
X1912230Y167330D03*
Y173030D03*
X1946105Y230344D03*
X1902909Y223195D03*
X1943517Y223637D03*
X1943800Y241800D03*
X1943900Y238500D03*
X1934750Y242700D03*
Y240300D03*
X1925600Y242700D03*
X1929000Y445800D03*
X1910500Y435600D03*
X1927100Y436200D03*
X1930100D03*
X1904724Y454422D03*
X1901574Y447930D03*
X1907500Y435600D03*
X1911023Y448400D03*
X1907874Y454422D03*
Y448400D03*
X1933100Y436200D03*
X1957100Y502990D03*
X1955790Y499790D03*
X1947380Y482450D03*
X1915100Y480050D03*
X1905010Y479410D03*
X1939000Y479400D03*
X1952500Y508000D03*
X1959260Y506010D03*
X1938410Y490650D03*
X1929480Y472880D03*
X1905000Y533900D03*
X1906050Y569100D03*
X1923600Y554200D03*
X1955400Y530500D03*
X1923600Y572300D03*
X1908400Y556800D03*
X1915593Y576807D03*
X1953500Y551900D03*
X1943300Y535700D03*
X1921800Y586100D03*
X1936770Y607210D03*
X1906200Y607800D03*
X1916050Y604450D03*
X1924000Y611391D03*
X1968179Y77969D03*
X1965679D03*
Y75369D03*
X1968179D03*
X1965679Y82969D03*
Y80469D03*
X1968179D03*
X1966212Y72897D03*
X1970679Y75369D03*
Y80469D03*
Y77969D03*
X1962800Y143700D03*
X1971200Y152500D03*
X1965400Y149700D03*
X1961472Y165760D03*
X1967817Y201029D03*
X1965900Y184600D03*
X1965057Y176447D03*
X1966542Y179606D03*
X1965973Y166190D03*
X1970270Y474640D03*
X1968870Y481710D03*
X1970500Y502720D03*
X1963500Y521000D03*
X1961500Y561700D03*
Y582700D03*
X1972700Y552700D03*
G54D30*
X1922248Y518328D03*
G54D12*
X-15748Y101221D03*
Y148465D03*
Y357362D03*
Y373110D03*
Y388858D03*
Y404606D03*
X12205Y156339D03*
X-4331D03*
X17323Y101221D03*
Y116969D03*
Y132717D03*
Y148465D03*
X787Y101221D03*
Y116969D03*
Y148465D03*
X33858Y101221D03*
Y116969D03*
Y132717D03*
Y148465D03*
X28740Y109095D03*
Y156339D03*
X12205Y109095D03*
Y140591D03*
X-4331Y109095D03*
Y124843D03*
Y140591D03*
X17323Y357362D03*
Y373110D03*
Y388858D03*
Y404606D03*
X787Y357362D03*
Y373110D03*
Y388858D03*
Y404606D03*
X33858Y357362D03*
Y373110D03*
Y388858D03*
Y404606D03*
X28740Y365236D03*
Y380984D03*
Y396732D03*
X12205Y365236D03*
Y380984D03*
Y396732D03*
X-4331Y365236D03*
Y380984D03*
Y396732D03*
X12205Y412480D03*
X-4331D03*
X28740D03*
G54D21*
X1643803Y585591D03*
X1640850Y582835D03*
X1631992D03*
X1623134D03*
X1640850Y567874D03*
X1631992D03*
X1623134D03*
X1646756Y595039D03*
X1623134Y612756D03*
X1640850Y597795D03*
X1631992D03*
X1623134D03*
X1640850Y612756D03*
X1631992D03*
X1691047Y585591D03*
X1688094Y582835D03*
X1679236D03*
X1670378D03*
X1688094Y567874D03*
X1679236D03*
X1670378D03*
X1694000Y595039D03*
X1688094Y612756D03*
X1679236D03*
X1670378D03*
X1688094Y597795D03*
X1679236D03*
X1670378D03*
G54D13*
X30500Y-42250D03*
Y-52250D03*
X12290Y264640D03*
X18450Y267010D03*
X22970Y244400D03*
X28720Y244450D03*
X17120Y244220D03*
X24200Y267060D03*
X50500Y-42250D03*
X70500D03*
X90500D03*
X110500D03*
X50500Y-52250D03*
X70500D03*
X90500D03*
X110500D03*
X130500Y-42250D03*
Y-52250D03*
X457246Y-52301D03*
Y-42301D03*
X477246Y-52301D03*
Y-42301D03*
X497246Y-52301D03*
Y-42301D03*
X517246Y-52301D03*
Y-42301D03*
X537246Y-52301D03*
Y-42301D03*
X557246Y-52301D03*
Y-42301D03*
X788984Y-52057D03*
Y-42057D03*
X808984Y-52057D03*
Y-42057D03*
X828984Y-52057D03*
Y-42057D03*
X848984Y-52057D03*
Y-42057D03*
X868984Y-52057D03*
Y-42057D03*
X888984Y-52057D03*
Y-42057D03*
X1125583Y-52285D03*
Y-42285D03*
X1145583Y-52285D03*
Y-42285D03*
X1382258Y-52257D03*
Y-42257D03*
X1402258Y-52257D03*
Y-42257D03*
X1422258Y-52257D03*
Y-42257D03*
X1442258Y-52257D03*
Y-42257D03*
G54D31*
X1952756Y605708D03*
G54D22*
X1702205Y536791D03*
X1687205D03*
X1717205D03*
G54D32*
G01X107249Y105000D02*
X109324Y102925D01*
G01X105174Y107075D02*
X107249Y105000D01*
G01D02*
X109324Y107075D01*
G01X105174Y102925D02*
X107249Y105000D01*
G01X1565000Y-15000D02*
X1567959Y-17959D01*
G01X1562041Y-12041D02*
X1565000Y-15000D01*
G01D02*
X1567959Y-12041D01*
G01X1562041Y-17959D02*
X1565000Y-15000D01*
G01X1702205Y536791D02*
X1704457Y534539D01*
G01X1699953Y539043D02*
X1702205Y536791D01*
G01D02*
X1704457Y539043D01*
G01X1699953Y534539D02*
X1702205Y536791D01*
G01X1687205D02*
X1689457Y534539D01*
G01X1684953Y539043D02*
X1687205Y536791D01*
G01D02*
X1689457Y539043D01*
G01X1684953Y534539D02*
X1687205Y536791D01*
G01X1717205D02*
X1719457Y534539D01*
G01X1714953Y539043D02*
X1717205Y536791D01*
G01D02*
X1719457Y539043D01*
G01X1714953Y534539D02*
X1717205Y536791D01*
G01X1753465D02*
X1755576Y534680D01*
G01X1751354Y538902D02*
X1753465Y536791D01*
G01D02*
X1755576Y538902D01*
G01X1751354Y534680D02*
X1753465Y536791D01*
G01X1749528D02*
X1751639Y534680D01*
G01X1747417Y538902D02*
X1749528Y536791D01*
G01D02*
X1751639Y538902D01*
G01X1747417Y534680D02*
X1749528Y536791D01*
G01X1819665Y618663D02*
X1822412Y615916D01*
G01X1816918Y621410D02*
X1819665Y618663D01*
G01D02*
X1822412Y621410D01*
G01X1816918Y615916D02*
X1819665Y618663D01*
G01X1893410Y24189D02*
X1895945Y21654D01*
G01X1893410Y19119D02*
X1895945Y21654D01*
G01X1894100Y493000D02*
X1896918Y490182D01*
G01X1891282Y495818D02*
X1894100Y493000D01*
G01D02*
X1896918Y495818D01*
G01X1891282Y490182D02*
X1894100Y493000D01*
G01X1851250Y576748D02*
X1853608Y574390D01*
G01X1848892Y579106D02*
X1851250Y576748D01*
G01D02*
X1853608Y579106D01*
G01X1848892Y574390D02*
X1851250Y576748D01*
G01Y561000D02*
X1853608Y558642D01*
G01X1848892Y563358D02*
X1851250Y561000D01*
G01D02*
X1853608Y563358D01*
G01X1848892Y558642D02*
X1851250Y561000D01*
G01X1891086Y602105D02*
X1893904Y599287D01*
G01X1888268Y604923D02*
X1891086Y602105D01*
G01D02*
X1893904Y604923D01*
G01X1888268Y599287D02*
X1891086Y602105D01*
G01X1922248Y518328D02*
X1924536Y516040D01*
G01X1919960Y520616D02*
X1922248Y518328D01*
G01D02*
X1924536Y520616D01*
G01X1919960Y516040D02*
X1922248Y518328D01*
G01X1952756Y605708D02*
X1955397Y603067D01*
G01X1950115Y608349D02*
X1952756Y605708D01*
G01D02*
X1955397Y608349D01*
G01X1950115Y603067D02*
X1952756Y605708D01*
G54D23*
X1753465Y536791D03*
X1749528D03*
G54D14*
X3937Y204370D03*
X-3937D03*
X-11811D03*
X35433D03*
X27559D03*
X19685D03*
X3937Y227992D03*
X-3937D03*
X-11811D03*
X35433D03*
X27559D03*
X19685D03*
X3937Y313504D03*
X-3937D03*
X-11811D03*
X3937Y337126D03*
X-3937D03*
X-11811D03*
X35433D03*
X27559D03*
X19685D03*
X35433Y313504D03*
X27559D03*
X19685D03*
G54D33*
G01X1887327Y511202D02*
X1891429D01*
G01X1883225D02*
X1887327D01*
G01D02*
Y514104D01*
G01Y508300D02*
Y511202D01*
G01Y532541D02*
X1892829D01*
G01X1881825D02*
X1887327D01*
G01D02*
Y535443D01*
G01Y529639D02*
Y532541D01*
G01X1929453Y511202D02*
X1934955D01*
G01X1923951D02*
X1929453D01*
G01D02*
Y514104D01*
G01Y508300D02*
Y511202D01*
G54D15*
X42724Y644684D03*
Y644656D03*
Y654684D03*
Y654656D03*
X67724Y644684D03*
Y644656D03*
Y654684D03*
Y654656D03*
X221656Y644656D03*
X196656D03*
X231446Y644756D03*
Y644784D03*
X221656Y644684D03*
X196656D03*
X221656Y654656D03*
X196656D03*
X231446Y654756D03*
Y654784D03*
X221656Y654684D03*
X196656D03*
X256446Y644756D03*
Y644784D03*
Y654756D03*
Y654784D03*
X409240Y644564D03*
X384240D03*
X418914Y644486D03*
Y644514D03*
X409240Y644536D03*
X384240D03*
X409240Y654564D03*
X384240D03*
X418914Y654486D03*
Y654514D03*
X409240Y654536D03*
X384240D03*
X443914Y644486D03*
Y644514D03*
Y654486D03*
Y654514D03*
X596707Y644293D03*
X571707D03*
X596708Y644266D03*
X571708D03*
X596707Y654293D03*
X571707D03*
X596708Y654266D03*
X571708D03*
X606462Y644245D03*
X631462D03*
X606462Y644217D03*
X631462D03*
X606462Y654245D03*
X631462D03*
X606462Y654217D03*
X631462D03*
X912351Y644245D03*
X887351D03*
X912351Y644273D03*
X887351D03*
X912351Y654245D03*
X887351D03*
X912351Y654273D03*
X887351D03*
X922116Y644206D03*
X947116D03*
X922116Y644234D03*
X947116D03*
X922116Y654206D03*
X947116D03*
X922116Y654234D03*
X947116D03*
X1200877Y644262D03*
Y644234D03*
Y654262D03*
Y654234D03*
X1225877Y644262D03*
X1235614Y644236D03*
X1260614D03*
X1235614Y644264D03*
X1260614D03*
X1225877Y644234D03*
Y654262D03*
X1235614Y654236D03*
X1260614D03*
X1235614Y654264D03*
X1260614D03*
X1225877Y654234D03*
X1514375Y644292D03*
Y644264D03*
Y654292D03*
Y654264D03*
X1539375Y644292D03*
Y644264D03*
Y654292D03*
Y654264D03*
G54D24*
X1819665Y618663D03*
G54D34*
G01X548049Y-193422D02*
Y-210922D01*
G01X543027Y-193422D02*
X553071D01*
G01X565549Y-199256D02*
Y-210922D01*
G01Y-194589D02*
X565112Y-194297D01*
Y-193714D01*
X565549Y-193422D01*
X565986Y-193714D01*
Y-194297D01*
X565549Y-194589D01*
G01X583049Y-210922D02*
X581739Y-210630D01*
X580429Y-209464D01*
X579555Y-207422D01*
X579119Y-205089D01*
X579555Y-202755D01*
X580429Y-200714D01*
X581739Y-199547D01*
X583049Y-199256D01*
X584359Y-199547D01*
X585669Y-200714D01*
X586542Y-202755D01*
X586761Y-205089D01*
X586542Y-207422D01*
X585669Y-209464D01*
X584359Y-210630D01*
X583049Y-210922D01*
G01X597492Y-215297D02*
X599021Y-216464D01*
X600767Y-216755D01*
X602295Y-216464D01*
X603606Y-215006D01*
X604479Y-212964D01*
Y-199256D01*
G01Y-201589D02*
X603606Y-200422D01*
X602295Y-199547D01*
X600767Y-199256D01*
X599021Y-199839D01*
X597929Y-201005D01*
X597055Y-203047D01*
X596619Y-205089D01*
X596837Y-206839D01*
X597711Y-208881D01*
X599021Y-210339D01*
X600767Y-210922D01*
X602077Y-210630D01*
X603606Y-209464D01*
X604479Y-208298D01*
G01X621979Y-210922D02*
Y-199256D01*
G01Y-201297D02*
X621106Y-200131D01*
X619795Y-199547D01*
X618267Y-199256D01*
X616739Y-199839D01*
X615429Y-201005D01*
X614555Y-202755D01*
X614119Y-205089D01*
X614555Y-207422D01*
X615429Y-209172D01*
X616739Y-210339D01*
X618267Y-210922D01*
X619795Y-210630D01*
X621106Y-209756D01*
X621979Y-208589D01*
G01X648682Y-210922D02*
Y-193422D01*
X653922D01*
X655669Y-194297D01*
X656979Y-196339D01*
X657416Y-198672D01*
X656979Y-201005D01*
X655887Y-202755D01*
X653922Y-203631D01*
X648682D01*
G01X674479Y-210922D02*
Y-199256D01*
G01Y-201297D02*
X673606Y-200131D01*
X672295Y-199547D01*
X670767Y-199256D01*
X669239Y-199839D01*
X667929Y-201005D01*
X667055Y-202755D01*
X666619Y-205089D01*
X667055Y-207422D01*
X667929Y-209172D01*
X669239Y-210339D01*
X670767Y-210922D01*
X672295Y-210630D01*
X673606Y-209756D01*
X674479Y-208589D01*
G01X684774Y-208881D02*
X685866Y-210047D01*
X687394Y-210922D01*
X688704D01*
X690014Y-210339D01*
X690887Y-209464D01*
X691324Y-208298D01*
X691106Y-206547D01*
X690232Y-205672D01*
X686302Y-203922D01*
X685429Y-201880D01*
X685866Y-200422D01*
X686739Y-199547D01*
X688049Y-199256D01*
X689359Y-199547D01*
X690669Y-200422D01*
G01X702274Y-208881D02*
X703366Y-210047D01*
X704894Y-210922D01*
X706204D01*
X707514Y-210339D01*
X708387Y-209464D01*
X708824Y-208298D01*
X708606Y-206547D01*
X707732Y-205672D01*
X703802Y-203922D01*
X702929Y-201880D01*
X703366Y-200422D01*
X704239Y-199547D01*
X705549Y-199256D01*
X706859Y-199547D01*
X708169Y-200422D01*
G01X735746Y-210922D02*
Y-193422D01*
X740112D01*
X741859Y-194297D01*
X743169Y-195464D01*
X744261Y-197213D01*
X745134Y-199256D01*
X745352Y-202172D01*
X745134Y-205089D01*
X744261Y-207131D01*
X743169Y-208881D01*
X741859Y-210047D01*
X740112Y-210922D01*
X735746D01*
G01X752590Y-193422D02*
X758049Y-210922D01*
X763508Y-193422D01*
G01X775549D02*
Y-210922D01*
G01X770527Y-193422D02*
X780571D01*
G01X804872Y-210922D02*
Y-193422D01*
X810549Y-208005D01*
X816226Y-193422D01*
Y-210922D01*
G01X829795Y-201589D02*
X830669Y-200714D01*
X831324Y-199256D01*
X831761Y-197213D01*
X831324Y-195464D01*
X830451Y-194297D01*
X828922Y-193422D01*
X823027D01*
Y-210922D01*
X830232D01*
X831761Y-209756D01*
X832634Y-208005D01*
X833071Y-205964D01*
X832634Y-203922D01*
X831324Y-202172D01*
X829795Y-201589D01*
X823027D01*
G01X647372Y-165922D02*
Y-148422D01*
X653049Y-163005D01*
X658726Y-148422D01*
Y-165922D01*
G01X670549D02*
X669239Y-165630D01*
X667929Y-164464D01*
X667055Y-162422D01*
X666619Y-160089D01*
X667055Y-157755D01*
X667929Y-155714D01*
X669239Y-154547D01*
X670549Y-154256D01*
X671859Y-154547D01*
X673169Y-155714D01*
X674042Y-157755D01*
X674261Y-160089D01*
X674042Y-162422D01*
X673169Y-164464D01*
X671859Y-165630D01*
X670549Y-165922D01*
G01X691979Y-148422D02*
Y-165922D01*
G01Y-163298D02*
X691106Y-164756D01*
X689795Y-165630D01*
X688267Y-165922D01*
X686521Y-165339D01*
X685211Y-163881D01*
X684337Y-162131D01*
X684119Y-160089D01*
X684337Y-158047D01*
X685211Y-156297D01*
X686521Y-154839D01*
X688267Y-154256D01*
X689795Y-154547D01*
X690887Y-155131D01*
X691979Y-156297D01*
G01X702274Y-158047D02*
X709261D01*
X708606Y-156005D01*
X707514Y-154839D01*
X705986Y-154256D01*
X704457Y-154547D01*
X703147Y-155422D01*
X702274Y-157464D01*
X701837Y-159214D01*
Y-160964D01*
X702274Y-162714D01*
X703366Y-164464D01*
X704676Y-165630D01*
X706204Y-165922D01*
X707732Y-165339D01*
X709261Y-163589D01*
G01X723049Y-165922D02*
Y-148422D01*
G01X975549Y-210922D02*
Y-193422D01*
X972929Y-196922D01*
G01Y-210922D02*
X978169D01*
G01X988246Y-208298D02*
X989555Y-209756D01*
X991084Y-210630D01*
X993049Y-210922D01*
X995014Y-210339D01*
X996542Y-209172D01*
X997634Y-207131D01*
X997852Y-204797D01*
X997416Y-202464D01*
X996324Y-201005D01*
X994795Y-199839D01*
X993267Y-199547D01*
X991739Y-199839D01*
X989774Y-201005D01*
X990429Y-193422D01*
X996324D01*
G01X1010549Y-210922D02*
Y-193422D01*
X1007929Y-196922D01*
G01Y-210922D02*
X1013169D01*
G01X1023901Y-196339D02*
X1025211Y-194589D01*
X1026739Y-193714D01*
X1028486Y-193422D01*
X1030669Y-194005D01*
X1032197Y-195464D01*
X1032634Y-197213D01*
X1032416Y-198964D01*
X1031542Y-200422D01*
X1027176Y-203339D01*
X1025211Y-205380D01*
X1023901Y-208298D01*
X1023464Y-210922D01*
X1032634D01*
G01X1041401Y-203631D02*
X1042929Y-201589D01*
X1044239Y-200422D01*
X1045986Y-199839D01*
X1047514Y-200422D01*
X1048606Y-201589D01*
X1049479Y-203339D01*
X1049697Y-205380D01*
X1049479Y-207131D01*
X1048606Y-208881D01*
X1047295Y-210339D01*
X1045767Y-210922D01*
X1044021Y-210339D01*
X1042492Y-208589D01*
X1041619Y-205964D01*
X1041401Y-203047D01*
X1041837Y-199256D01*
X1042492Y-197213D01*
X1043584Y-195172D01*
X1045112Y-193714D01*
X1046641Y-193422D01*
X1048169Y-194005D01*
X1049261Y-195464D01*
G01X962432Y-165922D02*
Y-148422D01*
X967672D01*
X969419Y-149297D01*
X970729Y-151339D01*
X971166Y-153672D01*
X970729Y-156005D01*
X969637Y-157755D01*
X967672Y-158631D01*
X962432D01*
G01X989102Y-149881D02*
X987792Y-149005D01*
X986264Y-148422D01*
X984517D01*
X982552Y-149297D01*
X981024Y-150755D01*
X979932Y-152506D01*
X979059Y-155422D01*
X978840Y-158047D01*
X979277Y-160672D01*
X979932Y-162422D01*
X981242Y-164172D01*
X982771Y-165339D01*
X984299Y-165922D01*
X985827D01*
X987356Y-165339D01*
X988666Y-164464D01*
X989758Y-163298D01*
G01X1003545Y-156589D02*
X1004419Y-155714D01*
X1005074Y-154256D01*
X1005511Y-152213D01*
X1005074Y-150464D01*
X1004201Y-149297D01*
X1002672Y-148422D01*
X996777D01*
Y-165922D01*
X1003982D01*
X1005511Y-164756D01*
X1006384Y-163005D01*
X1006821Y-160964D01*
X1006384Y-158922D01*
X1005074Y-157172D01*
X1003545Y-156589D01*
X996777D01*
G01X1012749Y-171755D02*
X1025849D01*
G01X1031777Y-165922D02*
Y-148422D01*
X1041821Y-165922D01*
Y-148422D01*
G01X1054299Y-165922D02*
X1052552Y-165630D01*
X1051024Y-164464D01*
X1049714Y-162714D01*
X1048840Y-160672D01*
X1048404Y-158339D01*
Y-156005D01*
X1048840Y-153672D01*
X1049714Y-151630D01*
X1051024Y-149881D01*
X1052552Y-148714D01*
X1054299Y-148422D01*
X1056045Y-148714D01*
X1057574Y-149881D01*
X1058884Y-151630D01*
X1059758Y-153672D01*
X1060194Y-156005D01*
Y-158339D01*
X1059758Y-160672D01*
X1058884Y-162714D01*
X1057574Y-164464D01*
X1056045Y-165630D01*
X1054299Y-165922D01*
G01X1128099Y-210922D02*
Y-193422D01*
X1125479Y-196922D01*
G01Y-210922D02*
X1130719D01*
G01X1147345Y-201589D02*
X1148219Y-200714D01*
X1148874Y-199256D01*
X1149311Y-197213D01*
X1148874Y-195464D01*
X1148001Y-194297D01*
X1146472Y-193422D01*
X1140577D01*
Y-210922D01*
X1147782D01*
X1149311Y-209756D01*
X1150184Y-208005D01*
X1150621Y-205964D01*
X1150184Y-203922D01*
X1148874Y-202172D01*
X1147345Y-201589D01*
X1140577D01*
G01X1105140Y-148422D02*
X1110599Y-165922D01*
X1116058Y-148422D01*
G01X1132466Y-165922D02*
X1123732D01*
Y-148422D01*
X1132466D01*
G01X1128972Y-156880D02*
X1123732D01*
G01X1141232Y-165922D02*
Y-148422D01*
X1146691D01*
X1148437Y-149297D01*
X1149529Y-150464D01*
X1149966Y-152797D01*
X1149529Y-155131D01*
X1148219Y-156589D01*
X1146691Y-157464D01*
X1141232D01*
G01X1146691D02*
X1149966Y-165922D01*
G01X1163099Y-166505D02*
X1162662Y-166214D01*
Y-165630D01*
X1163099Y-165339D01*
X1163536Y-165630D01*
Y-166214D01*
X1163099Y-166505D01*
G01X1326166Y-193422D02*
Y-210922D01*
X1317432D01*
G01X1304299D02*
Y-193422D01*
X1306919Y-196922D01*
G01Y-210922D02*
X1301679D01*
G01X1286799D02*
Y-193422D01*
X1289419Y-196922D01*
G01Y-210922D02*
X1284179D01*
G01X1267989Y-202172D02*
X1263622D01*
Y-207422D01*
X1264932Y-209172D01*
X1266461Y-210339D01*
X1268644Y-210922D01*
X1270827Y-210339D01*
X1272356Y-209172D01*
X1273666Y-207422D01*
X1274539Y-205380D01*
X1274976Y-203047D01*
Y-201005D01*
X1274539Y-199256D01*
X1273666Y-197213D01*
X1272356Y-195464D01*
X1271046Y-194297D01*
X1269299Y-193422D01*
X1267771D01*
X1266024Y-194005D01*
X1264714Y-195172D01*
G01X1256821Y-210922D02*
Y-193422D01*
X1246777Y-210922D01*
Y-193422D01*
G01X1239102Y-210922D02*
Y-193422D01*
X1234736D01*
X1232989Y-194297D01*
X1231679Y-195464D01*
X1230587Y-197213D01*
X1229714Y-199256D01*
X1229496Y-202172D01*
X1229714Y-205089D01*
X1230587Y-207131D01*
X1231679Y-208881D01*
X1232989Y-210047D01*
X1234736Y-210922D01*
X1239102D01*
G01X1238682Y-148422D02*
Y-165922D01*
X1247416D01*
G01X1264479D02*
Y-154256D01*
G01Y-156297D02*
X1263606Y-155131D01*
X1262295Y-154547D01*
X1260767Y-154256D01*
X1259239Y-154839D01*
X1257929Y-156005D01*
X1257055Y-157755D01*
X1256619Y-160089D01*
X1257055Y-162422D01*
X1257929Y-164172D01*
X1259239Y-165339D01*
X1260767Y-165922D01*
X1262295Y-165630D01*
X1263606Y-164756D01*
X1264479Y-163589D01*
G01X1273464Y-171172D02*
X1274774Y-171755D01*
X1276521Y-171172D01*
X1277612Y-170006D01*
X1278486Y-168547D01*
X1279795Y-163881D01*
X1282634Y-154256D01*
G01X1275647D02*
X1279795Y-163881D01*
G01X1292274Y-158047D02*
X1299261D01*
X1298606Y-156005D01*
X1297514Y-154839D01*
X1295986Y-154256D01*
X1294457Y-154547D01*
X1293147Y-155422D01*
X1292274Y-157464D01*
X1291837Y-159214D01*
Y-160964D01*
X1292274Y-162714D01*
X1293366Y-164464D01*
X1294676Y-165630D01*
X1296204Y-165922D01*
X1297732Y-165339D01*
X1299261Y-163589D01*
G01X1309992Y-165922D02*
Y-154256D01*
G01Y-156589D02*
X1311084Y-155422D01*
X1312176Y-154547D01*
X1313704Y-154256D01*
X1314795Y-154547D01*
X1316106Y-155422D01*
G01X1380796Y-165922D02*
Y-148422D01*
X1385162D01*
X1386909Y-149297D01*
X1388219Y-150464D01*
X1389311Y-152213D01*
X1390184Y-154256D01*
X1390402Y-157172D01*
X1390184Y-160089D01*
X1389311Y-162131D01*
X1388219Y-163881D01*
X1386909Y-165047D01*
X1385162Y-165922D01*
X1380796D01*
G01X1399824Y-158047D02*
X1406811D01*
X1406156Y-156005D01*
X1405064Y-154839D01*
X1403536Y-154256D01*
X1402007Y-154547D01*
X1400697Y-155422D01*
X1399824Y-157464D01*
X1399387Y-159214D01*
Y-160964D01*
X1399824Y-162714D01*
X1400916Y-164464D01*
X1402226Y-165630D01*
X1403754Y-165922D01*
X1405282Y-165339D01*
X1406811Y-163589D01*
G01X1417324Y-163881D02*
X1418416Y-165047D01*
X1419944Y-165922D01*
X1421254D01*
X1422564Y-165339D01*
X1423437Y-164464D01*
X1423874Y-163298D01*
X1423656Y-161547D01*
X1422782Y-160672D01*
X1418852Y-158922D01*
X1417979Y-156880D01*
X1418416Y-155422D01*
X1419289Y-154547D01*
X1420599Y-154256D01*
X1421909Y-154547D01*
X1423219Y-155422D01*
G01X1438099Y-154256D02*
Y-165922D01*
G01Y-149589D02*
X1437662Y-149297D01*
Y-148714D01*
X1438099Y-148422D01*
X1438536Y-148714D01*
Y-149297D01*
X1438099Y-149589D01*
G01X1452542Y-170297D02*
X1454071Y-171464D01*
X1455817Y-171755D01*
X1457345Y-171464D01*
X1458656Y-170006D01*
X1459529Y-167964D01*
Y-154256D01*
G01Y-156589D02*
X1458656Y-155422D01*
X1457345Y-154547D01*
X1455817Y-154256D01*
X1454071Y-154839D01*
X1452979Y-156005D01*
X1452105Y-158047D01*
X1451669Y-160089D01*
X1451887Y-161839D01*
X1452761Y-163881D01*
X1454071Y-165339D01*
X1455817Y-165922D01*
X1457127Y-165630D01*
X1458656Y-164464D01*
X1459529Y-163298D01*
G01X1469387Y-165922D02*
Y-154256D01*
G01Y-157172D02*
X1470261Y-155714D01*
X1471571Y-154547D01*
X1473317Y-154256D01*
X1474845Y-154547D01*
X1476156Y-155714D01*
X1476811Y-157755D01*
Y-165922D01*
G01X1487324Y-158047D02*
X1494311D01*
X1493656Y-156005D01*
X1492564Y-154839D01*
X1491036Y-154256D01*
X1489507Y-154547D01*
X1488197Y-155422D01*
X1487324Y-157464D01*
X1486887Y-159214D01*
Y-160964D01*
X1487324Y-162714D01*
X1488416Y-164464D01*
X1489726Y-165630D01*
X1491254Y-165922D01*
X1492782Y-165339D01*
X1494311Y-163589D01*
G01X1505042Y-165922D02*
Y-154256D01*
G01Y-156589D02*
X1506134Y-155422D01*
X1507226Y-154547D01*
X1508754Y-154256D01*
X1509845Y-154547D01*
X1511156Y-155422D01*
G01X1426729Y-193422D02*
X1431969D01*
G01X1429349D02*
Y-210922D01*
G01X1426729D02*
X1431969D01*
G01X1441390Y-193422D02*
X1446849Y-210922D01*
X1452308Y-193422D01*
G01X1464349Y-210922D02*
Y-203047D01*
X1459982Y-193422D01*
G01X1468716D02*
X1464349Y-203047D01*
G01X1551799Y-193422D02*
X1550052Y-194005D01*
X1548742Y-195464D01*
X1547869Y-197213D01*
X1547214Y-199547D01*
X1546996Y-202172D01*
X1547214Y-204797D01*
X1547869Y-207131D01*
X1548742Y-208881D01*
X1550052Y-210339D01*
X1551799Y-210922D01*
X1553545Y-210339D01*
X1554856Y-208881D01*
X1555729Y-207131D01*
X1556384Y-204797D01*
X1556602Y-202172D01*
X1556384Y-199547D01*
X1555729Y-197213D01*
X1554856Y-195464D01*
X1553545Y-194005D01*
X1551799Y-193422D01*
G01X1565151Y-196339D02*
X1566461Y-194589D01*
X1567989Y-193714D01*
X1569736Y-193422D01*
X1571919Y-194005D01*
X1573447Y-195464D01*
X1573884Y-197213D01*
X1573666Y-198964D01*
X1572792Y-200422D01*
X1568426Y-203339D01*
X1566461Y-205380D01*
X1565151Y-208298D01*
X1564714Y-210922D01*
X1573884D01*
G01X1582869Y-211505D02*
X1590729Y-193422D01*
G01X1604299Y-210922D02*
Y-193422D01*
X1601679Y-196922D01*
G01Y-210922D02*
X1606919D01*
G01X1621799Y-193422D02*
X1620052Y-194005D01*
X1618742Y-195464D01*
X1617869Y-197213D01*
X1617214Y-199547D01*
X1616996Y-202172D01*
X1617214Y-204797D01*
X1617869Y-207131D01*
X1618742Y-208881D01*
X1620052Y-210339D01*
X1621799Y-210922D01*
X1623545Y-210339D01*
X1624856Y-208881D01*
X1625729Y-207131D01*
X1626384Y-204797D01*
X1626602Y-202172D01*
X1626384Y-199547D01*
X1625729Y-197213D01*
X1624856Y-195464D01*
X1623545Y-194005D01*
X1621799Y-193422D01*
G01X1635369Y-211505D02*
X1643229Y-193422D01*
G01X1652651Y-196339D02*
X1653961Y-194589D01*
X1655489Y-193714D01*
X1657236Y-193422D01*
X1659419Y-194005D01*
X1660947Y-195464D01*
X1661384Y-197213D01*
X1661166Y-198964D01*
X1660292Y-200422D01*
X1655926Y-203339D01*
X1653961Y-205380D01*
X1652651Y-208298D01*
X1652214Y-210922D01*
X1661384D01*
G01X1674299Y-193422D02*
X1672552Y-194005D01*
X1671242Y-195464D01*
X1670369Y-197213D01*
X1669714Y-199547D01*
X1669496Y-202172D01*
X1669714Y-204797D01*
X1670369Y-207131D01*
X1671242Y-208881D01*
X1672552Y-210339D01*
X1674299Y-210922D01*
X1676045Y-210339D01*
X1677356Y-208881D01*
X1678229Y-207131D01*
X1678884Y-204797D01*
X1679102Y-202172D01*
X1678884Y-199547D01*
X1678229Y-197213D01*
X1677356Y-195464D01*
X1676045Y-194005D01*
X1674299Y-193422D01*
G01X1691799Y-210922D02*
Y-193422D01*
X1689179Y-196922D01*
G01Y-210922D02*
X1694419D01*
G01X1708862D02*
X1709299Y-207131D01*
X1709954Y-203922D01*
X1710827Y-201005D01*
X1711919Y-197797D01*
X1713666Y-193422D01*
X1704932D01*
G01X1599496Y-165922D02*
Y-148422D01*
X1603862D01*
X1605609Y-149297D01*
X1606919Y-150464D01*
X1608011Y-152213D01*
X1608884Y-154256D01*
X1609102Y-157172D01*
X1608884Y-160089D01*
X1608011Y-162131D01*
X1606919Y-163881D01*
X1605609Y-165047D01*
X1603862Y-165922D01*
X1599496D01*
G01X1625729D02*
Y-154256D01*
G01Y-156297D02*
X1624856Y-155131D01*
X1623545Y-154547D01*
X1622017Y-154256D01*
X1620489Y-154839D01*
X1619179Y-156005D01*
X1618305Y-157755D01*
X1617869Y-160089D01*
X1618305Y-162422D01*
X1619179Y-164172D01*
X1620489Y-165339D01*
X1622017Y-165922D01*
X1623545Y-165630D01*
X1624856Y-164756D01*
X1625729Y-163589D01*
G01X1639299Y-148422D02*
Y-165922D01*
G01X1636242Y-154256D02*
X1642356D01*
G01X1653524Y-158047D02*
X1660511D01*
X1659856Y-156005D01*
X1658764Y-154839D01*
X1657236Y-154256D01*
X1655707Y-154547D01*
X1654397Y-155422D01*
X1653524Y-157464D01*
X1653087Y-159214D01*
Y-160964D01*
X1653524Y-162714D01*
X1654616Y-164464D01*
X1655926Y-165630D01*
X1657454Y-165922D01*
X1658982Y-165339D01*
X1660511Y-163589D01*
G54D16*
X107249Y105000D03*
G54D25*
X1895945Y21654D03*
G54D26*
X1887327Y511202D03*
X1929453Y532541D03*
G54D17*
X72074Y243282D03*
X65180Y243368D03*
X61800Y243400D03*
X68498Y243368D03*
X49560Y649770D03*
Y644670D03*
X54360D03*
X49560Y649570D03*
Y644670D03*
X54360D03*
X49560Y654670D03*
X54360D03*
X49560D03*
X54360D03*
X214820Y649570D03*
Y644670D03*
X210020D03*
X214820Y649770D03*
Y644670D03*
X210020D03*
X214820Y654670D03*
X210020D03*
X214820D03*
X210020D03*
X238282Y649670D03*
Y644770D03*
X243082D03*
X238282Y649870D03*
Y644770D03*
X243082D03*
X238282Y654770D03*
X243082D03*
X238282D03*
X243082D03*
X402404Y649650D03*
Y644550D03*
X397604D03*
X402404Y649450D03*
Y644550D03*
X397604D03*
X402404Y654550D03*
X397604D03*
X402404D03*
X397604D03*
X425750Y649400D03*
Y644500D03*
X430550D03*
X425750Y649600D03*
Y644500D03*
X430550D03*
X425750Y654500D03*
X430550D03*
X425750D03*
X430550D03*
X589871Y649379D03*
Y644279D03*
X585071D03*
X589872Y649180D03*
Y644280D03*
X585072D03*
X589871Y654279D03*
X585071D03*
X589872Y654280D03*
X585072D03*
X613298Y649331D03*
Y644231D03*
X618098D03*
X613298Y649131D03*
Y644231D03*
X618098D03*
X613298Y654231D03*
X618098D03*
X613298D03*
X618098D03*
X905515Y649159D03*
Y644259D03*
X900715D03*
X905515Y649359D03*
Y644259D03*
X900715D03*
X905515Y654259D03*
X900715D03*
X905515D03*
X900715D03*
X928952Y649120D03*
Y644220D03*
X933752D03*
X928952Y649320D03*
Y644220D03*
X933752D03*
X928952Y654220D03*
X933752D03*
X928952D03*
X933752D03*
X1219041Y649348D03*
Y644248D03*
X1214241D03*
X1219041Y649148D03*
Y644248D03*
X1214241D03*
X1219041Y654248D03*
X1214241D03*
X1219041D03*
X1214241D03*
X1242450Y649150D03*
Y644250D03*
X1247250D03*
X1242450Y649350D03*
Y644250D03*
X1247250D03*
X1242450Y654250D03*
X1247250D03*
X1242450D03*
X1247250D03*
X1527739Y644278D03*
D03*
Y654278D03*
D03*
X1532539Y649378D03*
Y644278D03*
Y649178D03*
Y644278D03*
Y654278D03*
D03*
G54D27*
X1887327Y532541D03*
X1929453Y511202D03*
G54D18*
X60512Y467244D03*
X1894100Y493000D03*
X1891086Y602105D03*
G54D28*
X1851250Y576748D03*
Y561000D03*
G54D19*
G01X1097834Y569200D02*
X1100300D01*
G01X1098018Y531156D02*
X1100056D01*
G01X1098160Y533809D02*
X1100009D01*
G01X1098040Y536723D02*
X1100905D01*
X1101181Y536999D01*
G01X1097899Y574773D02*
X1101155D01*
X1101181Y574799D01*
X320784Y203219D03*
X330948Y201258D03*
X401377Y28022D03*
X411416D03*
X401377Y65822D03*
X411416D03*
X401377Y529022D03*
X411416D03*
X401377Y566822D03*
X411416D03*
X428149Y28022D03*
X434842Y28268D03*
X421456Y35957D03*
X434842Y65822D03*
X428149D03*
X458640Y200596D03*
X428149Y529022D03*
X434842D03*
X428149Y566822D03*
X434842D03*
X970392Y203219D03*
X980556Y201258D03*
X1050985Y28022D03*
X1061024D03*
X1077757D03*
X1084450Y28098D03*
X1050985Y65822D03*
X1071064Y35957D03*
X1061024Y65822D03*
X1084450D03*
X1077757D03*
X1050985Y529022D03*
Y566822D03*
X1061024Y529022D03*
X1084450D03*
X1077757D03*
X1067716Y547907D03*
X1071064Y574757D03*
X1061024Y566822D03*
X1084450D03*
X1077757D03*
X1108248Y200596D03*
X1111631Y198327D03*
X1451753Y276753D03*
X1454902Y279902D03*
X1445454Y270454D03*
X1448603Y273603D03*
X1454902Y305098D03*
X1448603Y311397D03*
X1458051Y301949D03*
X1464351Y295649D03*
Y289351D03*
X1458051Y283051D03*
X1489546Y270454D03*
X1486397Y273603D03*
X1483247Y276753D03*
X1470649Y295649D03*
Y289351D03*
X1480098Y305098D03*
X1476949Y301949D03*
X1486397Y311397D03*
X1489546Y314546D03*
X1483247Y308247D03*
X1476949Y283051D03*
X1606470Y93759D03*
X1638938Y109192D03*
X1638250Y125750D03*
X1651536Y121790D03*
X1638938Y118641D03*
X1645378Y128378D03*
X1638902Y112305D03*
X1648430Y150163D03*
X1638937Y131239D03*
Y143837D03*
Y137538D03*
X1638938Y153286D03*
X1616900Y153200D03*
X1629489Y150136D03*
X1616891Y146987D03*
X1616893Y140782D03*
X1635788Y137538D03*
Y143837D03*
Y131239D03*
X1616891Y134389D03*
X1629489Y137538D03*
Y143837D03*
Y131239D03*
X1620040Y106042D03*
X1623189Y118640D03*
X1629489D03*
X1610793Y109190D03*
X1607441Y118640D03*
X1616891Y124939D03*
X1596220Y109470D03*
X1613741Y115491D03*
X1602717Y102240D03*
X1620040Y162735D03*
X1627998Y172854D03*
X1601142Y172185D03*
X1674685Y134217D03*
X1693625Y133220D03*
X1680402Y128652D03*
X1678127Y117293D03*
X1673883Y124308D03*
X1654685Y146987D03*
X1654678Y137530D03*
X1657835Y134389D03*
X1671000Y103000D03*
X1709000Y127200D03*
X1691207Y139891D03*
X1667284Y137537D03*
X1657835Y124940D03*
Y150136D03*
X1667284Y121790D03*
Y128089D03*
Y150136D03*
X1664134Y140688D03*
X1668213Y172608D03*
X1729444Y123782D03*
X1726294Y101785D03*
X1742212Y117451D03*
X1717014Y108000D03*
Y139500D03*
X1739064Y108000D03*
X1742214Y101700D03*
X1745364Y114300D03*
X1755089Y150750D03*
X1752189Y136750D03*
X1752389Y132250D03*
X1754189Y124250D03*
X1757689Y123850D03*
X1752889Y146250D03*
X1745364Y145800D03*
X1731903Y133712D03*
X1720164Y97550D03*
Y111150D03*
X1723314D03*
Y117450D03*
X1720164Y120600D03*
Y133200D03*
Y126800D03*
X1751800Y141700D03*
X1742214Y98550D03*
Y126900D03*
X1745364Y120600D03*
X1742214Y111150D03*
X1739064Y114300D03*
G54D29*
X1952756Y-14960D03*
Y58268D03*
M02*
